(lib_symbols
	(symbol "antmicroBarrelAudioConnectors:BarrelJack_3167288" (pin_names hide) (in_bom yes) (on_board yes)
      (property "Reference" "J" (at 17.78 -5.08 0)
        (effects (font (size 1.27 1.27) (thickness 0.15)) (justify left bottom))
      )
      (property "Value" "BarrelJack_3167288" (at 17.78 -7.62 0)
        (effects (font (size 1.27 1.27) (thickness 0.15)) (justify left bottom))
      )
      (property "Footprint" "antmicro-footprints:BarrelJack_3167288_Horizontal" (at 17.78 -10.16 0)
        (effects (font (size 1.27 1.27) (thickness 0.15)) (justify left bottom) hide)
      )
      (property "Datasheet" "https://www.farnell.com/datasheets/3167288.pdf" (at 17.78 -12.7 0)
        (effects (font (size 1.27 1.27) (thickness 0.15)) (justify left bottom) hide)
      )
      (property "Manufacturer" "Multicomp Pro" (at 17.78 -15.24 0)
        (effects (font (size 1.27 1.27) (thickness 0.15)) (justify left bottom) hide)
      )
      (property "MPN" "MJ-179PH" (at 17.78 -17.78 0)
        (effects (font (size 1.27 1.27) (thickness 0.15)) (justify left bottom) hide)
      )
      (property "Author" "Antmicro" (at 17.78 -20.32 0)
        (effects (font (size 1.27 1.27) (thickness 0.15)) (justify left bottom) hide)
      )
      (property "License" "Apache-2.0" (at 17.78 -22.86 0)
        (effects (font (size 1.27 1.27) (thickness 0.15)) (justify left bottom) hide)
      )
      (property "ki_keywords" "HORIZONTAL, THT, JACK, CONNECTOR, POWER" (at 0 0 0)
        (effects (font (size 1.27 1.27)) hide)
      )
      (property "ki_description" "DC Power Connector, Jack, 4 A, 1.95 mm, PCB Mount, Through Hole" (at 0 0 0)
        (effects (font (size 1.27 1.27)) hide)
      )
      (symbol "BarrelJack_3167288_0_1"
        (polyline
          (pts
            (xy 5.08 -5.08)
            (xy 5.334 -4.064)
            (xy 4.826 -4.064)
            (xy 5.08 -5.08)
          )
          (stroke (width 0) (type default))
          (fill (type outline))
        )
      )
      (symbol "BarrelJack_3167288_1_1"
        (polyline
          (pts
            (xy 2.54 -5.08)
            (xy 6.985 -5.08)
          )
          (stroke (width 0.254) (type default))
          (fill (type background))
        )
        (polyline
          (pts
            (xy 2.54 -2.54)
            (xy 5.08 -2.54)
          )
          (stroke (width 0.254) (type default))
          (fill (type background))
        )
        (polyline
          (pts
            (xy 2.54 0)
            (xy 6.985 0)
          )
          (stroke (width 0.254) (type default))
          (fill (type background))
        )
        (polyline
          (pts
            (xy 5.08 -2.54)
            (xy 5.08 -5.08)
          )
          (stroke (width 0.254) (type default))
          (fill (type background))
        )
        (rectangle (start 2.54 -6.35) (end 12.7 1.27)
          (stroke (width 0.254) (type default))
          (fill (type background))
        )
        (rectangle (start 6.985 0.635) (end 10.16 -0.635)
          (stroke (width 0.254) (type default))
          (fill (type outline))
        )
        (arc (start 8.89 -3.175) (mid 7.543 -3.733) (end 6.985 -5.08)
          (stroke (width 0.254) (type default))
          (fill (type none))
        )
        (arc (start 10.16 -0.635) (mid 10.609 -0.449) (end 10.795 0)
          (stroke (width 0.254) (type default))
          (fill (type outline))
        )
        (arc (start 10.795 -5.08) (mid 10.237 -3.733) (end 8.89 -3.175)
          (stroke (width 0.254) (type default))
          (fill (type none))
        )
        (arc (start 10.795 0) (mid 10.609 0.449) (end 10.16 0.635)
          (stroke (width 0.254) (type default))
          (fill (type outline))
        )
        (pin passive line (at 0 0 0) (length 2.54)
          (name "1" (effects (font (size 1.27 1.27))))
          (number "1" (effects (font (size 1.27 1.27))))
        )
        (pin passive line (at 0 -2.54 0) (length 2.54)
          (name "2" (effects (font (size 1.27 1.27))))
          (number "2" (effects (font (size 1.27 1.27))))
        )
        (pin passive line (at 0 -5.08 0) (length 2.54)
          (name "3" (effects (font (size 1.27 1.27))))
          (number "3" (effects (font (size 1.27 1.27))))
        )
      )
    )
	(symbol "antmicroCapacitors0402:C_100n_0402" (pin_numbers hide) (pin_names hide) (in_bom yes) (on_board yes)
      (property "Reference" "C" (at 20.32 -5.08 0)
        (effects (font (size 1.27 1.27) (thickness 0.15)) (justify left bottom))
      )
      (property "Value" "C_100n_0402" (at 20.32 -10.16 0)
        (effects (font (size 1.27 1.27) (thickness 0.15)) (justify left bottom) hide)
      )
      (property "Footprint" "antmicro-footprints:C_0402_1005Metric" (at 20.32 -12.7 0)
        (effects (font (size 1.27 1.27) (thickness 0.15)) (justify left bottom) hide)
      )
      (property "Datasheet" "https://search.murata.co.jp/Ceramy/image/img/A01X/G101/ENG/GRM155R61H104KE14-01.pdf" (at 20.32 -15.24 0)
        (effects (font (size 1.27 1.27) (thickness 0.15)) (justify left bottom) hide)
      )
      (property "MPN" "GRM155R61H104KE14D" (at 20.32 -17.78 0)
        (effects (font (size 1.27 1.27) (thickness 0.15)) (justify left bottom) hide)
      )
      (property "Manufacturer" "Murata" (at 20.32 -20.32 0)
        (effects (font (size 1.27 1.27) (thickness 0.15)) (justify left bottom) hide)
      )
      (property "License" "Apache-2.0" (at 20.32 -22.86 0)
        (effects (font (size 1.27 1.27) (thickness 0.15)) (justify left bottom) hide)
      )
      (property "Author" "Antmicro" (at 20.32 -25.4 0)
        (effects (font (size 1.27 1.27) (thickness 0.15)) (justify left bottom) hide)
      )
      (property "Val" "100n" (at 20.32 -7.62 0)
        (effects (font (size 1.27 1.27) (thickness 0.15)) (justify left bottom))
      )
      (property "Voltage" "50V" (at 20.32 -27.94 0)
        (effects (font (size 1.27 1.27)) (justify left bottom) hide)
      )
      (property "Dielectric" "X5R" (at 20.32 -30.48 0)
        (effects (font (size 1.27 1.27)) (justify left bottom) hide)
      )
      (property "ki_description" " " (at 0 0 0)
        (effects (font (size 1.27 1.27)) hide)
      )
      (symbol "C_100n_0402_0_1"
        (polyline
          (pts
            (xy 2.032 -1.524)
            (xy 2.032 1.524)
          )
          (stroke (width 0.3048) (type default))
          (fill (type none))
        )
        (polyline
          (pts
            (xy 3.048 -1.524)
            (xy 3.048 1.524)
          )
          (stroke (width 0.3302) (type default))
          (fill (type none))
        )
      )
      (symbol "C_100n_0402_1_1"
        (pin passive line (at 0 0 0) (length 2.032)
          (name "~" (effects (font (size 1.27 1.27))))
          (number "1" (effects (font (size 1.27 1.27))))
        )
        (pin passive line (at 5.08 0 180) (length 2.032)
          (name "~" (effects (font (size 1.27 1.27))))
          (number "2" (effects (font (size 1.27 1.27))))
        )
      )
    )
	(symbol "antmicroCapacitors0402:C_10n_0402" (pin_numbers hide) (pin_names hide) (in_bom yes) (on_board yes)
      (property "Reference" "C" (at 20.32 -5.08 0)
        (effects (font (size 1.27 1.27) (thickness 0.15)) (justify left bottom))
      )
      (property "Value" "C_10n_0402" (at 20.32 -10.16 0)
        (effects (font (size 1.27 1.27) (thickness 0.15)) (justify left bottom) hide)
      )
      (property "Footprint" "antmicro-footprints:C_0402_1005Metric" (at 20.32 -12.7 0)
        (effects (font (size 1.27 1.27) (thickness 0.15)) (justify left bottom) hide)
      )
      (property "Datasheet" "https://search.murata.co.jp/Ceramy/image/img/A01X/G101/ENG/GRM155R71H103KA88-01.pdf" (at 20.32 -15.24 0)
        (effects (font (size 1.27 1.27) (thickness 0.15)) (justify left bottom) hide)
      )
      (property "MPN" "GRM155R71H103KA88D" (at 20.32 -17.78 0)
        (effects (font (size 1.27 1.27) (thickness 0.15)) (justify left bottom) hide)
      )
      (property "Manufacturer" "Murata" (at 20.32 -20.32 0)
        (effects (font (size 1.27 1.27) (thickness 0.15)) (justify left bottom) hide)
      )
      (property "License" "Apache-2.0" (at 20.32 -22.86 0)
        (effects (font (size 1.27 1.27) (thickness 0.15)) (justify left bottom) hide)
      )
      (property "Author" "Antmicro" (at 20.32 -25.4 0)
        (effects (font (size 1.27 1.27) (thickness 0.15)) (justify left bottom) hide)
      )
      (property "Val" "10n" (at 20.32 -7.62 0)
        (effects (font (size 1.27 1.27) (thickness 0.15)) (justify left bottom))
      )
      (property "Voltage" "50V" (at 20.32 -27.94 0)
        (effects (font (size 1.27 1.27)) (justify left bottom) hide)
      )
      (property "Dielectric" "X7R" (at 20.32 -30.48 0)
        (effects (font (size 1.27 1.27)) (justify left bottom) hide)
      )
      (property "ki_description" " " (at 0 0 0)
        (effects (font (size 1.27 1.27)) hide)
      )
      (symbol "C_10n_0402_0_1"
        (polyline
          (pts
            (xy 2.032 -1.524)
            (xy 2.032 1.524)
          )
          (stroke (width 0.3048) (type default))
          (fill (type none))
        )
        (polyline
          (pts
            (xy 3.048 -1.524)
            (xy 3.048 1.524)
          )
          (stroke (width 0.3302) (type default))
          (fill (type none))
        )
      )
      (symbol "C_10n_0402_1_1"
        (pin passive line (at 0 0 0) (length 2.032)
          (name "~" (effects (font (size 1.27 1.27))))
          (number "1" (effects (font (size 1.27 1.27))))
        )
        (pin passive line (at 5.08 0 180) (length 2.032)
          (name "~" (effects (font (size 1.27 1.27))))
          (number "2" (effects (font (size 1.27 1.27))))
        )
      )
    )
	(symbol "antmicroCapacitors0402:C_10u_0402" (pin_numbers hide) (pin_names hide) (in_bom yes) (on_board yes)
      (property "Reference" "C" (at 20.32 -5.08 0)
        (effects (font (size 1.27 1.27) (thickness 0.15)) (justify left bottom))
      )
      (property "Value" "C_10u_0402" (at 20.32 -10.16 0)
        (effects (font (size 1.27 1.27) (thickness 0.15)) (justify left bottom) hide)
      )
      (property "Footprint" "antmicro-footprints:C_0402_1005Metric" (at 20.32 -12.7 0)
        (effects (font (size 1.27 1.27) (thickness 0.15)) (justify left bottom) hide)
      )
      (property "Datasheet" " " (at 20.32 -15.24 0)
        (effects (font (size 1.27 1.27) (thickness 0.15)) (justify left bottom) hide)
      )
      (property "MPN" "CC0402MRX5R5BB106" (at 20.32 -17.78 0)
        (effects (font (size 1.27 1.27) (thickness 0.15)) (justify left bottom) hide)
      )
      (property "Manufacturer" "Yaego" (at 20.32 -20.32 0)
        (effects (font (size 1.27 1.27) (thickness 0.15)) (justify left bottom) hide)
      )
      (property "License" "Apache-2.0" (at 20.32 -22.86 0)
        (effects (font (size 1.27 1.27) (thickness 0.15)) (justify left bottom) hide)
      )
      (property "Author" "Antmicro" (at 20.32 -25.4 0)
        (effects (font (size 1.27 1.27) (thickness 0.15)) (justify left bottom) hide)
      )
      (property "Val" "10u" (at 20.32 -7.62 0)
        (effects (font (size 1.27 1.27) (thickness 0.15)) (justify left bottom))
      )
      (property "Voltage" "" (at 20.32 -27.94 0)
        (effects (font (size 1.27 1.27)) (justify left bottom) hide)
      )
      (property "Dielectric" "" (at 20.32 -30.48 0)
        (effects (font (size 1.27 1.27)) (justify left bottom) hide)
      )
      (property "ki_description" " " (at 0 0 0)
        (effects (font (size 1.27 1.27)) hide)
      )
      (symbol "C_10u_0402_0_1"
        (polyline
          (pts
            (xy 2.032 -1.524)
            (xy 2.032 1.524)
          )
          (stroke (width 0.3048) (type default))
          (fill (type none))
        )
        (polyline
          (pts
            (xy 3.048 -1.524)
            (xy 3.048 1.524)
          )
          (stroke (width 0.3302) (type default))
          (fill (type none))
        )
      )
      (symbol "C_10u_0402_1_1"
        (pin passive line (at 0 0 0) (length 2.032)
          (name "~" (effects (font (size 1.27 1.27))))
          (number "1" (effects (font (size 1.27 1.27))))
        )
        (pin passive line (at 5.08 0 180) (length 2.032)
          (name "~" (effects (font (size 1.27 1.27))))
          (number "2" (effects (font (size 1.27 1.27))))
        )
      )
    )
	(symbol "antmicroCapacitors0402:C_18p_0402" (pin_numbers hide) (pin_names hide) (in_bom yes) (on_board yes)
      (property "Reference" "C" (at 20.32 -5.08 0)
        (effects (font (size 1.27 1.27) (thickness 0.15)) (justify left bottom))
      )
      (property "Value" "C_18p_0402" (at 20.32 -10.16 0)
        (effects (font (size 1.27 1.27) (thickness 0.15)) (justify left bottom) hide)
      )
      (property "Footprint" "antmicro-footprints:C_0402_1005Metric" (at 20.32 -12.7 0)
        (effects (font (size 1.27 1.27) (thickness 0.15)) (justify left bottom) hide)
      )
      (property "Datasheet" " " (at 20.32 -15.24 0)
        (effects (font (size 1.27 1.27) (thickness 0.15)) (justify left bottom) hide)
      )
      (property "MPN" "MC0402N180J500CT" (at 20.32 -17.78 0)
        (effects (font (size 1.27 1.27) (thickness 0.15)) (justify left bottom) hide)
      )
      (property "Manufacturer" "Multicomp" (at 20.32 -20.32 0)
        (effects (font (size 1.27 1.27) (thickness 0.15)) (justify left bottom) hide)
      )
      (property "License" "Apache-2.0" (at 20.32 -22.86 0)
        (effects (font (size 1.27 1.27) (thickness 0.15)) (justify left bottom) hide)
      )
      (property "Author" "Antmicro" (at 20.32 -25.4 0)
        (effects (font (size 1.27 1.27) (thickness 0.15)) (justify left bottom) hide)
      )
      (property "Val" "18p" (at 20.32 -7.62 0)
        (effects (font (size 1.27 1.27) (thickness 0.15)) (justify left bottom))
      )
      (property "Voltage" "" (at 20.32 -27.94 0)
        (effects (font (size 1.27 1.27)) (justify left bottom) hide)
      )
      (property "Dielectric" "" (at 20.32 -30.48 0)
        (effects (font (size 1.27 1.27)) (justify left bottom) hide)
      )
      (property "ki_description" " " (at 0 0 0)
        (effects (font (size 1.27 1.27)) hide)
      )
      (symbol "C_18p_0402_0_1"
        (polyline
          (pts
            (xy 2.032 -1.524)
            (xy 2.032 1.524)
          )
          (stroke (width 0.3048) (type default))
          (fill (type none))
        )
        (polyline
          (pts
            (xy 3.048 -1.524)
            (xy 3.048 1.524)
          )
          (stroke (width 0.3302) (type default))
          (fill (type none))
        )
      )
      (symbol "C_18p_0402_1_1"
        (pin passive line (at 0 0 0) (length 2.032)
          (name "~" (effects (font (size 1.27 1.27))))
          (number "1" (effects (font (size 1.27 1.27))))
        )
        (pin passive line (at 5.08 0 180) (length 2.032)
          (name "~" (effects (font (size 1.27 1.27))))
          (number "2" (effects (font (size 1.27 1.27))))
        )
      )
    )
	(symbol "antmicroCapacitors0402:C_1u_0402" (pin_numbers hide) (pin_names hide) (in_bom yes) (on_board yes)
      (property "Reference" "C" (at 20.32 -5.08 0)
        (effects (font (size 1.27 1.27) (thickness 0.15)) (justify left bottom))
      )
      (property "Value" "C_1u_0402" (at 20.32 -10.16 0)
        (effects (font (size 1.27 1.27) (thickness 0.15)) (justify left bottom) hide)
      )
      (property "Footprint" "antmicro-footprints:C_0402_1005Metric" (at 20.32 -12.7 0)
        (effects (font (size 1.27 1.27) (thickness 0.15)) (justify left bottom) hide)
      )
      (property "Datasheet" " " (at 20.32 -15.24 0)
        (effects (font (size 1.27 1.27) (thickness 0.15)) (justify left bottom) hide)
      )
      (property "MPN" "C1005X6S1A105K050BC" (at 20.32 -17.78 0)
        (effects (font (size 1.27 1.27) (thickness 0.15)) (justify left bottom) hide)
      )
      (property "Manufacturer" "TDK" (at 20.32 -20.32 0)
        (effects (font (size 1.27 1.27) (thickness 0.15)) (justify left bottom) hide)
      )
      (property "License" "Apache-2.0" (at 20.32 -22.86 0)
        (effects (font (size 1.27 1.27) (thickness 0.15)) (justify left bottom) hide)
      )
      (property "Author" "Antmicro" (at 20.32 -25.4 0)
        (effects (font (size 1.27 1.27) (thickness 0.15)) (justify left bottom) hide)
      )
      (property "Val" "1u" (at 20.32 -7.62 0)
        (effects (font (size 1.27 1.27) (thickness 0.15)) (justify left bottom))
      )
      (property "Voltage" "" (at 20.32 -27.94 0)
        (effects (font (size 1.27 1.27)) (justify left bottom) hide)
      )
      (property "Dielectric" "" (at 20.32 -30.48 0)
        (effects (font (size 1.27 1.27)) (justify left bottom) hide)
      )
      (property "ki_description" " " (at 0 0 0)
        (effects (font (size 1.27 1.27)) hide)
      )
      (symbol "C_1u_0402_0_1"
        (polyline
          (pts
            (xy 2.032 -1.524)
            (xy 2.032 1.524)
          )
          (stroke (width 0.3048) (type default))
          (fill (type none))
        )
        (polyline
          (pts
            (xy 3.048 -1.524)
            (xy 3.048 1.524)
          )
          (stroke (width 0.3302) (type default))
          (fill (type none))
        )
      )
      (symbol "C_1u_0402_1_1"
        (pin passive line (at 0 0 0) (length 2.032)
          (name "~" (effects (font (size 1.27 1.27))))
          (number "1" (effects (font (size 1.27 1.27))))
        )
        (pin passive line (at 5.08 0 180) (length 2.032)
          (name "~" (effects (font (size 1.27 1.27))))
          (number "2" (effects (font (size 1.27 1.27))))
        )
      )
    )
	(symbol "antmicroCapacitors0402:C_1u_16V_0402" (pin_numbers hide) (pin_names hide) (in_bom yes) (on_board yes)
      (property "Reference" "C" (at 20.32 -5.08 0)
        (effects (font (size 1.27 1.27) (thickness 0.15)) (justify left bottom))
      )
      (property "Value" "C_1u_16V_0402" (at 20.32 -10.16 0)
        (effects (font (size 1.27 1.27) (thickness 0.15)) (justify left bottom) hide)
      )
      (property "Footprint" "antmicro-footprints:C_0402_1005Metric" (at 20.32 -12.7 0)
        (effects (font (size 1.27 1.27) (thickness 0.15)) (justify left bottom) hide)
      )
      (property "Datasheet" " " (at 20.32 -15.24 0)
        (effects (font (size 1.27 1.27) (thickness 0.15)) (justify left bottom) hide)
      )
      (property "MPN" "C0402C105M4PACTU" (at 20.32 -17.78 0)
        (effects (font (size 1.27 1.27) (thickness 0.15)) (justify left bottom) hide)
      )
      (property "Manufacturer" "KEMET" (at 20.32 -20.32 0)
        (effects (font (size 1.27 1.27) (thickness 0.15)) (justify left bottom) hide)
      )
      (property "License" "Apache-2.0" (at 20.32 -22.86 0)
        (effects (font (size 1.27 1.27) (thickness 0.15)) (justify left bottom) hide)
      )
      (property "Author" "Antmicro" (at 20.32 -25.4 0)
        (effects (font (size 1.27 1.27) (thickness 0.15)) (justify left bottom) hide)
      )
      (property "Val" "1u/16V" (at 20.32 -7.62 0)
        (effects (font (size 1.27 1.27) (thickness 0.15)) (justify left bottom))
      )
      (property "Voltage" "" (at 20.32 -27.94 0)
        (effects (font (size 1.27 1.27)) (justify left bottom) hide)
      )
      (property "Dielectric" "" (at 20.32 -30.48 0)
        (effects (font (size 1.27 1.27)) (justify left bottom) hide)
      )
      (property "ki_description" " " (at 0 0 0)
        (effects (font (size 1.27 1.27)) hide)
      )
      (symbol "C_1u_16V_0402_0_1"
        (polyline
          (pts
            (xy 2.032 -1.524)
            (xy 2.032 1.524)
          )
          (stroke (width 0.3048) (type default))
          (fill (type none))
        )
        (polyline
          (pts
            (xy 3.048 -1.524)
            (xy 3.048 1.524)
          )
          (stroke (width 0.3302) (type default))
          (fill (type none))
        )
      )
      (symbol "C_1u_16V_0402_1_1"
        (pin passive line (at 0 0 0) (length 2.032)
          (name "~" (effects (font (size 1.27 1.27))))
          (number "1" (effects (font (size 1.27 1.27))))
        )
        (pin passive line (at 5.08 0 180) (length 2.032)
          (name "~" (effects (font (size 1.27 1.27))))
          (number "2" (effects (font (size 1.27 1.27))))
        )
      )
    )
	(symbol "antmicroCapacitors0402:C_22p_0402" (pin_numbers hide) (pin_names hide) (in_bom yes) (on_board yes)
      (property "Reference" "C" (at 20.32 -5.08 0)
        (effects (font (size 1.27 1.27) (thickness 0.15)) (justify left bottom))
      )
      (property "Value" "C_22p_0402" (at 20.32 -10.16 0)
        (effects (font (size 1.27 1.27) (thickness 0.15)) (justify left bottom) hide)
      )
      (property "Footprint" "antmicro-footprints:C_0402_1005Metric" (at 20.32 -12.7 0)
        (effects (font (size 1.27 1.27) (thickness 0.15)) (justify left bottom) hide)
      )
      (property "Datasheet" " " (at 20.32 -15.24 0)
        (effects (font (size 1.27 1.27) (thickness 0.15)) (justify left bottom) hide)
      )
      (property "MPN" "CC0402JRNPO9BN220" (at 20.32 -17.78 0)
        (effects (font (size 1.27 1.27) (thickness 0.15)) (justify left bottom) hide)
      )
      (property "Manufacturer" "Yaego" (at 20.32 -20.32 0)
        (effects (font (size 1.27 1.27) (thickness 0.15)) (justify left bottom) hide)
      )
      (property "License" "Apache-2.0" (at 20.32 -22.86 0)
        (effects (font (size 1.27 1.27) (thickness 0.15)) (justify left bottom) hide)
      )
      (property "Author" "Antmicro" (at 20.32 -25.4 0)
        (effects (font (size 1.27 1.27) (thickness 0.15)) (justify left bottom) hide)
      )
      (property "Val" "22p" (at 20.32 -7.62 0)
        (effects (font (size 1.27 1.27) (thickness 0.15)) (justify left bottom))
      )
      (property "Voltage" "" (at 20.32 -27.94 0)
        (effects (font (size 1.27 1.27)) (justify left bottom) hide)
      )
      (property "Dielectric" "" (at 20.32 -30.48 0)
        (effects (font (size 1.27 1.27)) (justify left bottom) hide)
      )
      (property "ki_description" " " (at 0 0 0)
        (effects (font (size 1.27 1.27)) hide)
      )
      (symbol "C_22p_0402_0_1"
        (polyline
          (pts
            (xy 2.032 -1.524)
            (xy 2.032 1.524)
          )
          (stroke (width 0.3048) (type default))
          (fill (type none))
        )
        (polyline
          (pts
            (xy 3.048 -1.524)
            (xy 3.048 1.524)
          )
          (stroke (width 0.3302) (type default))
          (fill (type none))
        )
      )
      (symbol "C_22p_0402_1_1"
        (pin passive line (at 0 0 0) (length 2.032)
          (name "~" (effects (font (size 1.27 1.27))))
          (number "1" (effects (font (size 1.27 1.27))))
        )
        (pin passive line (at 5.08 0 180) (length 2.032)
          (name "~" (effects (font (size 1.27 1.27))))
          (number "2" (effects (font (size 1.27 1.27))))
        )
      )
    )
	(symbol "antmicroCapacitors0402:C_22u_0402" (pin_numbers hide) (pin_names hide) (in_bom yes) (on_board yes)
      (property "Reference" "C" (at 20.32 -5.08 0)
        (effects (font (size 1.27 1.27) (thickness 0.15)) (justify left bottom))
      )
      (property "Value" "C_22u_0402" (at 20.32 -10.16 0)
        (effects (font (size 1.27 1.27) (thickness 0.15)) (justify left bottom) hide)
      )
      (property "Footprint" "antmicro-footprints:C_0402_1005Metric" (at 20.32 -12.7 0)
        (effects (font (size 1.27 1.27) (thickness 0.15)) (justify left bottom) hide)
      )
      (property "Datasheet" " " (at 20.32 -15.24 0)
        (effects (font (size 1.27 1.27) (thickness 0.15)) (justify left bottom) hide)
      )
      (property "MPN" "04024W226MAT2A" (at 20.32 -17.78 0)
        (effects (font (size 1.27 1.27) (thickness 0.15)) (justify left bottom) hide)
      )
      (property "Manufacturer" "AVX" (at 20.32 -20.32 0)
        (effects (font (size 1.27 1.27) (thickness 0.15)) (justify left bottom) hide)
      )
      (property "License" "Apache-2.0" (at 20.32 -22.86 0)
        (effects (font (size 1.27 1.27) (thickness 0.15)) (justify left bottom) hide)
      )
      (property "Author" "Antmicro" (at 20.32 -25.4 0)
        (effects (font (size 1.27 1.27) (thickness 0.15)) (justify left bottom) hide)
      )
      (property "Val" "22u" (at 20.32 -7.62 0)
        (effects (font (size 1.27 1.27) (thickness 0.15)) (justify left bottom))
      )
      (property "Voltage" "" (at 20.32 -27.94 0)
        (effects (font (size 1.27 1.27)) (justify left bottom) hide)
      )
      (property "Dielectric" "" (at 20.32 -30.48 0)
        (effects (font (size 1.27 1.27)) (justify left bottom) hide)
      )
      (property "ki_description" " " (at 0 0 0)
        (effects (font (size 1.27 1.27)) hide)
      )
      (symbol "C_22u_0402_0_1"
        (polyline
          (pts
            (xy 2.032 -1.524)
            (xy 2.032 1.524)
          )
          (stroke (width 0.3048) (type default))
          (fill (type none))
        )
        (polyline
          (pts
            (xy 3.048 -1.524)
            (xy 3.048 1.524)
          )
          (stroke (width 0.3302) (type default))
          (fill (type none))
        )
      )
      (symbol "C_22u_0402_1_1"
        (pin passive line (at 0 0 0) (length 2.032)
          (name "~" (effects (font (size 1.27 1.27))))
          (number "1" (effects (font (size 1.27 1.27))))
        )
        (pin passive line (at 5.08 0 180) (length 2.032)
          (name "~" (effects (font (size 1.27 1.27))))
          (number "2" (effects (font (size 1.27 1.27))))
        )
      )
    )
	(symbol "antmicroCapacitors0402:C_470n_0402" (pin_numbers hide) (pin_names hide) (in_bom yes) (on_board yes)
      (property "Reference" "C" (at 20.32 -5.08 0)
        (effects (font (size 1.27 1.27) (thickness 0.15)) (justify left bottom))
      )
      (property "Value" "C_470n_0402" (at 20.32 -10.16 0)
        (effects (font (size 1.27 1.27) (thickness 0.15)) (justify left bottom) hide)
      )
      (property "Footprint" "antmicro-footprints:C_0402_1005Metric" (at 20.32 -12.7 0)
        (effects (font (size 1.27 1.27) (thickness 0.15)) (justify left bottom) hide)
      )
      (property "Datasheet" " " (at 20.32 -15.24 0)
        (effects (font (size 1.27 1.27) (thickness 0.15)) (justify left bottom) hide)
      )
      (property "MPN" "C1005X5R1E474M050BB" (at 20.32 -17.78 0)
        (effects (font (size 1.27 1.27) (thickness 0.15)) (justify left bottom) hide)
      )
      (property "Manufacturer" "TDK" (at 20.32 -20.32 0)
        (effects (font (size 1.27 1.27) (thickness 0.15)) (justify left bottom) hide)
      )
      (property "License" "Apache-2.0" (at 20.32 -22.86 0)
        (effects (font (size 1.27 1.27) (thickness 0.15)) (justify left bottom) hide)
      )
      (property "Author" "Antmicro" (at 20.32 -25.4 0)
        (effects (font (size 1.27 1.27) (thickness 0.15)) (justify left bottom) hide)
      )
      (property "Val" "470n" (at 20.32 -7.62 0)
        (effects (font (size 1.27 1.27) (thickness 0.15)) (justify left bottom))
      )
      (property "Voltage" "" (at 20.32 -27.94 0)
        (effects (font (size 1.27 1.27)) (justify left bottom) hide)
      )
      (property "Dielectric" "" (at 20.32 -30.48 0)
        (effects (font (size 1.27 1.27)) (justify left bottom) hide)
      )
      (property "ki_description" " " (at 0 0 0)
        (effects (font (size 1.27 1.27)) hide)
      )
      (symbol "C_470n_0402_0_1"
        (polyline
          (pts
            (xy 2.032 -1.524)
            (xy 2.032 1.524)
          )
          (stroke (width 0.3048) (type default))
          (fill (type none))
        )
        (polyline
          (pts
            (xy 3.048 -1.524)
            (xy 3.048 1.524)
          )
          (stroke (width 0.3302) (type default))
          (fill (type none))
        )
      )
      (symbol "C_470n_0402_1_1"
        (pin passive line (at 0 0 0) (length 2.032)
          (name "~" (effects (font (size 1.27 1.27))))
          (number "1" (effects (font (size 1.27 1.27))))
        )
        (pin passive line (at 5.08 0 180) (length 2.032)
          (name "~" (effects (font (size 1.27 1.27))))
          (number "2" (effects (font (size 1.27 1.27))))
        )
      )
    )
	(symbol "antmicroCapacitors0402:C_47p_0402" (pin_numbers hide) (pin_names hide) (in_bom yes) (on_board yes)
      (property "Reference" "C" (at 20.32 -5.08 0)
        (effects (font (size 1.27 1.27) (thickness 0.15)) (justify left bottom))
      )
      (property "Value" "C_47p_0402" (at 20.32 -10.16 0)
        (effects (font (size 1.27 1.27) (thickness 0.15)) (justify left bottom) hide)
      )
      (property "Footprint" "antmicro-footprints:C_0402_1005Metric" (at 20.32 -12.7 0)
        (effects (font (size 1.27 1.27) (thickness 0.15)) (justify left bottom) hide)
      )
      (property "Datasheet" " " (at 20.32 -15.24 0)
        (effects (font (size 1.27 1.27) (thickness 0.15)) (justify left bottom) hide)
      )
      (property "MPN" "GRM1555C1E470JA01D" (at 20.32 -17.78 0)
        (effects (font (size 1.27 1.27) (thickness 0.15)) (justify left bottom) hide)
      )
      (property "Manufacturer" "Murata" (at 20.32 -20.32 0)
        (effects (font (size 1.27 1.27) (thickness 0.15)) (justify left bottom) hide)
      )
      (property "License" "Apache-2.0" (at 20.32 -22.86 0)
        (effects (font (size 1.27 1.27) (thickness 0.15)) (justify left bottom) hide)
      )
      (property "Author" "Antmicro" (at 20.32 -25.4 0)
        (effects (font (size 1.27 1.27) (thickness 0.15)) (justify left bottom) hide)
      )
      (property "Val" "47p" (at 20.32 -7.62 0)
        (effects (font (size 1.27 1.27) (thickness 0.15)) (justify left bottom))
      )
      (property "Voltage" "" (at 20.32 -27.94 0)
        (effects (font (size 1.27 1.27)) (justify left bottom) hide)
      )
      (property "Dielectric" "C0G" (at 20.32 -30.48 0)
        (effects (font (size 1.27 1.27)) (justify left bottom) hide)
      )
      (property "ki_description" " " (at 0 0 0)
        (effects (font (size 1.27 1.27)) hide)
      )
      (symbol "C_47p_0402_0_1"
        (polyline
          (pts
            (xy 2.032 -1.524)
            (xy 2.032 1.524)
          )
          (stroke (width 0.3048) (type default))
          (fill (type none))
        )
        (polyline
          (pts
            (xy 3.048 -1.524)
            (xy 3.048 1.524)
          )
          (stroke (width 0.3302) (type default))
          (fill (type none))
        )
      )
      (symbol "C_47p_0402_1_1"
        (pin passive line (at 0 0 0) (length 2.032)
          (name "~" (effects (font (size 1.27 1.27))))
          (number "1" (effects (font (size 1.27 1.27))))
        )
        (pin passive line (at 5.08 0 180) (length 2.032)
          (name "~" (effects (font (size 1.27 1.27))))
          (number "2" (effects (font (size 1.27 1.27))))
        )
      )
    )
	(symbol "antmicroCapacitors0402:C_4n7_0402" (pin_numbers hide) (pin_names hide) (in_bom yes) (on_board yes)
      (property "Reference" "C" (at 20.32 -5.08 0)
        (effects (font (size 1.27 1.27) (thickness 0.15)) (justify left bottom))
      )
      (property "Value" "C_4n7_0402" (at 20.32 -10.16 0)
        (effects (font (size 1.27 1.27) (thickness 0.15)) (justify left bottom) hide)
      )
      (property "Footprint" "antmicro-footprints:C_0402_1005Metric" (at 20.32 -12.7 0)
        (effects (font (size 1.27 1.27) (thickness 0.15)) (justify left bottom) hide)
      )
      (property "Datasheet" " " (at 20.32 -15.24 0)
        (effects (font (size 1.27 1.27) (thickness 0.15)) (justify left bottom) hide)
      )
      (property "MPN" "CGA2B3X7S2A472K050BB" (at 20.32 -17.78 0)
        (effects (font (size 1.27 1.27) (thickness 0.15)) (justify left bottom) hide)
      )
      (property "Manufacturer" "TDK" (at 20.32 -20.32 0)
        (effects (font (size 1.27 1.27) (thickness 0.15)) (justify left bottom) hide)
      )
      (property "License" "Apache-2.0" (at 20.32 -22.86 0)
        (effects (font (size 1.27 1.27) (thickness 0.15)) (justify left bottom) hide)
      )
      (property "Author" "Antmicro" (at 20.32 -25.4 0)
        (effects (font (size 1.27 1.27) (thickness 0.15)) (justify left bottom) hide)
      )
      (property "Val" "4n7" (at 20.32 -7.62 0)
        (effects (font (size 1.27 1.27) (thickness 0.15)) (justify left bottom))
      )
      (property "Voltage" "" (at 20.32 -27.94 0)
        (effects (font (size 1.27 1.27)) (justify left bottom) hide)
      )
      (property "Dielectric" "" (at 20.32 -30.48 0)
        (effects (font (size 1.27 1.27)) (justify left bottom) hide)
      )
      (property "ki_description" " " (at 0 0 0)
        (effects (font (size 1.27 1.27)) hide)
      )
      (symbol "C_4n7_0402_0_1"
        (polyline
          (pts
            (xy 2.032 -1.524)
            (xy 2.032 1.524)
          )
          (stroke (width 0.3048) (type default))
          (fill (type none))
        )
        (polyline
          (pts
            (xy 3.048 -1.524)
            (xy 3.048 1.524)
          )
          (stroke (width 0.3302) (type default))
          (fill (type none))
        )
      )
      (symbol "C_4n7_0402_1_1"
        (pin passive line (at 0 0 0) (length 2.032)
          (name "~" (effects (font (size 1.27 1.27))))
          (number "1" (effects (font (size 1.27 1.27))))
        )
        (pin passive line (at 5.08 0 180) (length 2.032)
          (name "~" (effects (font (size 1.27 1.27))))
          (number "2" (effects (font (size 1.27 1.27))))
        )
      )
    )
	(symbol "antmicroCapacitors0402:C_4u7_0402" (pin_numbers hide) (pin_names hide) (in_bom yes) (on_board yes)
      (property "Reference" "C" (at 20.32 -5.08 0)
        (effects (font (size 1.27 1.27) (thickness 0.15)) (justify left bottom))
      )
      (property "Value" "C_4u7_0402" (at 20.32 -10.16 0)
        (effects (font (size 1.27 1.27) (thickness 0.15)) (justify left bottom) hide)
      )
      (property "Footprint" "antmicro-footprints:C_0402_1005Metric" (at 20.32 -12.7 0)
        (effects (font (size 1.27 1.27) (thickness 0.15)) (justify left bottom) hide)
      )
      (property "Datasheet" " " (at 20.32 -15.24 0)
        (effects (font (size 1.27 1.27) (thickness 0.15)) (justify left bottom) hide)
      )
      (property "MPN" "GRM155R61A475MEAAD" (at 20.32 -17.78 0)
        (effects (font (size 1.27 1.27) (thickness 0.15)) (justify left bottom) hide)
      )
      (property "Manufacturer" "Murata" (at 20.32 -20.32 0)
        (effects (font (size 1.27 1.27) (thickness 0.15)) (justify left bottom) hide)
      )
      (property "License" "Apache-2.0" (at 20.32 -22.86 0)
        (effects (font (size 1.27 1.27) (thickness 0.15)) (justify left bottom) hide)
      )
      (property "Author" "Antmicro" (at 20.32 -25.4 0)
        (effects (font (size 1.27 1.27) (thickness 0.15)) (justify left bottom) hide)
      )
      (property "Val" "4u7" (at 20.32 -7.62 0)
        (effects (font (size 1.27 1.27) (thickness 0.15)) (justify left bottom))
      )
      (property "Voltage" "" (at 20.32 -27.94 0)
        (effects (font (size 1.27 1.27)) (justify left bottom) hide)
      )
      (property "Dielectric" "" (at 20.32 -30.48 0)
        (effects (font (size 1.27 1.27)) (justify left bottom) hide)
      )
      (property "ki_description" " " (at 0 0 0)
        (effects (font (size 1.27 1.27)) hide)
      )
      (symbol "C_4u7_0402_0_1"
        (polyline
          (pts
            (xy 2.032 -1.524)
            (xy 2.032 1.524)
          )
          (stroke (width 0.3048) (type default))
          (fill (type none))
        )
        (polyline
          (pts
            (xy 3.048 -1.524)
            (xy 3.048 1.524)
          )
          (stroke (width 0.3302) (type default))
          (fill (type none))
        )
      )
      (symbol "C_4u7_0402_1_1"
        (pin passive line (at 0 0 0) (length 2.032)
          (name "~" (effects (font (size 1.27 1.27))))
          (number "1" (effects (font (size 1.27 1.27))))
        )
        (pin passive line (at 5.08 0 180) (length 2.032)
          (name "~" (effects (font (size 1.27 1.27))))
          (number "2" (effects (font (size 1.27 1.27))))
        )
      )
    )
	(symbol "antmicroCapacitors0603:C_100n_0603" (pin_numbers hide) (pin_names hide) (in_bom yes) (on_board yes)
      (property "Reference" "C" (at 20.32 -5.08 0)
        (effects (font (size 1.27 1.27) (thickness 0.15)) (justify left bottom))
      )
      (property "Value" "C_100n_0603" (at 20.32 -10.16 0)
        (effects (font (size 1.27 1.27) (thickness 0.15)) (justify left bottom) hide)
      )
      (property "Footprint" "antmicro-footprints:C_0603_1608Metric" (at 20.32 -12.7 0)
        (effects (font (size 1.27 1.27) (thickness 0.15)) (justify left bottom) hide)
      )
      (property "Datasheet" " " (at 20.32 -15.24 0)
        (effects (font (size 1.27 1.27) (thickness 0.15)) (justify left bottom) hide)
      )
      (property "MPN" "0603YC104KAZ2A" (at 20.32 -17.78 0)
        (effects (font (size 1.27 1.27) (thickness 0.15)) (justify left bottom) hide)
      )
      (property "Manufacturer" "AVX" (at 20.32 -20.32 0)
        (effects (font (size 1.27 1.27) (thickness 0.15)) (justify left bottom) hide)
      )
      (property "License" "Apache-2.0" (at 20.32 -22.86 0)
        (effects (font (size 1.27 1.27) (thickness 0.15)) (justify left bottom) hide)
      )
      (property "Author" "Antmicro" (at 20.32 -25.4 0)
        (effects (font (size 1.27 1.27) (thickness 0.15)) (justify left bottom) hide)
      )
      (property "Val" "100n" (at 20.32 -7.62 0)
        (effects (font (size 1.27 1.27) (thickness 0.15)) (justify left bottom))
      )
      (property "Voltage" "" (at 20.32 -27.94 0)
        (effects (font (size 1.27 1.27)) (justify left bottom) hide)
      )
      (property "Dielectric" "" (at 20.32 -30.48 0)
        (effects (font (size 1.27 1.27)) (justify left bottom) hide)
      )
      (property "ki_description" " " (at 0 0 0)
        (effects (font (size 1.27 1.27)) hide)
      )
      (symbol "C_100n_0603_0_1"
        (polyline
          (pts
            (xy 2.032 -1.524)
            (xy 2.032 1.524)
          )
          (stroke (width 0.3048) (type default))
          (fill (type none))
        )
        (polyline
          (pts
            (xy 3.048 -1.524)
            (xy 3.048 1.524)
          )
          (stroke (width 0.3302) (type default))
          (fill (type none))
        )
      )
      (symbol "C_100n_0603_1_1"
        (pin passive line (at 0 0 0) (length 2.032)
          (name "~" (effects (font (size 1.27 1.27))))
          (number "1" (effects (font (size 1.27 1.27))))
        )
        (pin passive line (at 5.08 0 180) (length 2.032)
          (name "~" (effects (font (size 1.27 1.27))))
          (number "2" (effects (font (size 1.27 1.27))))
        )
      )
    )
	(symbol "antmicroCapacitors0603:C_10n_0603" (pin_numbers hide) (pin_names hide) (in_bom yes) (on_board yes)
      (property "Reference" "C" (at 20.32 -5.08 0)
        (effects (font (size 1.27 1.27) (thickness 0.15)) (justify left bottom))
      )
      (property "Value" "C_10n_0603" (at 20.32 -10.16 0)
        (effects (font (size 1.27 1.27) (thickness 0.15)) (justify left bottom) hide)
      )
      (property "Footprint" "antmicro-footprints:C_0603_1608Metric" (at 20.32 -12.7 0)
        (effects (font (size 1.27 1.27) (thickness 0.15)) (justify left bottom) hide)
      )
      (property "Datasheet" " " (at 20.32 -15.24 0)
        (effects (font (size 1.27 1.27) (thickness 0.15)) (justify left bottom) hide)
      )
      (property "MPN" "06031C103JAT2A" (at 20.32 -17.78 0)
        (effects (font (size 1.27 1.27) (thickness 0.15)) (justify left bottom) hide)
      )
      (property "Manufacturer" "AVX" (at 20.32 -20.32 0)
        (effects (font (size 1.27 1.27) (thickness 0.15)) (justify left bottom) hide)
      )
      (property "License" "Apache-2.0" (at 20.32 -22.86 0)
        (effects (font (size 1.27 1.27) (thickness 0.15)) (justify left bottom) hide)
      )
      (property "Author" "Antmicro" (at 20.32 -25.4 0)
        (effects (font (size 1.27 1.27) (thickness 0.15)) (justify left bottom) hide)
      )
      (property "Val" "10n" (at 20.32 -7.62 0)
        (effects (font (size 1.27 1.27) (thickness 0.15)) (justify left bottom))
      )
      (property "Voltage" "" (at 20.32 -27.94 0)
        (effects (font (size 1.27 1.27)) (justify left bottom) hide)
      )
      (property "Dielectric" "" (at 20.32 -30.48 0)
        (effects (font (size 1.27 1.27)) (justify left bottom) hide)
      )
      (property "ki_description" " " (at 0 0 0)
        (effects (font (size 1.27 1.27)) hide)
      )
      (symbol "C_10n_0603_0_1"
        (polyline
          (pts
            (xy 2.032 -1.524)
            (xy 2.032 1.524)
          )
          (stroke (width 0.3048) (type default))
          (fill (type none))
        )
        (polyline
          (pts
            (xy 3.048 -1.524)
            (xy 3.048 1.524)
          )
          (stroke (width 0.3302) (type default))
          (fill (type none))
        )
      )
      (symbol "C_10n_0603_1_1"
        (pin passive line (at 0 0 0) (length 2.032)
          (name "~" (effects (font (size 1.27 1.27))))
          (number "1" (effects (font (size 1.27 1.27))))
        )
        (pin passive line (at 5.08 0 180) (length 2.032)
          (name "~" (effects (font (size 1.27 1.27))))
          (number "2" (effects (font (size 1.27 1.27))))
        )
      )
    )
	(symbol "antmicroCapacitors0603:C_10u_25V_0603" (pin_numbers hide) (pin_names hide) (in_bom yes) (on_board yes)
      (property "Reference" "C" (at 20.32 -5.08 0)
        (effects (font (size 1.27 1.27) (thickness 0.15)) (justify left bottom))
      )
      (property "Value" "C_10u_25V_0603" (at 20.32 -10.16 0)
        (effects (font (size 1.27 1.27) (thickness 0.15)) (justify left bottom) hide)
      )
      (property "Footprint" "antmicro-footprints:C_0603_1608Metric" (at 20.32 -12.7 0)
        (effects (font (size 1.27 1.27) (thickness 0.15)) (justify left bottom) hide)
      )
      (property "Datasheet" " " (at 20.32 -15.24 0)
        (effects (font (size 1.27 1.27) (thickness 0.15)) (justify left bottom) hide)
      )
      (property "MPN" "C1608X5R1E106M080AC" (at 20.32 -17.78 0)
        (effects (font (size 1.27 1.27) (thickness 0.15)) (justify left bottom) hide)
      )
      (property "Manufacturer" "TDK" (at 20.32 -20.32 0)
        (effects (font (size 1.27 1.27) (thickness 0.15)) (justify left bottom) hide)
      )
      (property "License" "Apache-2.0" (at 20.32 -22.86 0)
        (effects (font (size 1.27 1.27) (thickness 0.15)) (justify left bottom) hide)
      )
      (property "Author" "Antmicro" (at 20.32 -25.4 0)
        (effects (font (size 1.27 1.27) (thickness 0.15)) (justify left bottom) hide)
      )
      (property "Val" "10u/25V" (at 20.32 -7.62 0)
        (effects (font (size 1.27 1.27) (thickness 0.15)) (justify left bottom))
      )
      (property "Voltage" "" (at 20.32 -27.94 0)
        (effects (font (size 1.27 1.27)) (justify left bottom) hide)
      )
      (property "Dielectric" "" (at 20.32 -30.48 0)
        (effects (font (size 1.27 1.27)) (justify left bottom) hide)
      )
      (property "ki_description" " " (at 0 0 0)
        (effects (font (size 1.27 1.27)) hide)
      )
      (symbol "C_10u_25V_0603_0_1"
        (polyline
          (pts
            (xy 2.032 -1.524)
            (xy 2.032 1.524)
          )
          (stroke (width 0.3048) (type default))
          (fill (type none))
        )
        (polyline
          (pts
            (xy 3.048 -1.524)
            (xy 3.048 1.524)
          )
          (stroke (width 0.3302) (type default))
          (fill (type none))
        )
      )
      (symbol "C_10u_25V_0603_1_1"
        (pin passive line (at 0 0 0) (length 2.032)
          (name "~" (effects (font (size 1.27 1.27))))
          (number "1" (effects (font (size 1.27 1.27))))
        )
        (pin passive line (at 5.08 0 180) (length 2.032)
          (name "~" (effects (font (size 1.27 1.27))))
          (number "2" (effects (font (size 1.27 1.27))))
        )
      )
    )
	(symbol "antmicroCapacitors0603:C_1u_0603" (pin_numbers hide) (pin_names hide) (in_bom yes) (on_board yes)
      (property "Reference" "C" (at 20.32 -5.08 0)
        (effects (font (size 1.27 1.27) (thickness 0.15)) (justify left bottom))
      )
      (property "Value" "C_1u_0603" (at 20.32 -10.16 0)
        (effects (font (size 1.27 1.27) (thickness 0.15)) (justify left bottom) hide)
      )
      (property "Footprint" "antmicro-footprints:C_0603_1608Metric" (at 20.32 -12.7 0)
        (effects (font (size 1.27 1.27) (thickness 0.15)) (justify left bottom) hide)
      )
      (property "Datasheet" " " (at 20.32 -15.24 0)
        (effects (font (size 1.27 1.27) (thickness 0.15)) (justify left bottom) hide)
      )
      (property "MPN" "0603YD105KAT2A" (at 20.32 -17.78 0)
        (effects (font (size 1.27 1.27) (thickness 0.15)) (justify left bottom) hide)
      )
      (property "Manufacturer" "Walsin" (at 20.32 -20.32 0)
        (effects (font (size 1.27 1.27) (thickness 0.15)) (justify left bottom) hide)
      )
      (property "License" "Apache-2.0" (at 20.32 -22.86 0)
        (effects (font (size 1.27 1.27) (thickness 0.15)) (justify left bottom) hide)
      )
      (property "Author" "Antmicro" (at 20.32 -25.4 0)
        (effects (font (size 1.27 1.27) (thickness 0.15)) (justify left bottom) hide)
      )
      (property "Val" "1u" (at 20.32 -7.62 0)
        (effects (font (size 1.27 1.27) (thickness 0.15)) (justify left bottom))
      )
      (property "Voltage" "" (at 20.32 -27.94 0)
        (effects (font (size 1.27 1.27)) (justify left bottom) hide)
      )
      (property "Dielectric" "" (at 20.32 -30.48 0)
        (effects (font (size 1.27 1.27)) (justify left bottom) hide)
      )
      (property "ki_description" " " (at 0 0 0)
        (effects (font (size 1.27 1.27)) hide)
      )
      (symbol "C_1u_0603_0_1"
        (polyline
          (pts
            (xy 2.032 -1.524)
            (xy 2.032 1.524)
          )
          (stroke (width 0.3048) (type default))
          (fill (type none))
        )
        (polyline
          (pts
            (xy 3.048 -1.524)
            (xy 3.048 1.524)
          )
          (stroke (width 0.3302) (type default))
          (fill (type none))
        )
      )
      (symbol "C_1u_0603_1_1"
        (pin passive line (at 0 0 0) (length 2.032)
          (name "~" (effects (font (size 1.27 1.27))))
          (number "1" (effects (font (size 1.27 1.27))))
        )
        (pin passive line (at 5.08 0 180) (length 2.032)
          (name "~" (effects (font (size 1.27 1.27))))
          (number "2" (effects (font (size 1.27 1.27))))
        )
      )
    )
	(symbol "antmicroCapacitors0603:C_22u_0603" (pin_numbers hide) (pin_names hide) (in_bom yes) (on_board yes)
      (property "Reference" "C" (at 20.32 -5.08 0)
        (effects (font (size 1.27 1.27) (thickness 0.15)) (justify left bottom))
      )
      (property "Value" "C_22u_0603" (at 20.32 -10.16 0)
        (effects (font (size 1.27 1.27) (thickness 0.15)) (justify left bottom) hide)
      )
      (property "Footprint" "antmicro-footprints:C_0603_1608Metric" (at 20.32 -12.7 0)
        (effects (font (size 1.27 1.27) (thickness 0.15)) (justify left bottom) hide)
      )
      (property "Datasheet" " " (at 20.32 -15.24 0)
        (effects (font (size 1.27 1.27) (thickness 0.15)) (justify left bottom) hide)
      )
      (property "MPN" "GRM188R60J226MEA0D" (at 20.32 -17.78 0)
        (effects (font (size 1.27 1.27) (thickness 0.15)) (justify left bottom) hide)
      )
      (property "Manufacturer" "Murata" (at 20.32 -20.32 0)
        (effects (font (size 1.27 1.27) (thickness 0.15)) (justify left bottom) hide)
      )
      (property "License" "Apache-2.0" (at 20.32 -22.86 0)
        (effects (font (size 1.27 1.27) (thickness 0.15)) (justify left bottom) hide)
      )
      (property "Author" "Antmicro" (at 20.32 -25.4 0)
        (effects (font (size 1.27 1.27) (thickness 0.15)) (justify left bottom) hide)
      )
      (property "Val" "22u" (at 20.32 -7.62 0)
        (effects (font (size 1.27 1.27) (thickness 0.15)) (justify left bottom))
      )
      (property "Voltage" "" (at 20.32 -27.94 0)
        (effects (font (size 1.27 1.27)) (justify left bottom) hide)
      )
      (property "Dielectric" "" (at 20.32 -30.48 0)
        (effects (font (size 1.27 1.27)) (justify left bottom) hide)
      )
      (property "ki_description" " " (at 0 0 0)
        (effects (font (size 1.27 1.27)) hide)
      )
      (symbol "C_22u_0603_0_1"
        (polyline
          (pts
            (xy 2.032 -1.524)
            (xy 2.032 1.524)
          )
          (stroke (width 0.3048) (type default))
          (fill (type none))
        )
        (polyline
          (pts
            (xy 3.048 -1.524)
            (xy 3.048 1.524)
          )
          (stroke (width 0.3302) (type default))
          (fill (type none))
        )
      )
      (symbol "C_22u_0603_1_1"
        (pin passive line (at 0 0 0) (length 2.032)
          (name "~" (effects (font (size 1.27 1.27))))
          (number "1" (effects (font (size 1.27 1.27))))
        )
        (pin passive line (at 5.08 0 180) (length 2.032)
          (name "~" (effects (font (size 1.27 1.27))))
          (number "2" (effects (font (size 1.27 1.27))))
        )
      )
    )
	(symbol "antmicroCapacitors0603:C_47u_0603" (pin_numbers hide) (pin_names hide) (in_bom yes) (on_board yes)
      (property "Reference" "C" (at 20.32 -5.08 0)
        (effects (font (size 1.27 1.27) (thickness 0.15)) (justify left bottom))
      )
      (property "Value" "C_47u_0603" (at 20.32 -10.16 0)
        (effects (font (size 1.27 1.27) (thickness 0.15)) (justify left bottom) hide)
      )
      (property "Footprint" "antmicro-footprints:C_0603_1608Metric" (at 20.32 -12.7 0)
        (effects (font (size 1.27 1.27) (thickness 0.15)) (justify left bottom) hide)
      )
      (property "Datasheet" " " (at 20.32 -15.24 0)
        (effects (font (size 1.27 1.27) (thickness 0.15)) (justify left bottom) hide)
      )
      (property "MPN" "GRM188R60J476ME15D" (at 20.32 -17.78 0)
        (effects (font (size 1.27 1.27) (thickness 0.15)) (justify left bottom) hide)
      )
      (property "Manufacturer" "Murata" (at 20.32 -20.32 0)
        (effects (font (size 1.27 1.27) (thickness 0.15)) (justify left bottom) hide)
      )
      (property "License" "Apache-2.0" (at 20.32 -22.86 0)
        (effects (font (size 1.27 1.27) (thickness 0.15)) (justify left bottom) hide)
      )
      (property "Author" "Antmicro" (at 20.32 -25.4 0)
        (effects (font (size 1.27 1.27) (thickness 0.15)) (justify left bottom) hide)
      )
      (property "Val" "47u" (at 20.32 -7.62 0)
        (effects (font (size 1.27 1.27) (thickness 0.15)) (justify left bottom))
      )
      (property "Voltage" "" (at 20.32 -27.94 0)
        (effects (font (size 1.27 1.27)) (justify left bottom) hide)
      )
      (property "Dielectric" "" (at 20.32 -30.48 0)
        (effects (font (size 1.27 1.27)) (justify left bottom) hide)
      )
      (property "ki_description" " " (at 0 0 0)
        (effects (font (size 1.27 1.27)) hide)
      )
      (symbol "C_47u_0603_0_1"
        (polyline
          (pts
            (xy 2.032 -1.524)
            (xy 2.032 1.524)
          )
          (stroke (width 0.3048) (type default))
          (fill (type none))
        )
        (polyline
          (pts
            (xy 3.048 -1.524)
            (xy 3.048 1.524)
          )
          (stroke (width 0.3302) (type default))
          (fill (type none))
        )
      )
      (symbol "C_47u_0603_1_1"
        (pin passive line (at 0 0 0) (length 2.032)
          (name "~" (effects (font (size 1.27 1.27))))
          (number "1" (effects (font (size 1.27 1.27))))
        )
        (pin passive line (at 5.08 0 180) (length 2.032)
          (name "~" (effects (font (size 1.27 1.27))))
          (number "2" (effects (font (size 1.27 1.27))))
        )
      )
    )
	(symbol "antmicroCapacitorsmisc:C_100n_0201" (pin_numbers hide) (pin_names hide) (in_bom yes) (on_board yes)
      (property "Reference" "C" (at 20.32 -5.08 0)
        (effects (font (size 1.27 1.27) (thickness 0.15)) (justify left bottom))
      )
      (property "Value" "C_100n_0201" (at 20.32 -10.16 0)
        (effects (font (size 1.27 1.27) (thickness 0.15)) (justify left bottom) hide)
      )
      (property "Footprint" "antmicro-footprints:C_0201" (at 20.32 -12.7 0)
        (effects (font (size 1.27 1.27) (thickness 0.15)) (justify left bottom) hide)
      )
      (property "Datasheet" " " (at 20.32 -15.24 0)
        (effects (font (size 1.27 1.27) (thickness 0.15)) (justify left bottom) hide)
      )
      (property "MPN" "CC0201KRX6S5BB104" (at 20.32 -17.78 0)
        (effects (font (size 1.27 1.27) (thickness 0.15)) (justify left bottom) hide)
      )
      (property "Manufacturer" "Yaego" (at 20.32 -20.32 0)
        (effects (font (size 1.27 1.27) (thickness 0.15)) (justify left bottom) hide)
      )
      (property "License" "Apache-2.0" (at 20.32 -22.86 0)
        (effects (font (size 1.27 1.27) (thickness 0.15)) (justify left bottom) hide)
      )
      (property "Author" "Antmicro" (at 20.32 -25.4 0)
        (effects (font (size 1.27 1.27) (thickness 0.15)) (justify left bottom) hide)
      )
      (property "Val" "100n" (at 20.32 -7.62 0)
        (effects (font (size 1.27 1.27) (thickness 0.15)) (justify left bottom))
      )
      (property "Voltage" "" (at 20.32 -27.94 0)
        (effects (font (size 1.27 1.27)) (justify left bottom) hide)
      )
      (property "Dielectric" "" (at 20.32 -30.48 0)
        (effects (font (size 1.27 1.27)) (justify left bottom) hide)
      )
      (property "ki_description" " " (at 0 0 0)
        (effects (font (size 1.27 1.27)) hide)
      )
      (symbol "C_100n_0201_0_1"
        (polyline
          (pts
            (xy 2.032 -1.524)
            (xy 2.032 1.524)
          )
          (stroke (width 0.3048) (type default))
          (fill (type none))
        )
        (polyline
          (pts
            (xy 3.048 -1.524)
            (xy 3.048 1.524)
          )
          (stroke (width 0.3302) (type default))
          (fill (type none))
        )
      )
      (symbol "C_100n_0201_1_1"
        (pin passive line (at 0 0 0) (length 2.032)
          (name "~" (effects (font (size 1.27 1.27))))
          (number "1" (effects (font (size 1.27 1.27))))
        )
        (pin passive line (at 5.08 0 180) (length 2.032)
          (name "~" (effects (font (size 1.27 1.27))))
          (number "2" (effects (font (size 1.27 1.27))))
        )
      )
    )
	(symbol "antmicroCapacitorsmisc:C_22u_100V_2220" (pin_numbers hide) (pin_names hide) (in_bom yes) (on_board yes)
      (property "Reference" "C" (at 20.32 -5.08 0)
        (effects (font (size 1.27 1.27) (thickness 0.15)) (justify left bottom))
      )
      (property "Value" "C_22u_100V_2220" (at 20.32 -10.16 0)
        (effects (font (size 1.27 1.27) (thickness 0.15)) (justify left bottom) hide)
      )
      (property "Footprint" "antmicro-footprints:C_2220_5650Metric" (at 20.32 -12.7 0)
        (effects (font (size 1.27 1.27) (thickness 0.15)) (justify left bottom) hide)
      )
      (property "Datasheet" " " (at 20.32 -15.24 0)
        (effects (font (size 1.27 1.27) (thickness 0.15)) (justify left bottom) hide)
      )
      (property "MPN" "C5750X7S2A226M280KB" (at 20.32 -17.78 0)
        (effects (font (size 1.27 1.27) (thickness 0.15)) (justify left bottom) hide)
      )
      (property "Manufacturer" "TDK" (at 20.32 -20.32 0)
        (effects (font (size 1.27 1.27) (thickness 0.15)) (justify left bottom) hide)
      )
      (property "License" "Apache-2.0" (at 20.32 -22.86 0)
        (effects (font (size 1.27 1.27) (thickness 0.15)) (justify left bottom) hide)
      )
      (property "Author" "Antmicro" (at 20.32 -25.4 0)
        (effects (font (size 1.27 1.27) (thickness 0.15)) (justify left bottom) hide)
      )
      (property "Val" "22u/100V" (at 20.32 -7.62 0)
        (effects (font (size 1.27 1.27) (thickness 0.15)) (justify left bottom))
      )
      (property "Voltage" "" (at 20.32 -27.94 0)
        (effects (font (size 1.27 1.27)) (justify left bottom) hide)
      )
      (property "Dielectric" "" (at 20.32 -30.48 0)
        (effects (font (size 1.27 1.27)) (justify left bottom) hide)
      )
      (property "ki_description" " " (at 0 0 0)
        (effects (font (size 1.27 1.27)) hide)
      )
      (symbol "C_22u_100V_2220_0_1"
        (polyline
          (pts
            (xy 2.032 -1.524)
            (xy 2.032 1.524)
          )
          (stroke (width 0.3048) (type default))
          (fill (type none))
        )
        (polyline
          (pts
            (xy 3.048 -1.524)
            (xy 3.048 1.524)
          )
          (stroke (width 0.3302) (type default))
          (fill (type none))
        )
      )
      (symbol "C_22u_100V_2220_1_1"
        (pin passive line (at 0 0 0) (length 2.032)
          (name "~" (effects (font (size 1.27 1.27))))
          (number "1" (effects (font (size 1.27 1.27))))
        )
        (pin passive line (at 5.08 0 180) (length 2.032)
          (name "~" (effects (font (size 1.27 1.27))))
          (number "2" (effects (font (size 1.27 1.27))))
        )
      )
    )
	(symbol "antmicroCapacitorsmisc:C_47u_16V_1206" (pin_numbers hide) (pin_names hide) (in_bom yes) (on_board yes)
      (property "Reference" "C" (at 20.32 -5.08 0)
        (effects (font (size 1.27 1.27) (thickness 0.15)) (justify left bottom))
      )
      (property "Value" "C_47u_16V_1206" (at 20.32 -10.16 0)
        (effects (font (size 1.27 1.27) (thickness 0.15)) (justify left bottom) hide)
      )
      (property "Footprint" "antmicro-footprints:C_1206_3216Metric" (at 20.32 -12.7 0)
        (effects (font (size 1.27 1.27) (thickness 0.15)) (justify left bottom) hide)
      )
      (property "Datasheet" " " (at 20.32 -15.24 0)
        (effects (font (size 1.27 1.27) (thickness 0.15)) (justify left bottom) hide)
      )
      (property "MPN" "C3216X5R1C476M160AB" (at 20.32 -17.78 0)
        (effects (font (size 1.27 1.27) (thickness 0.15)) (justify left bottom) hide)
      )
      (property "Manufacturer" "TDK" (at 20.32 -20.32 0)
        (effects (font (size 1.27 1.27) (thickness 0.15)) (justify left bottom) hide)
      )
      (property "License" "Apache-2.0" (at 20.32 -22.86 0)
        (effects (font (size 1.27 1.27) (thickness 0.15)) (justify left bottom) hide)
      )
      (property "Author" "Antmicro" (at 20.32 -25.4 0)
        (effects (font (size 1.27 1.27) (thickness 0.15)) (justify left bottom) hide)
      )
      (property "Val" "47u/16V" (at 20.32 -7.62 0)
        (effects (font (size 1.27 1.27) (thickness 0.15)) (justify left bottom))
      )
      (property "Voltage" "" (at 20.32 -27.94 0)
        (effects (font (size 1.27 1.27)) (justify left bottom) hide)
      )
      (property "Dielectric" "" (at 20.32 -30.48 0)
        (effects (font (size 1.27 1.27)) (justify left bottom) hide)
      )
      (property "ki_description" " " (at 0 0 0)
        (effects (font (size 1.27 1.27)) hide)
      )
      (symbol "C_47u_16V_1206_0_1"
        (polyline
          (pts
            (xy 2.032 -1.524)
            (xy 2.032 1.524)
          )
          (stroke (width 0.3048) (type default))
          (fill (type none))
        )
        (polyline
          (pts
            (xy 3.048 -1.524)
            (xy 3.048 1.524)
          )
          (stroke (width 0.3302) (type default))
          (fill (type none))
        )
      )
      (symbol "C_47u_16V_1206_1_1"
        (pin passive line (at 0 0 0) (length 2.032)
          (name "~" (effects (font (size 1.27 1.27))))
          (number "1" (effects (font (size 1.27 1.27))))
        )
        (pin passive line (at 5.08 0 180) (length 2.032)
          (name "~" (effects (font (size 1.27 1.27))))
          (number "2" (effects (font (size 1.27 1.27))))
        )
      )
    )
	(symbol "antmicroDCDCConverters:PDQE30-Q48-S12-D" (in_bom yes) (on_board yes)
      (property "Reference" "U" (at 35.56 -2.54 0)
        (effects (font (size 1.27 1.27) (thickness 0.15)) (justify left bottom))
      )
      (property "Value" "PDQE30-Q48-S12-D" (at 35.56 -5.08 0)
        (effects (font (size 1.27 1.27) (thickness 0.15)) (justify left bottom))
      )
      (property "Footprint" "antmicro-footprints:CONV_PDQE30-Q48-S5-D" (at 35.56 -7.62 0)
        (effects (font (size 1.27 1.27) (thickness 0.15)) (justify left bottom) hide)
      )
      (property "Datasheet" "https://www.cui.com/product/resource/pdqe30-d.pdf" (at 35.56 -10.16 0)
        (effects (font (size 1.27 1.27) (thickness 0.15)) (justify left bottom) hide)
      )
      (property "MPN" "PDQE30-Q48-S12-D" (at 35.56 -15.24 0)
        (effects (font (size 1.27 1.27) (thickness 0.15)) (justify left bottom) hide)
      )
      (property "Manufacturer" "CUI Inc" (at 35.56 -17.78 0)
        (effects (font (size 1.27 1.27) (thickness 0.15)) (justify left bottom) hide)
      )
      (property "Author" "Antmicro" (at 35.56 -20.32 0)
        (effects (font (size 1.27 1.27) (thickness 0.15)) (justify left bottom) hide)
      )
      (property "License" "Apache-2.0" (at 35.56 -22.86 0)
        (effects (font (size 1.27 1.27) (thickness 0.15)) (justify left bottom) hide)
      )
      (property "ki_keywords" "dc converter step down 12v 48v isolated 30W poe" (at 0 0 0)
        (effects (font (size 1.27 1.27)) hide)
      )
      (property "ki_description" "DC-DC CONVERTER, 48VDC input, 12VDC nom isolated output w/ trim option, 30W, 270kHz PWM mode" (at 0 0 0)
        (effects (font (size 1.27 1.27)) hide)
      )
      (symbol "PDQE30-Q48-S12-D_1_1"
        (rectangle (start 2.54 2.54) (end 17.78 -17.78)
          (stroke (width 0.254) (type default))
          (fill (type background))
        )
        (pin input line (at 0 -7.62 0) (length 2.54)
          (name "CTRL" (effects (font (size 1.27 1.27))))
          (number "1" (effects (font (size 1.27 1.27))))
        )
        (pin power_in line (at 0 -15.24 0) (length 2.54)
          (name "VIN-" (effects (font (size 1.27 1.27))))
          (number "2" (effects (font (size 1.27 1.27))))
        )
        (pin power_in line (at 0 0 0) (length 2.54)
          (name "VIN+" (effects (font (size 1.27 1.27))))
          (number "3" (effects (font (size 1.27 1.27))))
        )
        (pin power_in line (at 20.32 0 180) (length 2.54)
          (name "VOUT" (effects (font (size 1.27 1.27))))
          (number "4" (effects (font (size 1.27 1.27))))
        )
        (pin passive line (at 20.32 -7.62 180) (length 2.54)
          (name "TRIM" (effects (font (size 1.27 1.27))))
          (number "5" (effects (font (size 1.27 1.27))))
        )
        (pin power_in line (at 20.32 -15.24 180) (length 2.54)
          (name "GND" (effects (font (size 1.27 1.27))))
          (number "6" (effects (font (size 1.27 1.27))))
        )
      )
    )
	(symbol "antmicroDiodesRectifiersSingle:PDS760" (pin_numbers hide) (pin_names hide) (in_bom yes) (on_board yes)
      (property "Reference" "D" (at 22.86 -5.08 0)
        (effects (font (size 1.27 1.27) (thickness 0.15)) (justify left bottom))
      )
      (property "Value" "PDS760" (at 22.86 -7.62 0)
        (effects (font (size 1.27 1.27) (thickness 0.15)) (justify left bottom))
      )
      (property "Footprint" "antmicro-footprints:PowerDI5" (at 22.86 -10.16 0)
        (effects (font (size 1.27 1.27) (thickness 0.15)) (justify left bottom) hide)
      )
      (property "Datasheet" "https://www.diodes.com/assets/Datasheets/ds30470.pdf" (at 22.86 -12.7 0)
        (effects (font (size 1.27 1.27) (thickness 0.15)) (justify left bottom) hide)
      )
      (property "Manufacturer" "Diodes Incorporated" (at 22.86 -15.24 0)
        (effects (font (size 1.27 1.27) (thickness 0.15)) (justify left bottom) hide)
      )
      (property "MPN" "PDS760-13" (at 22.86 -17.78 0)
        (effects (font (size 1.27 1.27) (thickness 0.15)) (justify left bottom) hide)
      )
      (property "Author" "Antmicro" (at 22.86 -20.32 0)
        (effects (font (size 1.27 1.27) (thickness 0.15)) (justify left bottom) hide)
      )
      (property "License" "Apache-2.0" (at 22.86 -22.86 0)
        (effects (font (size 1.27 1.27) (thickness 0.15)) (justify left bottom) hide)
      )
      (property "ki_keywords" "PDS760 Series 60 V 7 A Surface Mount Schottky Barrier Rectifier - PowerDI-5" (at 0 0 0)
        (effects (font (size 1.27 1.27)) hide)
      )
      (property "ki_description" "PDS760 Series 60 V 7 A Surface Mount Schottky Barrier Rectifier - PowerDI-5" (at 0 0 0)
        (effects (font (size 1.27 1.27)) hide)
      )
      (symbol "PDS760_1_1"
        (polyline
          (pts
            (xy 4.572 -1.016)
            (xy 4.572 -1.3462)
          )
          (stroke (width 0.254) (type default))
          (fill (type background))
        )
        (polyline
          (pts
            (xy 5.588 1.1938)
            (xy 5.588 0.8128)
          )
          (stroke (width 0.254) (type default))
          (fill (type background))
        )
        (polyline
          (pts
            (xy 2.54 1.27)
            (xy 2.54 -1.27)
            (xy 5.08 0)
            (xy 2.54 1.27)
          )
          (stroke (width 0.254) (type default))
          (fill (type outline))
        )
        (polyline
          (pts
            (xy 5.588 1.1938)
            (xy 5.08 1.1938)
            (xy 5.08 -1.3462)
            (xy 4.572 -1.3462)
          )
          (stroke (width 0.254) (type default))
          (fill (type none))
        )
        (pin passive line (at 0 0 0) (length 2.54)
          (name "A" (effects (font (size 1.27 1.27))))
          (number "A" (effects (font (size 1.27 1.27))))
        )
        (pin passive line (at 7.62 0 180) (length 2.54)
          (name "C" (effects (font (size 1.27 1.27))))
          (number "C" (effects (font (size 1.27 1.27))))
        )
      )
    )
	(symbol "antmicroDiodesRectifiersSingle:PTVS58VS1UR,115" (pin_numbers hide) (pin_names hide) (in_bom yes) (on_board yes)
      (property "Reference" "D" (at 21.59 -5.08 0)
        (effects (font (size 1.27 1.27) (thickness 0.15)) (justify left bottom))
      )
      (property "Value" "PTVS58VS1UR,115" (at 21.59 -7.62 0)
        (effects (font (size 1.27 1.27) (thickness 0.15)) (justify left bottom))
      )
      (property "Footprint" "antmicro-footprints:D_SOD-123F" (at 21.59 -10.16 0)
        (effects (font (size 1.27 1.27) (thickness 0.15)) (justify left bottom) hide)
      )
      (property "Datasheet" "https://assets.nexperia.com/documents/data-sheet/PTVSXS1UR_SER.pdf" (at 21.59 -12.7 0)
        (effects (font (size 1.27 1.27) (thickness 0.15)) (justify left bottom) hide)
      )
      (property "MPN" "PTVS58VS1UR,115" (at 21.59 -15.24 0)
        (effects (font (size 1.27 1.27) (thickness 0.15)) (justify left bottom) hide)
      )
      (property "Manufacturer" "Nexperia" (at 21.59 -17.78 0)
        (effects (font (size 1.27 1.27) (thickness 0.15)) (justify left bottom) hide)
      )
      (property "Author" "Antmicro" (at 21.59 -20.32 0)
        (effects (font (size 1.27 1.27) (thickness 0.15)) (justify left bottom) hide)
      )
      (property "License" "Apache-2.0" (at 21.59 -22.86 0)
        (effects (font (size 1.27 1.27) (thickness 0.15)) (justify left bottom) hide)
      )
      (property "ki_keywords" "400 W Transient Voltage Suppressor" (at 0 0 0)
        (effects (font (size 1.27 1.27)) hide)
      )
      (property "ki_description" "400 W Transient Voltage Suppressor" (at 0 0 0)
        (effects (font (size 1.27 1.27)) hide)
      )
      (symbol "PTVS58VS1UR,115_0_1"
        (polyline
          (pts
            (xy 5.715 1.905)
            (xy 5.08 1.27)
            (xy 5.08 -1.27)
            (xy 4.445 -1.905)
          )
          (stroke (width 0.254) (type default))
          (fill (type none))
        )
      )
      (symbol "PTVS58VS1UR,115_1_1"
        (polyline
          (pts
            (xy 2.54 1.27)
            (xy 2.54 -1.27)
            (xy 5.08 0)
            (xy 2.54 1.27)
          )
          (stroke (width 0.254) (type default))
          (fill (type outline))
        )
        (pin passive line (at 0 0 0) (length 2.54)
          (name "A" (effects (font (size 1.27 1.27))))
          (number "A" (effects (font (size 1.27 1.27))))
        )
        (pin passive line (at 7.62 0 180) (length 2.54)
          (name "C" (effects (font (size 1.27 1.27))))
          (number "K" (effects (font (size 1.27 1.27))))
        )
      )
    )
	(symbol "antmicroDiodesZenerSingle:BZX84C5V1-TP" (pin_names hide) (in_bom yes) (on_board yes)
      (property "Reference" "D" (at 22.86 -5.08 0)
        (effects (font (size 1.27 1.27) (thickness 0.15)) (justify left bottom))
      )
      (property "Value" "BZX84C5V1-TP" (at 22.86 -7.62 0)
        (effects (font (size 1.27 1.27) (thickness 0.15)) (justify left bottom))
      )
      (property "Footprint" "antmicro-footprints:SOT-23-3" (at 22.86 -10.16 0)
        (effects (font (size 1.27 1.27) (thickness 0.15)) (justify left bottom) hide)
      )
      (property "Datasheet" "https://www.mccsemi.com/pdf/Products/BZX84C(B)2V4~BZX84C(B)75(SOT-23).pdf" (at 22.86 -12.7 0)
        (effects (font (size 1.27 1.27) (thickness 0.15)) (justify left bottom) hide)
      )
      (property "MPN" "BZX84C5V1-TP" (at 22.86 -15.24 0)
        (effects (font (size 1.27 1.27) (thickness 0.15)) (justify left bottom) hide)
      )
      (property "Manufacturer" "Micro Commercial Co" (at 22.86 -17.78 0)
        (effects (font (size 1.27 1.27) (thickness 0.15)) (justify left bottom) hide)
      )
      (property "Author" "Antmicro" (at 22.86 -20.32 0)
        (effects (font (size 1.27 1.27) (thickness 0.15)) (justify left bottom) hide)
      )
      (property "License" "Apache-2.0" (at 22.86 -22.86 0)
        (effects (font (size 1.27 1.27) (thickness 0.15)) (justify left bottom) hide)
      )
      (property "ki_description" "DIODE ZENER 5.1V 350MW SOT23" (at 0 0 0)
        (effects (font (size 1.27 1.27)) hide)
      )
      (symbol "BZX84C5V1-TP_1_1"
        (polyline
          (pts
            (xy 5.08 0)
            (xy 2.54 0)
          )
          (stroke (width 0.254) (type default))
          (fill (type none))
        )
        (polyline
          (pts
            (xy 2.54 -1.27)
            (xy 2.54 1.27)
            (xy 3.048 1.27)
          )
          (stroke (width 0.254) (type default))
          (fill (type none))
        )
        (polyline
          (pts
            (xy 5.08 -1.27)
            (xy 5.08 1.27)
            (xy 2.54 0)
            (xy 5.08 -1.27)
          )
          (stroke (width 0.254) (type default))
          (fill (type outline))
        )
        (pin passive line (at 7.62 0 180) (length 2.54)
          (name "1" (effects (font (size 1.27 1.27))))
          (number "1" (effects (font (size 1.27 1.27))))
        )
        (pin no_connect line (at 2.54 0 0) (length 2.54) hide
          (name "2" (effects (font (size 1.27 1.27))))
          (number "2" (effects (font (size 1.27 1.27))))
        )
        (pin passive line (at 0 0 0) (length 2.54)
          (name "3" (effects (font (size 1.27 1.27))))
          (number "3" (effects (font (size 1.27 1.27))))
        )
      )
    )
	(symbol "antmicroFMCConnectors:ASP-134486-01" (in_bom yes) (on_board yes)
      (property "Reference" "J" (at 45.72 -6.35 0)
        (effects (font (size 1.27 1.27) (thickness 0.15)) (justify left bottom))
      )
      (property "Value" "ASP-134486-01" (at 45.72 -8.89 0)
        (effects (font (size 1.27 1.27) (thickness 0.15)) (justify left bottom))
      )
      (property "Footprint" "antmicro-footprints:FMC_SAMTEC_ASP-134486-01" (at 45.72 -11.43 0)
        (effects (font (size 1.27 1.27) (thickness 0.15)) (justify left bottom) hide)
      )
      (property "Datasheet" "https://suddendocs.samtec.com/prints/asp-134486-01-mkt.pdf?_gl=1*a2d3qa*_ga*MzYxMTM5My4xNjYzOTI3MDkz*_ga_3KFNZC07WW*MTY2NDIwMTUxMC4zLjAuMTY2NDIwMTUxMC42MC4wLjA." (at 45.72 -13.97 0)
        (effects (font (size 1.27 1.27) (thickness 0.15)) (justify left bottom) hide)
      )
      (property "Manufacturer" "Samtec" (at 45.72 -16.51 0)
        (effects (font (size 1.27 1.27) (thickness 0.15)) (justify left bottom) hide)
      )
      (property "MPN" "ASP-134486-01" (at 45.72 -19.05 0)
        (effects (font (size 1.27 1.27) (thickness 0.15)) (justify left bottom) hide)
      )
      (property "Author" "Antmicro" (at 45.72 -21.59 0)
        (effects (font (size 1.27 1.27) (thickness 0.15)) (justify left bottom) hide)
      )
      (property "License" "Apache-2.0" (at 45.72 -24.13 0)
        (effects (font (size 1.27 1.27) (thickness 0.15)) (justify left bottom) hide)
      )
      (property "ki_locked" "" (at 0 0 0)
        (effects (font (size 1.27 1.27)))
      )
      (property "ki_description" "400-pole 10-row 1.27mm Female FMC HPC Connector with gold-plated copper alloy contacts. " (at 0 0 0)
        (effects (font (size 1.27 1.27)) hide)
      )
      (symbol "ASP-134486-01_1_1"
        (rectangle (start 3.81 2.54) (end 26.67 -87.63)
          (stroke (width 0.254) (type default))
          (fill (type background))
        )
        (pin passive line (at 0 -82.55 0) (length 3.81)
          (name "GND" (effects (font (size 1.27 1.27))))
          (number "J1" (effects (font (size 1.27 1.27))))
        )
        (pin passive line (at 30.48 -21.59 180) (length 3.81)
          (name "HA07-" (effects (font (size 1.27 1.27))))
          (number "J10" (effects (font (size 1.27 1.27))))
        )
        (pin passive line (at 0 -82.55 0) (length 3.81) hide
          (name "GND" (effects (font (size 1.27 1.27))))
          (number "J11" (effects (font (size 1.27 1.27))))
        )
        (pin passive line (at 30.48 -25.4 180) (length 3.81)
          (name "HA11+" (effects (font (size 1.27 1.27))))
          (number "J12" (effects (font (size 1.27 1.27))))
        )
        (pin passive line (at 30.48 -27.94 180) (length 3.81)
          (name "HA11-" (effects (font (size 1.27 1.27))))
          (number "J13" (effects (font (size 1.27 1.27))))
        )
        (pin passive line (at 0 -82.55 0) (length 3.81) hide
          (name "GND" (effects (font (size 1.27 1.27))))
          (number "J14" (effects (font (size 1.27 1.27))))
        )
        (pin passive line (at 30.48 -31.75 180) (length 3.81)
          (name "HA14+" (effects (font (size 1.27 1.27))))
          (number "J15" (effects (font (size 1.27 1.27))))
        )
        (pin passive line (at 30.48 -34.29 180) (length 3.81)
          (name "HA14-" (effects (font (size 1.27 1.27))))
          (number "J16" (effects (font (size 1.27 1.27))))
        )
        (pin passive line (at 0 -82.55 0) (length 3.81) hide
          (name "GND" (effects (font (size 1.27 1.27))))
          (number "J17" (effects (font (size 1.27 1.27))))
        )
        (pin passive line (at 30.48 -38.1 180) (length 3.81)
          (name "HA18+" (effects (font (size 1.27 1.27))))
          (number "J18" (effects (font (size 1.27 1.27))))
        )
        (pin passive line (at 30.48 -40.64 180) (length 3.81)
          (name "HA18-" (effects (font (size 1.27 1.27))))
          (number "J19" (effects (font (size 1.27 1.27))))
        )
        (pin passive line (at 30.48 -6.35 180) (length 3.81)
          (name "CLK3_{BIDIR}+" (effects (font (size 1.27 1.27))))
          (number "J2" (effects (font (size 1.27 1.27))))
        )
        (pin passive line (at 0 -82.55 0) (length 3.81) hide
          (name "GND" (effects (font (size 1.27 1.27))))
          (number "J20" (effects (font (size 1.27 1.27))))
        )
        (pin passive line (at 30.48 -44.45 180) (length 3.81)
          (name "HA22+" (effects (font (size 1.27 1.27))))
          (number "J21" (effects (font (size 1.27 1.27))))
        )
        (pin passive line (at 30.48 -46.99 180) (length 3.81)
          (name "HA22-" (effects (font (size 1.27 1.27))))
          (number "J22" (effects (font (size 1.27 1.27))))
        )
        (pin passive line (at 0 -82.55 0) (length 3.81) hide
          (name "GND" (effects (font (size 1.27 1.27))))
          (number "J23" (effects (font (size 1.27 1.27))))
        )
        (pin passive line (at 30.48 -50.8 180) (length 3.81)
          (name "HB01+" (effects (font (size 1.27 1.27))))
          (number "J24" (effects (font (size 1.27 1.27))))
        )
        (pin passive line (at 30.48 -53.34 180) (length 3.81)
          (name "HB01-" (effects (font (size 1.27 1.27))))
          (number "J25" (effects (font (size 1.27 1.27))))
        )
        (pin passive line (at 0 -82.55 0) (length 3.81) hide
          (name "GND" (effects (font (size 1.27 1.27))))
          (number "J26" (effects (font (size 1.27 1.27))))
        )
        (pin passive line (at 30.48 -57.15 180) (length 3.81)
          (name "HB07+" (effects (font (size 1.27 1.27))))
          (number "J27" (effects (font (size 1.27 1.27))))
        )
        (pin passive line (at 30.48 -59.69 180) (length 3.81)
          (name "HB07-" (effects (font (size 1.27 1.27))))
          (number "J28" (effects (font (size 1.27 1.27))))
        )
        (pin passive line (at 0 -82.55 0) (length 3.81) hide
          (name "GND" (effects (font (size 1.27 1.27))))
          (number "J29" (effects (font (size 1.27 1.27))))
        )
        (pin passive line (at 30.48 -8.89 180) (length 3.81)
          (name "CLK3_{BIDIR}-" (effects (font (size 1.27 1.27))))
          (number "J3" (effects (font (size 1.27 1.27))))
        )
        (pin passive line (at 30.48 -63.5 180) (length 3.81)
          (name "HB11+" (effects (font (size 1.27 1.27))))
          (number "J30" (effects (font (size 1.27 1.27))))
        )
        (pin passive line (at 30.48 -66.04 180) (length 3.81)
          (name "HB11-" (effects (font (size 1.27 1.27))))
          (number "J31" (effects (font (size 1.27 1.27))))
        )
        (pin passive line (at 0 -82.55 0) (length 3.81) hide
          (name "GND" (effects (font (size 1.27 1.27))))
          (number "J32" (effects (font (size 1.27 1.27))))
        )
        (pin passive line (at 30.48 -69.85 180) (length 3.81)
          (name "HB15+" (effects (font (size 1.27 1.27))))
          (number "J33" (effects (font (size 1.27 1.27))))
        )
        (pin passive line (at 30.48 -72.39 180) (length 3.81)
          (name "HB15-" (effects (font (size 1.27 1.27))))
          (number "J34" (effects (font (size 1.27 1.27))))
        )
        (pin passive line (at 0 -82.55 0) (length 3.81) hide
          (name "GND" (effects (font (size 1.27 1.27))))
          (number "J35" (effects (font (size 1.27 1.27))))
        )
        (pin passive line (at 30.48 -76.2 180) (length 3.81)
          (name "HB18+" (effects (font (size 1.27 1.27))))
          (number "J36" (effects (font (size 1.27 1.27))))
        )
        (pin passive line (at 30.48 -78.74 180) (length 3.81)
          (name "HB18-" (effects (font (size 1.27 1.27))))
          (number "J37" (effects (font (size 1.27 1.27))))
        )
        (pin passive line (at 0 -82.55 0) (length 3.81) hide
          (name "GND" (effects (font (size 1.27 1.27))))
          (number "J38" (effects (font (size 1.27 1.27))))
        )
        (pin passive line (at 30.48 -85.09 180) (length 3.81)
          (name "VIO_{B_M2C}" (effects (font (size 1.27 1.27))))
          (number "J39" (effects (font (size 1.27 1.27))))
        )
        (pin passive line (at 0 -82.55 0) (length 3.81) hide
          (name "GND" (effects (font (size 1.27 1.27))))
          (number "J4" (effects (font (size 1.27 1.27))))
        )
        (pin passive line (at 0 -82.55 0) (length 3.81) hide
          (name "GND" (effects (font (size 1.27 1.27))))
          (number "J40" (effects (font (size 1.27 1.27))))
        )
        (pin passive line (at 0 -82.55 0) (length 3.81) hide
          (name "GND" (effects (font (size 1.27 1.27))))
          (number "J5" (effects (font (size 1.27 1.27))))
        )
        (pin passive line (at 30.48 -12.7 180) (length 3.81)
          (name "HA03+" (effects (font (size 1.27 1.27))))
          (number "J6" (effects (font (size 1.27 1.27))))
        )
        (pin passive line (at 30.48 -15.24 180) (length 3.81)
          (name "HA03-" (effects (font (size 1.27 1.27))))
          (number "J7" (effects (font (size 1.27 1.27))))
        )
        (pin passive line (at 0 -82.55 0) (length 3.81) hide
          (name "GND" (effects (font (size 1.27 1.27))))
          (number "J8" (effects (font (size 1.27 1.27))))
        )
        (pin passive line (at 30.48 -19.05 180) (length 3.81)
          (name "HA07+" (effects (font (size 1.27 1.27))))
          (number "J9" (effects (font (size 1.27 1.27))))
        )
        (pin passive line (at 0 0 0) (length 3.81)
          (name "VREF_{B_M2C}" (effects (font (size 1.27 1.27))))
          (number "K1" (effects (font (size 1.27 1.27))))
        )
        (pin passive line (at 0 -19.05 0) (length 3.81)
          (name "HA06+" (effects (font (size 1.27 1.27))))
          (number "K10" (effects (font (size 1.27 1.27))))
        )
        (pin passive line (at 0 -21.59 0) (length 3.81)
          (name "HA06-" (effects (font (size 1.27 1.27))))
          (number "K11" (effects (font (size 1.27 1.27))))
        )
        (pin passive line (at 0 -82.55 0) (length 3.81) hide
          (name "GND" (effects (font (size 1.27 1.27))))
          (number "K12" (effects (font (size 1.27 1.27))))
        )
        (pin passive line (at 0 -25.4 0) (length 3.81)
          (name "HA10+" (effects (font (size 1.27 1.27))))
          (number "K13" (effects (font (size 1.27 1.27))))
        )
        (pin passive line (at 0 -27.94 0) (length 3.81)
          (name "HA10-" (effects (font (size 1.27 1.27))))
          (number "K14" (effects (font (size 1.27 1.27))))
        )
        (pin passive line (at 0 -82.55 0) (length 3.81) hide
          (name "GND" (effects (font (size 1.27 1.27))))
          (number "K15" (effects (font (size 1.27 1.27))))
        )
        (pin passive line (at 0 -31.75 0) (length 3.81)
          (name "HA17_{CC}+" (effects (font (size 1.27 1.27))))
          (number "K16" (effects (font (size 1.27 1.27))))
        )
        (pin passive line (at 0 -34.29 0) (length 3.81)
          (name "HA17_{CC}-" (effects (font (size 1.27 1.27))))
          (number "K17" (effects (font (size 1.27 1.27))))
        )
        (pin passive line (at 0 -82.55 0) (length 3.81) hide
          (name "GND" (effects (font (size 1.27 1.27))))
          (number "K18" (effects (font (size 1.27 1.27))))
        )
        (pin passive line (at 0 -38.1 0) (length 3.81)
          (name "HA21+" (effects (font (size 1.27 1.27))))
          (number "K19" (effects (font (size 1.27 1.27))))
        )
        (pin passive line (at 0 -82.55 0) (length 3.81) hide
          (name "GND" (effects (font (size 1.27 1.27))))
          (number "K2" (effects (font (size 1.27 1.27))))
        )
        (pin passive line (at 0 -40.64 0) (length 3.81)
          (name "HA21-" (effects (font (size 1.27 1.27))))
          (number "K20" (effects (font (size 1.27 1.27))))
        )
        (pin passive line (at 0 -82.55 0) (length 3.81) hide
          (name "GND" (effects (font (size 1.27 1.27))))
          (number "K21" (effects (font (size 1.27 1.27))))
        )
        (pin passive line (at 0 -44.45 0) (length 3.81)
          (name "HA23+" (effects (font (size 1.27 1.27))))
          (number "K22" (effects (font (size 1.27 1.27))))
        )
        (pin passive line (at 0 -46.99 0) (length 3.81)
          (name "HA23-" (effects (font (size 1.27 1.27))))
          (number "K23" (effects (font (size 1.27 1.27))))
        )
        (pin passive line (at 0 -82.55 0) (length 3.81) hide
          (name "GND" (effects (font (size 1.27 1.27))))
          (number "K24" (effects (font (size 1.27 1.27))))
        )
        (pin passive line (at 0 -50.8 0) (length 3.81)
          (name "HB00_{CC}+" (effects (font (size 1.27 1.27))))
          (number "K25" (effects (font (size 1.27 1.27))))
        )
        (pin passive line (at 0 -53.34 0) (length 3.81)
          (name "HB00_{CC}-" (effects (font (size 1.27 1.27))))
          (number "K26" (effects (font (size 1.27 1.27))))
        )
        (pin passive line (at 0 -82.55 0) (length 3.81) hide
          (name "GND" (effects (font (size 1.27 1.27))))
          (number "K27" (effects (font (size 1.27 1.27))))
        )
        (pin passive line (at 0 -57.15 0) (length 3.81)
          (name "HB06_{CC}+" (effects (font (size 1.27 1.27))))
          (number "K28" (effects (font (size 1.27 1.27))))
        )
        (pin passive line (at 0 -59.69 0) (length 3.81)
          (name "HB06_{CC}-" (effects (font (size 1.27 1.27))))
          (number "K29" (effects (font (size 1.27 1.27))))
        )
        (pin passive line (at 0 -82.55 0) (length 3.81) hide
          (name "GND" (effects (font (size 1.27 1.27))))
          (number "K3" (effects (font (size 1.27 1.27))))
        )
        (pin passive line (at 0 -82.55 0) (length 3.81) hide
          (name "GND" (effects (font (size 1.27 1.27))))
          (number "K30" (effects (font (size 1.27 1.27))))
        )
        (pin passive line (at 0 -63.5 0) (length 3.81)
          (name "HB10+" (effects (font (size 1.27 1.27))))
          (number "K31" (effects (font (size 1.27 1.27))))
        )
        (pin passive line (at 0 -66.04 0) (length 3.81)
          (name "HB10-" (effects (font (size 1.27 1.27))))
          (number "K32" (effects (font (size 1.27 1.27))))
        )
        (pin passive line (at 0 -82.55 0) (length 3.81) hide
          (name "GND" (effects (font (size 1.27 1.27))))
          (number "K33" (effects (font (size 1.27 1.27))))
        )
        (pin passive line (at 0 -69.85 0) (length 3.81)
          (name "HB14+" (effects (font (size 1.27 1.27))))
          (number "K34" (effects (font (size 1.27 1.27))))
        )
        (pin passive line (at 0 -72.39 0) (length 3.81)
          (name "HB14-" (effects (font (size 1.27 1.27))))
          (number "K35" (effects (font (size 1.27 1.27))))
        )
        (pin passive line (at 0 -82.55 0) (length 3.81) hide
          (name "GND" (effects (font (size 1.27 1.27))))
          (number "K36" (effects (font (size 1.27 1.27))))
        )
        (pin passive line (at 0 -76.2 0) (length 3.81)
          (name "HB17_{CC}+" (effects (font (size 1.27 1.27))))
          (number "K37" (effects (font (size 1.27 1.27))))
        )
        (pin passive line (at 0 -78.74 0) (length 3.81)
          (name "HB17_{CC}-" (effects (font (size 1.27 1.27))))
          (number "K38" (effects (font (size 1.27 1.27))))
        )
        (pin passive line (at 0 -82.55 0) (length 3.81) hide
          (name "GND" (effects (font (size 1.27 1.27))))
          (number "K39" (effects (font (size 1.27 1.27))))
        )
        (pin passive line (at 0 -6.35 0) (length 3.81)
          (name "CLK2_{BIDIR}+" (effects (font (size 1.27 1.27))))
          (number "K4" (effects (font (size 1.27 1.27))))
        )
        (pin passive line (at 30.48 -82.55 180) (length 3.81)
          (name "VIO_{B_M2C}" (effects (font (size 1.27 1.27))))
          (number "K40" (effects (font (size 1.27 1.27))))
        )
        (pin passive line (at 0 -8.89 0) (length 3.81)
          (name "CLK2_{BIDIR}-" (effects (font (size 1.27 1.27))))
          (number "K5" (effects (font (size 1.27 1.27))))
        )
        (pin passive line (at 0 -82.55 0) (length 3.81) hide
          (name "GND" (effects (font (size 1.27 1.27))))
          (number "K6" (effects (font (size 1.27 1.27))))
        )
        (pin passive line (at 0 -12.7 0) (length 3.81)
          (name "HA02+" (effects (font (size 1.27 1.27))))
          (number "K7" (effects (font (size 1.27 1.27))))
        )
        (pin passive line (at 0 -15.24 0) (length 3.81)
          (name "HA02-" (effects (font (size 1.27 1.27))))
          (number "K8" (effects (font (size 1.27 1.27))))
        )
        (pin passive line (at 0 -82.55 0) (length 3.81) hide
          (name "GND" (effects (font (size 1.27 1.27))))
          (number "K9" (effects (font (size 1.27 1.27))))
        )
      )
      (symbol "ASP-134486-01_2_1"
        (rectangle (start 3.81 2.54) (end 26.67 -87.63)
          (stroke (width 0.254) (type default))
          (fill (type background))
        )
        (pin passive line (at 0 -82.55 0) (length 3.81)
          (name "GND" (effects (font (size 1.27 1.27))))
          (number "G1" (effects (font (size 1.27 1.27))))
        )
        (pin passive line (at 30.48 -21.59 180) (length 3.81)
          (name "LA03-" (effects (font (size 1.27 1.27))))
          (number "G10" (effects (font (size 1.27 1.27))))
        )
        (pin passive line (at 0 -82.55 0) (length 3.81) hide
          (name "GND" (effects (font (size 1.27 1.27))))
          (number "G11" (effects (font (size 1.27 1.27))))
        )
        (pin passive line (at 30.48 -25.4 180) (length 3.81)
          (name "LA08+" (effects (font (size 1.27 1.27))))
          (number "G12" (effects (font (size 1.27 1.27))))
        )
        (pin passive line (at 30.48 -27.94 180) (length 3.81)
          (name "LA08-" (effects (font (size 1.27 1.27))))
          (number "G13" (effects (font (size 1.27 1.27))))
        )
        (pin passive line (at 0 -82.55 0) (length 3.81) hide
          (name "GND" (effects (font (size 1.27 1.27))))
          (number "G14" (effects (font (size 1.27 1.27))))
        )
        (pin passive line (at 30.48 -31.75 180) (length 3.81)
          (name "LA12+" (effects (font (size 1.27 1.27))))
          (number "G15" (effects (font (size 1.27 1.27))))
        )
        (pin passive line (at 30.48 -34.29 180) (length 3.81)
          (name "LA12-" (effects (font (size 1.27 1.27))))
          (number "G16" (effects (font (size 1.27 1.27))))
        )
        (pin passive line (at 0 -82.55 0) (length 3.81) hide
          (name "GND" (effects (font (size 1.27 1.27))))
          (number "G17" (effects (font (size 1.27 1.27))))
        )
        (pin passive line (at 30.48 -38.1 180) (length 3.81)
          (name "LA16+" (effects (font (size 1.27 1.27))))
          (number "G18" (effects (font (size 1.27 1.27))))
        )
        (pin passive line (at 30.48 -40.64 180) (length 3.81)
          (name "LA16-" (effects (font (size 1.27 1.27))))
          (number "G19" (effects (font (size 1.27 1.27))))
        )
        (pin passive line (at 30.48 -6.35 180) (length 3.81)
          (name "CLK1_{M2C}+" (effects (font (size 1.27 1.27))))
          (number "G2" (effects (font (size 1.27 1.27))))
        )
        (pin passive line (at 0 -82.55 0) (length 3.81) hide
          (name "GND" (effects (font (size 1.27 1.27))))
          (number "G20" (effects (font (size 1.27 1.27))))
        )
        (pin passive line (at 30.48 -44.45 180) (length 3.81)
          (name "LA20+" (effects (font (size 1.27 1.27))))
          (number "G21" (effects (font (size 1.27 1.27))))
        )
        (pin passive line (at 30.48 -46.99 180) (length 3.81)
          (name "LA20-" (effects (font (size 1.27 1.27))))
          (number "G22" (effects (font (size 1.27 1.27))))
        )
        (pin passive line (at 0 -82.55 0) (length 3.81) hide
          (name "GND" (effects (font (size 1.27 1.27))))
          (number "G23" (effects (font (size 1.27 1.27))))
        )
        (pin passive line (at 30.48 -50.8 180) (length 3.81)
          (name "LA22+" (effects (font (size 1.27 1.27))))
          (number "G24" (effects (font (size 1.27 1.27))))
        )
        (pin passive line (at 30.48 -53.34 180) (length 3.81)
          (name "LA22-" (effects (font (size 1.27 1.27))))
          (number "G25" (effects (font (size 1.27 1.27))))
        )
        (pin passive line (at 0 -82.55 0) (length 3.81) hide
          (name "GND" (effects (font (size 1.27 1.27))))
          (number "G26" (effects (font (size 1.27 1.27))))
        )
        (pin passive line (at 30.48 -57.15 180) (length 3.81)
          (name "LA25+" (effects (font (size 1.27 1.27))))
          (number "G27" (effects (font (size 1.27 1.27))))
        )
        (pin passive line (at 30.48 -59.69 180) (length 3.81)
          (name "LA25-" (effects (font (size 1.27 1.27))))
          (number "G28" (effects (font (size 1.27 1.27))))
        )
        (pin passive line (at 0 -82.55 0) (length 3.81) hide
          (name "GND" (effects (font (size 1.27 1.27))))
          (number "G29" (effects (font (size 1.27 1.27))))
        )
        (pin passive line (at 30.48 -8.89 180) (length 3.81)
          (name "CLK1_{M2C}-" (effects (font (size 1.27 1.27))))
          (number "G3" (effects (font (size 1.27 1.27))))
        )
        (pin passive line (at 30.48 -63.5 180) (length 3.81)
          (name "LA29+" (effects (font (size 1.27 1.27))))
          (number "G30" (effects (font (size 1.27 1.27))))
        )
        (pin passive line (at 30.48 -66.04 180) (length 3.81)
          (name "LA29-" (effects (font (size 1.27 1.27))))
          (number "G31" (effects (font (size 1.27 1.27))))
        )
        (pin passive line (at 0 -82.55 0) (length 3.81) hide
          (name "GND" (effects (font (size 1.27 1.27))))
          (number "G32" (effects (font (size 1.27 1.27))))
        )
        (pin passive line (at 30.48 -69.85 180) (length 3.81)
          (name "LA31+" (effects (font (size 1.27 1.27))))
          (number "G33" (effects (font (size 1.27 1.27))))
        )
        (pin passive line (at 30.48 -72.39 180) (length 3.81)
          (name "LA31-" (effects (font (size 1.27 1.27))))
          (number "G34" (effects (font (size 1.27 1.27))))
        )
        (pin passive line (at 0 -82.55 0) (length 3.81) hide
          (name "GND" (effects (font (size 1.27 1.27))))
          (number "G35" (effects (font (size 1.27 1.27))))
        )
        (pin passive line (at 30.48 -76.2 180) (length 3.81)
          (name "LA33+" (effects (font (size 1.27 1.27))))
          (number "G36" (effects (font (size 1.27 1.27))))
        )
        (pin passive line (at 30.48 -78.74 180) (length 3.81)
          (name "LA33-" (effects (font (size 1.27 1.27))))
          (number "G37" (effects (font (size 1.27 1.27))))
        )
        (pin passive line (at 0 -82.55 0) (length 3.81) hide
          (name "GND" (effects (font (size 1.27 1.27))))
          (number "G38" (effects (font (size 1.27 1.27))))
        )
        (pin passive line (at 30.48 -82.55 180) (length 3.81)
          (name "VADJ" (effects (font (size 1.27 1.27))))
          (number "G39" (effects (font (size 1.27 1.27))))
        )
        (pin passive line (at 0 -82.55 0) (length 3.81) hide
          (name "GND" (effects (font (size 1.27 1.27))))
          (number "G4" (effects (font (size 1.27 1.27))))
        )
        (pin passive line (at 0 -82.55 0) (length 3.81) hide
          (name "GND" (effects (font (size 1.27 1.27))))
          (number "G40" (effects (font (size 1.27 1.27))))
        )
        (pin passive line (at 0 -82.55 0) (length 3.81) hide
          (name "GND" (effects (font (size 1.27 1.27))))
          (number "G5" (effects (font (size 1.27 1.27))))
        )
        (pin passive line (at 30.48 -12.7 180) (length 3.81)
          (name "LA00_{CC}+" (effects (font (size 1.27 1.27))))
          (number "G6" (effects (font (size 1.27 1.27))))
        )
        (pin passive line (at 30.48 -15.24 180) (length 3.81)
          (name "LA00_{CC}-" (effects (font (size 1.27 1.27))))
          (number "G7" (effects (font (size 1.27 1.27))))
        )
        (pin passive line (at 0 -82.55 0) (length 3.81) hide
          (name "GND" (effects (font (size 1.27 1.27))))
          (number "G8" (effects (font (size 1.27 1.27))))
        )
        (pin passive line (at 30.48 -19.05 180) (length 3.81)
          (name "LA03+" (effects (font (size 1.27 1.27))))
          (number "G9" (effects (font (size 1.27 1.27))))
        )
        (pin passive line (at 0 0 0) (length 3.81)
          (name "VREF_{A_M2C}" (effects (font (size 1.27 1.27))))
          (number "H1" (effects (font (size 1.27 1.27))))
        )
        (pin passive line (at 0 -19.05 0) (length 3.81)
          (name "LA04+" (effects (font (size 1.27 1.27))))
          (number "H10" (effects (font (size 1.27 1.27))))
        )
        (pin passive line (at 0 -21.59 0) (length 3.81)
          (name "LA04-" (effects (font (size 1.27 1.27))))
          (number "H11" (effects (font (size 1.27 1.27))))
        )
        (pin passive line (at 0 -82.55 0) (length 3.81) hide
          (name "GND" (effects (font (size 1.27 1.27))))
          (number "H12" (effects (font (size 1.27 1.27))))
        )
        (pin passive line (at 0 -25.4 0) (length 3.81)
          (name "LA07+" (effects (font (size 1.27 1.27))))
          (number "H13" (effects (font (size 1.27 1.27))))
        )
        (pin passive line (at 0 -27.94 0) (length 3.81)
          (name "LA07-" (effects (font (size 1.27 1.27))))
          (number "H14" (effects (font (size 1.27 1.27))))
        )
        (pin passive line (at 0 -82.55 0) (length 3.81) hide
          (name "GND" (effects (font (size 1.27 1.27))))
          (number "H15" (effects (font (size 1.27 1.27))))
        )
        (pin passive line (at 0 -31.75 0) (length 3.81)
          (name "LA11+" (effects (font (size 1.27 1.27))))
          (number "H16" (effects (font (size 1.27 1.27))))
        )
        (pin passive line (at 0 -34.29 0) (length 3.81)
          (name "LA11-" (effects (font (size 1.27 1.27))))
          (number "H17" (effects (font (size 1.27 1.27))))
        )
        (pin passive line (at 0 -82.55 0) (length 3.81) hide
          (name "GND" (effects (font (size 1.27 1.27))))
          (number "H18" (effects (font (size 1.27 1.27))))
        )
        (pin passive line (at 0 -38.1 0) (length 3.81)
          (name "LA15+" (effects (font (size 1.27 1.27))))
          (number "H19" (effects (font (size 1.27 1.27))))
        )
        (pin passive line (at 0 -2.54 0) (length 3.81)
          (name "~{PRSNT_{M2C}}" (effects (font (size 1.27 1.27))))
          (number "H2" (effects (font (size 1.27 1.27))))
        )
        (pin passive line (at 0 -40.64 0) (length 3.81)
          (name "LA15-" (effects (font (size 1.27 1.27))))
          (number "H20" (effects (font (size 1.27 1.27))))
        )
        (pin passive line (at 0 -82.55 0) (length 3.81) hide
          (name "GND" (effects (font (size 1.27 1.27))))
          (number "H21" (effects (font (size 1.27 1.27))))
        )
        (pin passive line (at 0 -44.45 0) (length 3.81)
          (name "LA19+" (effects (font (size 1.27 1.27))))
          (number "H22" (effects (font (size 1.27 1.27))))
        )
        (pin passive line (at 0 -46.99 0) (length 3.81)
          (name "LA19-" (effects (font (size 1.27 1.27))))
          (number "H23" (effects (font (size 1.27 1.27))))
        )
        (pin passive line (at 0 -82.55 0) (length 3.81) hide
          (name "GND" (effects (font (size 1.27 1.27))))
          (number "H24" (effects (font (size 1.27 1.27))))
        )
        (pin passive line (at 0 -50.8 0) (length 3.81)
          (name "LA21+" (effects (font (size 1.27 1.27))))
          (number "H25" (effects (font (size 1.27 1.27))))
        )
        (pin passive line (at 0 -53.34 0) (length 3.81)
          (name "LA21-" (effects (font (size 1.27 1.27))))
          (number "H26" (effects (font (size 1.27 1.27))))
        )
        (pin passive line (at 0 -82.55 0) (length 3.81) hide
          (name "GND" (effects (font (size 1.27 1.27))))
          (number "H27" (effects (font (size 1.27 1.27))))
        )
        (pin passive line (at 0 -57.15 0) (length 3.81)
          (name "LA24+" (effects (font (size 1.27 1.27))))
          (number "H28" (effects (font (size 1.27 1.27))))
        )
        (pin passive line (at 0 -59.69 0) (length 3.81)
          (name "LA24-" (effects (font (size 1.27 1.27))))
          (number "H29" (effects (font (size 1.27 1.27))))
        )
        (pin passive line (at 0 -82.55 0) (length 3.81) hide
          (name "GND" (effects (font (size 1.27 1.27))))
          (number "H3" (effects (font (size 1.27 1.27))))
        )
        (pin passive line (at 0 -82.55 0) (length 3.81) hide
          (name "GND" (effects (font (size 1.27 1.27))))
          (number "H30" (effects (font (size 1.27 1.27))))
        )
        (pin passive line (at 0 -63.5 0) (length 3.81)
          (name "LA28+" (effects (font (size 1.27 1.27))))
          (number "H31" (effects (font (size 1.27 1.27))))
        )
        (pin passive line (at 0 -66.04 0) (length 3.81)
          (name "LA28-" (effects (font (size 1.27 1.27))))
          (number "H32" (effects (font (size 1.27 1.27))))
        )
        (pin passive line (at 0 -82.55 0) (length 3.81) hide
          (name "GND" (effects (font (size 1.27 1.27))))
          (number "H33" (effects (font (size 1.27 1.27))))
        )
        (pin passive line (at 0 -69.85 0) (length 3.81)
          (name "LA30+" (effects (font (size 1.27 1.27))))
          (number "H34" (effects (font (size 1.27 1.27))))
        )
        (pin passive line (at 0 -72.39 0) (length 3.81)
          (name "LA30-" (effects (font (size 1.27 1.27))))
          (number "H35" (effects (font (size 1.27 1.27))))
        )
        (pin passive line (at 0 -82.55 0) (length 3.81) hide
          (name "GND" (effects (font (size 1.27 1.27))))
          (number "H36" (effects (font (size 1.27 1.27))))
        )
        (pin passive line (at 0 -76.2 0) (length 3.81)
          (name "LA32+" (effects (font (size 1.27 1.27))))
          (number "H37" (effects (font (size 1.27 1.27))))
        )
        (pin passive line (at 0 -78.74 0) (length 3.81)
          (name "LA32-" (effects (font (size 1.27 1.27))))
          (number "H38" (effects (font (size 1.27 1.27))))
        )
        (pin passive line (at 0 -82.55 0) (length 3.81) hide
          (name "GND" (effects (font (size 1.27 1.27))))
          (number "H39" (effects (font (size 1.27 1.27))))
        )
        (pin passive line (at 0 -6.35 0) (length 3.81)
          (name "CLK0_{M2C}+" (effects (font (size 1.27 1.27))))
          (number "H4" (effects (font (size 1.27 1.27))))
        )
        (pin passive line (at 30.48 -85.09 180) (length 3.81)
          (name "VADJ" (effects (font (size 1.27 1.27))))
          (number "H40" (effects (font (size 1.27 1.27))))
        )
        (pin passive line (at 0 -8.89 0) (length 3.81)
          (name "CLK0_{M2C}-" (effects (font (size 1.27 1.27))))
          (number "H5" (effects (font (size 1.27 1.27))))
        )
        (pin passive line (at 0 -82.55 0) (length 3.81) hide
          (name "GND" (effects (font (size 1.27 1.27))))
          (number "H6" (effects (font (size 1.27 1.27))))
        )
        (pin passive line (at 0 -12.7 0) (length 3.81)
          (name "LA02+" (effects (font (size 1.27 1.27))))
          (number "H7" (effects (font (size 1.27 1.27))))
        )
        (pin passive line (at 0 -15.24 0) (length 3.81)
          (name "LA02-" (effects (font (size 1.27 1.27))))
          (number "H8" (effects (font (size 1.27 1.27))))
        )
        (pin passive line (at 0 -82.55 0) (length 3.81) hide
          (name "GND" (effects (font (size 1.27 1.27))))
          (number "H9" (effects (font (size 1.27 1.27))))
        )
      )
      (symbol "ASP-134486-01_3_1"
        (rectangle (start 3.81 2.54) (end 26.67 -87.63)
          (stroke (width 0.254) (type default))
          (fill (type background))
        )
        (pin passive line (at 0 -82.55 0) (length 3.81)
          (name "GND" (effects (font (size 1.27 1.27))))
          (number "E1" (effects (font (size 1.27 1.27))))
        )
        (pin passive line (at 30.48 -21.59 180) (length 3.81)
          (name "HA09-" (effects (font (size 1.27 1.27))))
          (number "E10" (effects (font (size 1.27 1.27))))
        )
        (pin passive line (at 0 -82.55 0) (length 3.81) hide
          (name "GND" (effects (font (size 1.27 1.27))))
          (number "E11" (effects (font (size 1.27 1.27))))
        )
        (pin passive line (at 30.48 -25.4 180) (length 3.81)
          (name "HA13+" (effects (font (size 1.27 1.27))))
          (number "E12" (effects (font (size 1.27 1.27))))
        )
        (pin passive line (at 30.48 -27.94 180) (length 3.81)
          (name "HA13-" (effects (font (size 1.27 1.27))))
          (number "E13" (effects (font (size 1.27 1.27))))
        )
        (pin passive line (at 0 -82.55 0) (length 3.81) hide
          (name "GND" (effects (font (size 1.27 1.27))))
          (number "E14" (effects (font (size 1.27 1.27))))
        )
        (pin passive line (at 30.48 -31.75 180) (length 3.81)
          (name "HA16+" (effects (font (size 1.27 1.27))))
          (number "E15" (effects (font (size 1.27 1.27))))
        )
        (pin passive line (at 30.48 -34.29 180) (length 3.81)
          (name "HA16-" (effects (font (size 1.27 1.27))))
          (number "E16" (effects (font (size 1.27 1.27))))
        )
        (pin passive line (at 0 -82.55 0) (length 3.81) hide
          (name "GND" (effects (font (size 1.27 1.27))))
          (number "E17" (effects (font (size 1.27 1.27))))
        )
        (pin passive line (at 30.48 -38.1 180) (length 3.81)
          (name "HA20+" (effects (font (size 1.27 1.27))))
          (number "E18" (effects (font (size 1.27 1.27))))
        )
        (pin passive line (at 30.48 -40.64 180) (length 3.81)
          (name "HA20-" (effects (font (size 1.27 1.27))))
          (number "E19" (effects (font (size 1.27 1.27))))
        )
        (pin passive line (at 30.48 -6.35 180) (length 3.81)
          (name "HA01_{CC}+" (effects (font (size 1.27 1.27))))
          (number "E2" (effects (font (size 1.27 1.27))))
        )
        (pin passive line (at 0 -82.55 0) (length 3.81) hide
          (name "GND" (effects (font (size 1.27 1.27))))
          (number "E20" (effects (font (size 1.27 1.27))))
        )
        (pin passive line (at 30.48 -44.45 180) (length 3.81)
          (name "HB03+" (effects (font (size 1.27 1.27))))
          (number "E21" (effects (font (size 1.27 1.27))))
        )
        (pin passive line (at 30.48 -46.99 180) (length 3.81)
          (name "HB03-" (effects (font (size 1.27 1.27))))
          (number "E22" (effects (font (size 1.27 1.27))))
        )
        (pin passive line (at 0 -82.55 0) (length 3.81) hide
          (name "GND" (effects (font (size 1.27 1.27))))
          (number "E23" (effects (font (size 1.27 1.27))))
        )
        (pin passive line (at 30.48 -50.8 180) (length 3.81)
          (name "HB05+" (effects (font (size 1.27 1.27))))
          (number "E24" (effects (font (size 1.27 1.27))))
        )
        (pin passive line (at 30.48 -53.34 180) (length 3.81)
          (name "HB05-" (effects (font (size 1.27 1.27))))
          (number "E25" (effects (font (size 1.27 1.27))))
        )
        (pin passive line (at 0 -82.55 0) (length 3.81) hide
          (name "GND" (effects (font (size 1.27 1.27))))
          (number "E26" (effects (font (size 1.27 1.27))))
        )
        (pin passive line (at 30.48 -57.15 180) (length 3.81)
          (name "HB09+" (effects (font (size 1.27 1.27))))
          (number "E27" (effects (font (size 1.27 1.27))))
        )
        (pin passive line (at 30.48 -59.69 180) (length 3.81)
          (name "HB09-" (effects (font (size 1.27 1.27))))
          (number "E28" (effects (font (size 1.27 1.27))))
        )
        (pin passive line (at 0 -82.55 0) (length 3.81) hide
          (name "GND" (effects (font (size 1.27 1.27))))
          (number "E29" (effects (font (size 1.27 1.27))))
        )
        (pin passive line (at 30.48 -8.89 180) (length 3.81)
          (name "HA01_{CC}-" (effects (font (size 1.27 1.27))))
          (number "E3" (effects (font (size 1.27 1.27))))
        )
        (pin passive line (at 30.48 -63.5 180) (length 3.81)
          (name "HB13+" (effects (font (size 1.27 1.27))))
          (number "E30" (effects (font (size 1.27 1.27))))
        )
        (pin passive line (at 30.48 -66.04 180) (length 3.81)
          (name "HB13-" (effects (font (size 1.27 1.27))))
          (number "E31" (effects (font (size 1.27 1.27))))
        )
        (pin passive line (at 0 -82.55 0) (length 3.81) hide
          (name "GND" (effects (font (size 1.27 1.27))))
          (number "E32" (effects (font (size 1.27 1.27))))
        )
        (pin passive line (at 30.48 -69.85 180) (length 3.81)
          (name "HB19+" (effects (font (size 1.27 1.27))))
          (number "E33" (effects (font (size 1.27 1.27))))
        )
        (pin passive line (at 30.48 -72.39 180) (length 3.81)
          (name "HB19-" (effects (font (size 1.27 1.27))))
          (number "E34" (effects (font (size 1.27 1.27))))
        )
        (pin passive line (at 0 -82.55 0) (length 3.81) hide
          (name "GND" (effects (font (size 1.27 1.27))))
          (number "E35" (effects (font (size 1.27 1.27))))
        )
        (pin passive line (at 30.48 -76.2 180) (length 3.81)
          (name "HB21+" (effects (font (size 1.27 1.27))))
          (number "E36" (effects (font (size 1.27 1.27))))
        )
        (pin passive line (at 30.48 -78.74 180) (length 3.81)
          (name "HB21-" (effects (font (size 1.27 1.27))))
          (number "E37" (effects (font (size 1.27 1.27))))
        )
        (pin passive line (at 0 -82.55 0) (length 3.81) hide
          (name "GND" (effects (font (size 1.27 1.27))))
          (number "E38" (effects (font (size 1.27 1.27))))
        )
        (pin passive line (at 30.48 -82.55 180) (length 3.81)
          (name "VADJ" (effects (font (size 1.27 1.27))))
          (number "E39" (effects (font (size 1.27 1.27))))
        )
        (pin passive line (at 0 -82.55 0) (length 3.81) hide
          (name "GND" (effects (font (size 1.27 1.27))))
          (number "E4" (effects (font (size 1.27 1.27))))
        )
        (pin passive line (at 0 -82.55 0) (length 3.81) hide
          (name "GND" (effects (font (size 1.27 1.27))))
          (number "E40" (effects (font (size 1.27 1.27))))
        )
        (pin passive line (at 0 -82.55 0) (length 3.81) hide
          (name "GND" (effects (font (size 1.27 1.27))))
          (number "E5" (effects (font (size 1.27 1.27))))
        )
        (pin passive line (at 30.48 -12.7 180) (length 3.81)
          (name "HA05+" (effects (font (size 1.27 1.27))))
          (number "E6" (effects (font (size 1.27 1.27))))
        )
        (pin passive line (at 30.48 -15.24 180) (length 3.81)
          (name "HA05-" (effects (font (size 1.27 1.27))))
          (number "E7" (effects (font (size 1.27 1.27))))
        )
        (pin passive line (at 0 -82.55 0) (length 3.81) hide
          (name "GND" (effects (font (size 1.27 1.27))))
          (number "E8" (effects (font (size 1.27 1.27))))
        )
        (pin passive line (at 30.48 -19.05 180) (length 3.81)
          (name "HA09+" (effects (font (size 1.27 1.27))))
          (number "E9" (effects (font (size 1.27 1.27))))
        )
        (pin passive line (at 0 0 0) (length 3.81)
          (name "PG_{M2C}" (effects (font (size 1.27 1.27))))
          (number "F1" (effects (font (size 1.27 1.27))))
        )
        (pin passive line (at 0 -19.05 0) (length 3.81)
          (name "HA08+" (effects (font (size 1.27 1.27))))
          (number "F10" (effects (font (size 1.27 1.27))))
        )
        (pin passive line (at 0 -21.59 0) (length 3.81)
          (name "HA08-" (effects (font (size 1.27 1.27))))
          (number "F11" (effects (font (size 1.27 1.27))))
        )
        (pin passive line (at 0 -82.55 0) (length 3.81) hide
          (name "GND" (effects (font (size 1.27 1.27))))
          (number "F12" (effects (font (size 1.27 1.27))))
        )
        (pin passive line (at 0 -25.4 0) (length 3.81)
          (name "HA12+" (effects (font (size 1.27 1.27))))
          (number "F13" (effects (font (size 1.27 1.27))))
        )
        (pin passive line (at 0 -27.94 0) (length 3.81)
          (name "HA12-" (effects (font (size 1.27 1.27))))
          (number "F14" (effects (font (size 1.27 1.27))))
        )
        (pin passive line (at 0 -82.55 0) (length 3.81) hide
          (name "GND" (effects (font (size 1.27 1.27))))
          (number "F15" (effects (font (size 1.27 1.27))))
        )
        (pin passive line (at 0 -31.75 0) (length 3.81)
          (name "HA15+" (effects (font (size 1.27 1.27))))
          (number "F16" (effects (font (size 1.27 1.27))))
        )
        (pin passive line (at 0 -34.29 0) (length 3.81)
          (name "HA15-" (effects (font (size 1.27 1.27))))
          (number "F17" (effects (font (size 1.27 1.27))))
        )
        (pin passive line (at 0 -82.55 0) (length 3.81) hide
          (name "GND" (effects (font (size 1.27 1.27))))
          (number "F18" (effects (font (size 1.27 1.27))))
        )
        (pin passive line (at 0 -38.1 0) (length 3.81)
          (name "HA19+" (effects (font (size 1.27 1.27))))
          (number "F19" (effects (font (size 1.27 1.27))))
        )
        (pin passive line (at 0 -82.55 0) (length 3.81) hide
          (name "GND" (effects (font (size 1.27 1.27))))
          (number "F2" (effects (font (size 1.27 1.27))))
        )
        (pin passive line (at 0 -40.64 0) (length 3.81)
          (name "HA19-" (effects (font (size 1.27 1.27))))
          (number "F20" (effects (font (size 1.27 1.27))))
        )
        (pin passive line (at 0 -82.55 0) (length 3.81) hide
          (name "GND" (effects (font (size 1.27 1.27))))
          (number "F21" (effects (font (size 1.27 1.27))))
        )
        (pin passive line (at 0 -44.45 0) (length 3.81)
          (name "HB02+" (effects (font (size 1.27 1.27))))
          (number "F22" (effects (font (size 1.27 1.27))))
        )
        (pin passive line (at 0 -46.99 0) (length 3.81)
          (name "HB02-" (effects (font (size 1.27 1.27))))
          (number "F23" (effects (font (size 1.27 1.27))))
        )
        (pin passive line (at 0 -82.55 0) (length 3.81) hide
          (name "GND" (effects (font (size 1.27 1.27))))
          (number "F24" (effects (font (size 1.27 1.27))))
        )
        (pin passive line (at 0 -50.8 0) (length 3.81)
          (name "HB04+" (effects (font (size 1.27 1.27))))
          (number "F25" (effects (font (size 1.27 1.27))))
        )
        (pin passive line (at 0 -53.34 0) (length 3.81)
          (name "HB04-" (effects (font (size 1.27 1.27))))
          (number "F26" (effects (font (size 1.27 1.27))))
        )
        (pin passive line (at 0 -82.55 0) (length 3.81) hide
          (name "GND" (effects (font (size 1.27 1.27))))
          (number "F27" (effects (font (size 1.27 1.27))))
        )
        (pin passive line (at 0 -57.15 0) (length 3.81)
          (name "HB08+" (effects (font (size 1.27 1.27))))
          (number "F28" (effects (font (size 1.27 1.27))))
        )
        (pin passive line (at 0 -59.69 0) (length 3.81)
          (name "HB08-" (effects (font (size 1.27 1.27))))
          (number "F29" (effects (font (size 1.27 1.27))))
        )
        (pin passive line (at 0 -82.55 0) (length 3.81) hide
          (name "GND" (effects (font (size 1.27 1.27))))
          (number "F3" (effects (font (size 1.27 1.27))))
        )
        (pin passive line (at 0 -82.55 0) (length 3.81) hide
          (name "GND" (effects (font (size 1.27 1.27))))
          (number "F30" (effects (font (size 1.27 1.27))))
        )
        (pin passive line (at 0 -63.5 0) (length 3.81)
          (name "HB12+" (effects (font (size 1.27 1.27))))
          (number "F31" (effects (font (size 1.27 1.27))))
        )
        (pin passive line (at 0 -66.04 0) (length 3.81)
          (name "HB12-" (effects (font (size 1.27 1.27))))
          (number "F32" (effects (font (size 1.27 1.27))))
        )
        (pin passive line (at 0 -82.55 0) (length 3.81) hide
          (name "GND" (effects (font (size 1.27 1.27))))
          (number "F33" (effects (font (size 1.27 1.27))))
        )
        (pin passive line (at 0 -69.85 0) (length 3.81)
          (name "HB16+" (effects (font (size 1.27 1.27))))
          (number "F34" (effects (font (size 1.27 1.27))))
        )
        (pin passive line (at 0 -72.39 0) (length 3.81)
          (name "HB16-" (effects (font (size 1.27 1.27))))
          (number "F35" (effects (font (size 1.27 1.27))))
        )
        (pin passive line (at 0 -82.55 0) (length 3.81) hide
          (name "GND" (effects (font (size 1.27 1.27))))
          (number "F36" (effects (font (size 1.27 1.27))))
        )
        (pin passive line (at 0 -76.2 0) (length 3.81)
          (name "HB20+" (effects (font (size 1.27 1.27))))
          (number "F37" (effects (font (size 1.27 1.27))))
        )
        (pin passive line (at 0 -78.74 0) (length 3.81)
          (name "HB20-" (effects (font (size 1.27 1.27))))
          (number "F38" (effects (font (size 1.27 1.27))))
        )
        (pin passive line (at 0 -82.55 0) (length 3.81) hide
          (name "GND" (effects (font (size 1.27 1.27))))
          (number "F39" (effects (font (size 1.27 1.27))))
        )
        (pin passive line (at 0 -6.35 0) (length 3.81)
          (name "HA00_{CC}+" (effects (font (size 1.27 1.27))))
          (number "F4" (effects (font (size 1.27 1.27))))
        )
        (pin passive line (at 30.48 -85.09 180) (length 3.81)
          (name "VADJ" (effects (font (size 1.27 1.27))))
          (number "F40" (effects (font (size 1.27 1.27))))
        )
        (pin passive line (at 0 -8.89 0) (length 3.81)
          (name "HA00_{CC}-" (effects (font (size 1.27 1.27))))
          (number "F5" (effects (font (size 1.27 1.27))))
        )
        (pin passive line (at 0 -82.55 0) (length 3.81) hide
          (name "GND" (effects (font (size 1.27 1.27))))
          (number "F6" (effects (font (size 1.27 1.27))))
        )
        (pin passive line (at 0 -12.7 0) (length 3.81)
          (name "HA04+" (effects (font (size 1.27 1.27))))
          (number "F7" (effects (font (size 1.27 1.27))))
        )
        (pin passive line (at 0 -15.24 0) (length 3.81)
          (name "HA04-" (effects (font (size 1.27 1.27))))
          (number "F8" (effects (font (size 1.27 1.27))))
        )
        (pin passive line (at 0 -82.55 0) (length 3.81) hide
          (name "GND" (effects (font (size 1.27 1.27))))
          (number "F9" (effects (font (size 1.27 1.27))))
        )
      )
      (symbol "ASP-134486-01_4_1"
        (rectangle (start 3.81 2.54) (end 26.67 -85.09)
          (stroke (width 0.254) (type default))
          (fill (type background))
        )
        (pin passive line (at 0 -82.55 0) (length 3.81)
          (name "GND" (effects (font (size 1.27 1.27))))
          (number "C1" (effects (font (size 1.27 1.27))))
        )
        (pin passive line (at 30.48 -19.05 180) (length 3.81)
          (name "LA06+" (effects (font (size 1.27 1.27))))
          (number "C10" (effects (font (size 1.27 1.27))))
        )
        (pin passive line (at 30.48 -21.59 180) (length 3.81)
          (name "LA06-" (effects (font (size 1.27 1.27))))
          (number "C11" (effects (font (size 1.27 1.27))))
        )
        (pin passive line (at 0 -82.55 0) (length 3.81) hide
          (name "GND" (effects (font (size 1.27 1.27))))
          (number "C12" (effects (font (size 1.27 1.27))))
        )
        (pin passive line (at 0 -82.55 0) (length 3.81) hide
          (name "GND" (effects (font (size 1.27 1.27))))
          (number "C13" (effects (font (size 1.27 1.27))))
        )
        (pin passive line (at 30.48 -25.4 180) (length 3.81)
          (name "LA10+" (effects (font (size 1.27 1.27))))
          (number "C14" (effects (font (size 1.27 1.27))))
        )
        (pin passive line (at 30.48 -27.94 180) (length 3.81)
          (name "LA10-" (effects (font (size 1.27 1.27))))
          (number "C15" (effects (font (size 1.27 1.27))))
        )
        (pin passive line (at 0 -82.55 0) (length 3.81) hide
          (name "GND" (effects (font (size 1.27 1.27))))
          (number "C16" (effects (font (size 1.27 1.27))))
        )
        (pin passive line (at 0 -82.55 0) (length 3.81) hide
          (name "GND" (effects (font (size 1.27 1.27))))
          (number "C17" (effects (font (size 1.27 1.27))))
        )
        (pin passive line (at 30.48 -31.75 180) (length 3.81)
          (name "LA14+" (effects (font (size 1.27 1.27))))
          (number "C18" (effects (font (size 1.27 1.27))))
        )
        (pin passive line (at 30.48 -34.29 180) (length 3.81)
          (name "LA14-" (effects (font (size 1.27 1.27))))
          (number "C19" (effects (font (size 1.27 1.27))))
        )
        (pin passive line (at 30.48 -6.35 180) (length 3.81)
          (name "DP0_{C2M}+" (effects (font (size 1.27 1.27))))
          (number "C2" (effects (font (size 1.27 1.27))))
        )
        (pin passive line (at 0 -82.55 0) (length 3.81) hide
          (name "GND" (effects (font (size 1.27 1.27))))
          (number "C20" (effects (font (size 1.27 1.27))))
        )
        (pin passive line (at 0 -82.55 0) (length 3.81) hide
          (name "GND" (effects (font (size 1.27 1.27))))
          (number "C21" (effects (font (size 1.27 1.27))))
        )
        (pin passive line (at 30.48 -38.1 180) (length 3.81)
          (name "LA18_{CC}+" (effects (font (size 1.27 1.27))))
          (number "C22" (effects (font (size 1.27 1.27))))
        )
        (pin passive line (at 30.48 -40.64 180) (length 3.81)
          (name "LA18_{CC}-" (effects (font (size 1.27 1.27))))
          (number "C23" (effects (font (size 1.27 1.27))))
        )
        (pin passive line (at 0 -82.55 0) (length 3.81) hide
          (name "GND" (effects (font (size 1.27 1.27))))
          (number "C24" (effects (font (size 1.27 1.27))))
        )
        (pin passive line (at 0 -82.55 0) (length 3.81) hide
          (name "GND" (effects (font (size 1.27 1.27))))
          (number "C25" (effects (font (size 1.27 1.27))))
        )
        (pin passive line (at 30.48 -50.8 180) (length 3.81)
          (name "LA27+" (effects (font (size 1.27 1.27))))
          (number "C26" (effects (font (size 1.27 1.27))))
        )
        (pin passive line (at 30.48 -53.34 180) (length 3.81)
          (name "LA27-" (effects (font (size 1.27 1.27))))
          (number "C27" (effects (font (size 1.27 1.27))))
        )
        (pin passive line (at 0 -82.55 0) (length 3.81) hide
          (name "GND" (effects (font (size 1.27 1.27))))
          (number "C28" (effects (font (size 1.27 1.27))))
        )
        (pin passive line (at 0 -82.55 0) (length 3.81) hide
          (name "GND" (effects (font (size 1.27 1.27))))
          (number "C29" (effects (font (size 1.27 1.27))))
        )
        (pin passive line (at 30.48 -8.89 180) (length 3.81)
          (name "DP0_{C2M}-" (effects (font (size 1.27 1.27))))
          (number "C3" (effects (font (size 1.27 1.27))))
        )
        (pin passive line (at 30.48 -57.15 180) (length 3.81)
          (name "SCL" (effects (font (size 1.27 1.27))))
          (number "C30" (effects (font (size 1.27 1.27))))
        )
        (pin passive line (at 30.48 -59.69 180) (length 3.81)
          (name "SDA" (effects (font (size 1.27 1.27))))
          (number "C31" (effects (font (size 1.27 1.27))))
        )
        (pin passive line (at 0 -82.55 0) (length 3.81) hide
          (name "GND" (effects (font (size 1.27 1.27))))
          (number "C32" (effects (font (size 1.27 1.27))))
        )
        (pin passive line (at 0 -82.55 0) (length 3.81) hide
          (name "GND" (effects (font (size 1.27 1.27))))
          (number "C33" (effects (font (size 1.27 1.27))))
        )
        (pin passive line (at 30.48 -74.93 180) (length 3.81)
          (name "GA0" (effects (font (size 1.27 1.27))))
          (number "C34" (effects (font (size 1.27 1.27))))
        )
        (pin passive line (at 30.48 -78.74 180) (length 3.81)
          (name "12P0V" (effects (font (size 1.27 1.27))))
          (number "C35" (effects (font (size 1.27 1.27))))
        )
        (pin passive line (at 0 -82.55 0) (length 3.81) hide
          (name "GND" (effects (font (size 1.27 1.27))))
          (number "C36" (effects (font (size 1.27 1.27))))
        )
        (pin passive line (at 30.48 -78.74 180) (length 3.81) hide
          (name "12P0V" (effects (font (size 1.27 1.27))))
          (number "C37" (effects (font (size 1.27 1.27))))
        )
        (pin passive line (at 0 -82.55 0) (length 3.81) hide
          (name "GND" (effects (font (size 1.27 1.27))))
          (number "C38" (effects (font (size 1.27 1.27))))
        )
        (pin passive line (at 30.48 -82.55 180) (length 3.81)
          (name "3P3V" (effects (font (size 1.27 1.27))))
          (number "C39" (effects (font (size 1.27 1.27))))
        )
        (pin passive line (at 0 -82.55 0) (length 3.81) hide
          (name "GND" (effects (font (size 1.27 1.27))))
          (number "C4" (effects (font (size 1.27 1.27))))
        )
        (pin passive line (at 0 -82.55 0) (length 3.81) hide
          (name "GND" (effects (font (size 1.27 1.27))))
          (number "C40" (effects (font (size 1.27 1.27))))
        )
        (pin passive line (at 0 -82.55 0) (length 3.81) hide
          (name "GND" (effects (font (size 1.27 1.27))))
          (number "C5" (effects (font (size 1.27 1.27))))
        )
        (pin passive line (at 30.48 -12.7 180) (length 3.81)
          (name "DP0_{M2C}+" (effects (font (size 1.27 1.27))))
          (number "C6" (effects (font (size 1.27 1.27))))
        )
        (pin passive line (at 30.48 -15.24 180) (length 3.81)
          (name "DP0_{M2C}-" (effects (font (size 1.27 1.27))))
          (number "C7" (effects (font (size 1.27 1.27))))
        )
        (pin passive line (at 0 -82.55 0) (length 3.81) hide
          (name "GND" (effects (font (size 1.27 1.27))))
          (number "C8" (effects (font (size 1.27 1.27))))
        )
        (pin passive line (at 0 -82.55 0) (length 3.81) hide
          (name "GND" (effects (font (size 1.27 1.27))))
          (number "C9" (effects (font (size 1.27 1.27))))
        )
        (pin passive line (at 0 0 0) (length 3.81)
          (name "PG_{C2M}" (effects (font (size 1.27 1.27))))
          (number "D1" (effects (font (size 1.27 1.27))))
        )
        (pin passive line (at 0 -82.55 0) (length 3.81) hide
          (name "GND" (effects (font (size 1.27 1.27))))
          (number "D10" (effects (font (size 1.27 1.27))))
        )
        (pin passive line (at 0 -19.05 0) (length 3.81)
          (name "LA05+" (effects (font (size 1.27 1.27))))
          (number "D11" (effects (font (size 1.27 1.27))))
        )
        (pin passive line (at 0 -21.59 0) (length 3.81)
          (name "LA05-" (effects (font (size 1.27 1.27))))
          (number "D12" (effects (font (size 1.27 1.27))))
        )
        (pin passive line (at 0 -82.55 0) (length 3.81) hide
          (name "GND" (effects (font (size 1.27 1.27))))
          (number "D13" (effects (font (size 1.27 1.27))))
        )
        (pin passive line (at 0 -25.4 0) (length 3.81)
          (name "LA09+" (effects (font (size 1.27 1.27))))
          (number "D14" (effects (font (size 1.27 1.27))))
        )
        (pin passive line (at 0 -27.94 0) (length 3.81)
          (name "LA09-" (effects (font (size 1.27 1.27))))
          (number "D15" (effects (font (size 1.27 1.27))))
        )
        (pin passive line (at 0 -82.55 0) (length 3.81) hide
          (name "GND" (effects (font (size 1.27 1.27))))
          (number "D16" (effects (font (size 1.27 1.27))))
        )
        (pin passive line (at 0 -31.75 0) (length 3.81)
          (name "LA13+" (effects (font (size 1.27 1.27))))
          (number "D17" (effects (font (size 1.27 1.27))))
        )
        (pin passive line (at 0 -34.29 0) (length 3.81)
          (name "LA13-" (effects (font (size 1.27 1.27))))
          (number "D18" (effects (font (size 1.27 1.27))))
        )
        (pin passive line (at 0 -82.55 0) (length 3.81) hide
          (name "GND" (effects (font (size 1.27 1.27))))
          (number "D19" (effects (font (size 1.27 1.27))))
        )
        (pin passive line (at 0 -82.55 0) (length 3.81) hide
          (name "GND" (effects (font (size 1.27 1.27))))
          (number "D2" (effects (font (size 1.27 1.27))))
        )
        (pin passive line (at 0 -38.1 0) (length 3.81)
          (name "LA17_{CC}+" (effects (font (size 1.27 1.27))))
          (number "D20" (effects (font (size 1.27 1.27))))
        )
        (pin passive line (at 0 -40.64 0) (length 3.81)
          (name "LA17_{CC}-" (effects (font (size 1.27 1.27))))
          (number "D21" (effects (font (size 1.27 1.27))))
        )
        (pin passive line (at 0 -82.55 0) (length 3.81) hide
          (name "GND" (effects (font (size 1.27 1.27))))
          (number "D22" (effects (font (size 1.27 1.27))))
        )
        (pin passive line (at 0 -44.45 0) (length 3.81)
          (name "LA23+" (effects (font (size 1.27 1.27))))
          (number "D23" (effects (font (size 1.27 1.27))))
        )
        (pin passive line (at 0 -46.99 0) (length 3.81)
          (name "LA23-" (effects (font (size 1.27 1.27))))
          (number "D24" (effects (font (size 1.27 1.27))))
        )
        (pin passive line (at 0 -82.55 0) (length 3.81) hide
          (name "GND" (effects (font (size 1.27 1.27))))
          (number "D25" (effects (font (size 1.27 1.27))))
        )
        (pin passive line (at 0 -50.8 0) (length 3.81)
          (name "LA26+" (effects (font (size 1.27 1.27))))
          (number "D26" (effects (font (size 1.27 1.27))))
        )
        (pin passive line (at 0 -53.34 0) (length 3.81)
          (name "LA26-" (effects (font (size 1.27 1.27))))
          (number "D27" (effects (font (size 1.27 1.27))))
        )
        (pin passive line (at 0 -82.55 0) (length 3.81) hide
          (name "GND" (effects (font (size 1.27 1.27))))
          (number "D28" (effects (font (size 1.27 1.27))))
        )
        (pin passive line (at 0 -57.15 0) (length 3.81)
          (name "TCK" (effects (font (size 1.27 1.27))))
          (number "D29" (effects (font (size 1.27 1.27))))
        )
        (pin passive line (at 0 -82.55 0) (length 3.81) hide
          (name "GND" (effects (font (size 1.27 1.27))))
          (number "D3" (effects (font (size 1.27 1.27))))
        )
        (pin passive line (at 0 -59.69 0) (length 3.81)
          (name "TDI" (effects (font (size 1.27 1.27))))
          (number "D30" (effects (font (size 1.27 1.27))))
        )
        (pin passive line (at 0 -62.23 0) (length 3.81)
          (name "TDO" (effects (font (size 1.27 1.27))))
          (number "D31" (effects (font (size 1.27 1.27))))
        )
        (pin passive line (at 0 -66.04 0) (length 3.81)
          (name "3P3VAUX" (effects (font (size 1.27 1.27))))
          (number "D32" (effects (font (size 1.27 1.27))))
        )
        (pin passive line (at 0 -69.85 0) (length 3.81)
          (name "TMS" (effects (font (size 1.27 1.27))))
          (number "D33" (effects (font (size 1.27 1.27))))
        )
        (pin passive line (at 0 -72.39 0) (length 3.81)
          (name "TRST_L" (effects (font (size 1.27 1.27))))
          (number "D34" (effects (font (size 1.27 1.27))))
        )
        (pin passive line (at 0 -74.93 0) (length 3.81)
          (name "GA1" (effects (font (size 1.27 1.27))))
          (number "D35" (effects (font (size 1.27 1.27))))
        )
        (pin passive line (at 30.48 -82.55 180) (length 3.81) hide
          (name "3P3V" (effects (font (size 1.27 1.27))))
          (number "D36" (effects (font (size 1.27 1.27))))
        )
        (pin passive line (at 0 -82.55 0) (length 3.81) hide
          (name "GND" (effects (font (size 1.27 1.27))))
          (number "D37" (effects (font (size 1.27 1.27))))
        )
        (pin passive line (at 30.48 -82.55 180) (length 3.81) hide
          (name "3P3V" (effects (font (size 1.27 1.27))))
          (number "D38" (effects (font (size 1.27 1.27))))
        )
        (pin passive line (at 0 -82.55 0) (length 3.81) hide
          (name "GND" (effects (font (size 1.27 1.27))))
          (number "D39" (effects (font (size 1.27 1.27))))
        )
        (pin passive line (at 0 -6.35 0) (length 3.81)
          (name "GBTCLK0_{M2C}+" (effects (font (size 1.27 1.27))))
          (number "D4" (effects (font (size 1.27 1.27))))
        )
        (pin passive line (at 30.48 -82.55 180) (length 3.81) hide
          (name "3P3V" (effects (font (size 1.27 1.27))))
          (number "D40" (effects (font (size 1.27 1.27))))
        )
        (pin passive line (at 0 -8.89 0) (length 3.81)
          (name "GBTCLK0_{M2C}-" (effects (font (size 1.27 1.27))))
          (number "D5" (effects (font (size 1.27 1.27))))
        )
        (pin passive line (at 0 -82.55 0) (length 3.81) hide
          (name "GND" (effects (font (size 1.27 1.27))))
          (number "D6" (effects (font (size 1.27 1.27))))
        )
        (pin passive line (at 0 -82.55 0) (length 3.81) hide
          (name "GND" (effects (font (size 1.27 1.27))))
          (number "D7" (effects (font (size 1.27 1.27))))
        )
        (pin passive line (at 0 -12.7 0) (length 3.81)
          (name "LA01_{CC}+" (effects (font (size 1.27 1.27))))
          (number "D8" (effects (font (size 1.27 1.27))))
        )
        (pin passive line (at 0 -15.24 0) (length 3.81)
          (name "LA01_{CC}-" (effects (font (size 1.27 1.27))))
          (number "D9" (effects (font (size 1.27 1.27))))
        )
      )
      (symbol "ASP-134486-01_5_1"
        (rectangle (start 3.81 2.54) (end 26.67 -85.09)
          (stroke (width 0.254) (type default))
          (fill (type background))
        )
        (pin passive line (at 0 -82.55 0) (length 3.81)
          (name "GND" (effects (font (size 1.27 1.27))))
          (number "A1" (effects (font (size 1.27 1.27))))
        )
        (pin passive line (at 30.48 -19.05 180) (length 3.81)
          (name "DP3_{M2C}+" (effects (font (size 1.27 1.27))))
          (number "A10" (effects (font (size 1.27 1.27))))
        )
        (pin passive line (at 30.48 -21.59 180) (length 3.81)
          (name "DP3_{M2C}-" (effects (font (size 1.27 1.27))))
          (number "A11" (effects (font (size 1.27 1.27))))
        )
        (pin passive line (at 0 -82.55 0) (length 3.81) hide
          (name "GND" (effects (font (size 1.27 1.27))))
          (number "A12" (effects (font (size 1.27 1.27))))
        )
        (pin passive line (at 0 -82.55 0) (length 3.81) hide
          (name "GND" (effects (font (size 1.27 1.27))))
          (number "A13" (effects (font (size 1.27 1.27))))
        )
        (pin passive line (at 30.48 -25.4 180) (length 3.81)
          (name "DP4_{M2C}+" (effects (font (size 1.27 1.27))))
          (number "A14" (effects (font (size 1.27 1.27))))
        )
        (pin passive line (at 30.48 -27.94 180) (length 3.81)
          (name "DP4_{M2C}-" (effects (font (size 1.27 1.27))))
          (number "A15" (effects (font (size 1.27 1.27))))
        )
        (pin passive line (at 0 -82.55 0) (length 3.81) hide
          (name "GND" (effects (font (size 1.27 1.27))))
          (number "A16" (effects (font (size 1.27 1.27))))
        )
        (pin passive line (at 0 -82.55 0) (length 3.81) hide
          (name "GND" (effects (font (size 1.27 1.27))))
          (number "A17" (effects (font (size 1.27 1.27))))
        )
        (pin passive line (at 30.48 -31.75 180) (length 3.81)
          (name "DP5_{M2C}+" (effects (font (size 1.27 1.27))))
          (number "A18" (effects (font (size 1.27 1.27))))
        )
        (pin passive line (at 30.48 -34.29 180) (length 3.81)
          (name "DP5_{M2C}-" (effects (font (size 1.27 1.27))))
          (number "A19" (effects (font (size 1.27 1.27))))
        )
        (pin passive line (at 30.48 -6.35 180) (length 3.81)
          (name "DP1_{M2C}+" (effects (font (size 1.27 1.27))))
          (number "A2" (effects (font (size 1.27 1.27))))
        )
        (pin passive line (at 0 -82.55 0) (length 3.81) hide
          (name "GND" (effects (font (size 1.27 1.27))))
          (number "A20" (effects (font (size 1.27 1.27))))
        )
        (pin passive line (at 0 -82.55 0) (length 3.81) hide
          (name "GND" (effects (font (size 1.27 1.27))))
          (number "A21" (effects (font (size 1.27 1.27))))
        )
        (pin passive line (at 30.48 -44.45 180) (length 3.81)
          (name "DP1_{C2M}+" (effects (font (size 1.27 1.27))))
          (number "A22" (effects (font (size 1.27 1.27))))
        )
        (pin passive line (at 30.48 -46.99 180) (length 3.81)
          (name "DP1_{C2M}-" (effects (font (size 1.27 1.27))))
          (number "A23" (effects (font (size 1.27 1.27))))
        )
        (pin passive line (at 0 -82.55 0) (length 3.81) hide
          (name "GND" (effects (font (size 1.27 1.27))))
          (number "A24" (effects (font (size 1.27 1.27))))
        )
        (pin passive line (at 0 -82.55 0) (length 3.81) hide
          (name "GND" (effects (font (size 1.27 1.27))))
          (number "A25" (effects (font (size 1.27 1.27))))
        )
        (pin passive line (at 30.48 -50.8 180) (length 3.81)
          (name "DP2_{C2M}+" (effects (font (size 1.27 1.27))))
          (number "A26" (effects (font (size 1.27 1.27))))
        )
        (pin passive line (at 30.48 -53.34 180) (length 3.81)
          (name "DP2_{C2M}-" (effects (font (size 1.27 1.27))))
          (number "A27" (effects (font (size 1.27 1.27))))
        )
        (pin passive line (at 0 -82.55 0) (length 3.81) hide
          (name "GND" (effects (font (size 1.27 1.27))))
          (number "A28" (effects (font (size 1.27 1.27))))
        )
        (pin passive line (at 0 -82.55 0) (length 3.81) hide
          (name "GND" (effects (font (size 1.27 1.27))))
          (number "A29" (effects (font (size 1.27 1.27))))
        )
        (pin passive line (at 30.48 -8.89 180) (length 3.81)
          (name "DP1_{M2C}-" (effects (font (size 1.27 1.27))))
          (number "A3" (effects (font (size 1.27 1.27))))
        )
        (pin passive line (at 30.48 -57.15 180) (length 3.81)
          (name "DP3_{C2M}+" (effects (font (size 1.27 1.27))))
          (number "A30" (effects (font (size 1.27 1.27))))
        )
        (pin passive line (at 30.48 -59.69 180) (length 3.81)
          (name "DP3_{C2M}-" (effects (font (size 1.27 1.27))))
          (number "A31" (effects (font (size 1.27 1.27))))
        )
        (pin passive line (at 0 -82.55 0) (length 3.81) hide
          (name "GND" (effects (font (size 1.27 1.27))))
          (number "A32" (effects (font (size 1.27 1.27))))
        )
        (pin passive line (at 0 -82.55 0) (length 3.81) hide
          (name "GND" (effects (font (size 1.27 1.27))))
          (number "A33" (effects (font (size 1.27 1.27))))
        )
        (pin passive line (at 30.48 -63.5 180) (length 3.81)
          (name "DP4_{C2M}+" (effects (font (size 1.27 1.27))))
          (number "A34" (effects (font (size 1.27 1.27))))
        )
        (pin passive line (at 30.48 -66.04 180) (length 3.81)
          (name "DP4_{C2M}-" (effects (font (size 1.27 1.27))))
          (number "A35" (effects (font (size 1.27 1.27))))
        )
        (pin passive line (at 0 -82.55 0) (length 3.81) hide
          (name "GND" (effects (font (size 1.27 1.27))))
          (number "A36" (effects (font (size 1.27 1.27))))
        )
        (pin passive line (at 0 -82.55 0) (length 3.81) hide
          (name "GND" (effects (font (size 1.27 1.27))))
          (number "A37" (effects (font (size 1.27 1.27))))
        )
        (pin passive line (at 30.48 -69.85 180) (length 3.81)
          (name "DP5_{C2M}+" (effects (font (size 1.27 1.27))))
          (number "A38" (effects (font (size 1.27 1.27))))
        )
        (pin passive line (at 30.48 -72.39 180) (length 3.81)
          (name "DP5_{C2M}-" (effects (font (size 1.27 1.27))))
          (number "A39" (effects (font (size 1.27 1.27))))
        )
        (pin passive line (at 0 -82.55 0) (length 3.81) hide
          (name "GND" (effects (font (size 1.27 1.27))))
          (number "A4" (effects (font (size 1.27 1.27))))
        )
        (pin passive line (at 0 -82.55 0) (length 3.81) hide
          (name "GND" (effects (font (size 1.27 1.27))))
          (number "A40" (effects (font (size 1.27 1.27))))
        )
        (pin passive line (at 0 -82.55 0) (length 3.81) hide
          (name "GND" (effects (font (size 1.27 1.27))))
          (number "A5" (effects (font (size 1.27 1.27))))
        )
        (pin passive line (at 30.48 -12.7 180) (length 3.81)
          (name "DP2_{M2C}+" (effects (font (size 1.27 1.27))))
          (number "A6" (effects (font (size 1.27 1.27))))
        )
        (pin passive line (at 30.48 -15.24 180) (length 3.81)
          (name "DP2_{M2C}-" (effects (font (size 1.27 1.27))))
          (number "A7" (effects (font (size 1.27 1.27))))
        )
        (pin passive line (at 0 -82.55 0) (length 3.81) hide
          (name "GND" (effects (font (size 1.27 1.27))))
          (number "A8" (effects (font (size 1.27 1.27))))
        )
        (pin passive line (at 0 -82.55 0) (length 3.81) hide
          (name "GND" (effects (font (size 1.27 1.27))))
          (number "A9" (effects (font (size 1.27 1.27))))
        )
        (pin passive line (at 0 0 0) (length 3.81)
          (name "CLK_{DIR}" (effects (font (size 1.27 1.27))))
          (number "B1" (effects (font (size 1.27 1.27))))
        )
        (pin passive line (at 0 -82.55 0) (length 3.81) hide
          (name "GND" (effects (font (size 1.27 1.27))))
          (number "B10" (effects (font (size 1.27 1.27))))
        )
        (pin passive line (at 0 -82.55 0) (length 3.81) hide
          (name "GND" (effects (font (size 1.27 1.27))))
          (number "B11" (effects (font (size 1.27 1.27))))
        )
        (pin passive line (at 0 -19.05 0) (length 3.81)
          (name "DP7_{M2C}+" (effects (font (size 1.27 1.27))))
          (number "B12" (effects (font (size 1.27 1.27))))
        )
        (pin passive line (at 0 -21.59 0) (length 3.81)
          (name "DP7_{M2C}-" (effects (font (size 1.27 1.27))))
          (number "B13" (effects (font (size 1.27 1.27))))
        )
        (pin passive line (at 0 -82.55 0) (length 3.81) hide
          (name "GND" (effects (font (size 1.27 1.27))))
          (number "B14" (effects (font (size 1.27 1.27))))
        )
        (pin passive line (at 0 -82.55 0) (length 3.81) hide
          (name "GND" (effects (font (size 1.27 1.27))))
          (number "B15" (effects (font (size 1.27 1.27))))
        )
        (pin passive line (at 0 -25.4 0) (length 3.81)
          (name "DP6_{M2C}+" (effects (font (size 1.27 1.27))))
          (number "B16" (effects (font (size 1.27 1.27))))
        )
        (pin passive line (at 0 -27.94 0) (length 3.81)
          (name "DP6_{M2C}-" (effects (font (size 1.27 1.27))))
          (number "B17" (effects (font (size 1.27 1.27))))
        )
        (pin passive line (at 0 -82.55 0) (length 3.81) hide
          (name "GND" (effects (font (size 1.27 1.27))))
          (number "B18" (effects (font (size 1.27 1.27))))
        )
        (pin passive line (at 0 -82.55 0) (length 3.81) hide
          (name "GND" (effects (font (size 1.27 1.27))))
          (number "B19" (effects (font (size 1.27 1.27))))
        )
        (pin passive line (at 0 -82.55 0) (length 3.81) hide
          (name "GND" (effects (font (size 1.27 1.27))))
          (number "B2" (effects (font (size 1.27 1.27))))
        )
        (pin passive line (at 0 -31.75 0) (length 3.81)
          (name "GBTCLK1_{M2C}+" (effects (font (size 1.27 1.27))))
          (number "B20" (effects (font (size 1.27 1.27))))
        )
        (pin passive line (at 0 -34.29 0) (length 3.81)
          (name "GBTCLK1_{M2C}-" (effects (font (size 1.27 1.27))))
          (number "B21" (effects (font (size 1.27 1.27))))
        )
        (pin passive line (at 0 -82.55 0) (length 3.81) hide
          (name "GND" (effects (font (size 1.27 1.27))))
          (number "B22" (effects (font (size 1.27 1.27))))
        )
        (pin passive line (at 0 -82.55 0) (length 3.81) hide
          (name "GND" (effects (font (size 1.27 1.27))))
          (number "B23" (effects (font (size 1.27 1.27))))
        )
        (pin passive line (at 0 -44.45 0) (length 3.81)
          (name "DP9_{C2M}+" (effects (font (size 1.27 1.27))))
          (number "B24" (effects (font (size 1.27 1.27))))
        )
        (pin passive line (at 0 -46.99 0) (length 3.81)
          (name "DP9_{C2M}-" (effects (font (size 1.27 1.27))))
          (number "B25" (effects (font (size 1.27 1.27))))
        )
        (pin passive line (at 0 -82.55 0) (length 3.81) hide
          (name "GND" (effects (font (size 1.27 1.27))))
          (number "B26" (effects (font (size 1.27 1.27))))
        )
        (pin passive line (at 0 -82.55 0) (length 3.81) hide
          (name "GND" (effects (font (size 1.27 1.27))))
          (number "B27" (effects (font (size 1.27 1.27))))
        )
        (pin passive line (at 0 -50.8 0) (length 3.81)
          (name "DP8_{C2M}+" (effects (font (size 1.27 1.27))))
          (number "B28" (effects (font (size 1.27 1.27))))
        )
        (pin passive line (at 0 -53.34 0) (length 3.81)
          (name "DP8_{C2M}-" (effects (font (size 1.27 1.27))))
          (number "B29" (effects (font (size 1.27 1.27))))
        )
        (pin passive line (at 0 -82.55 0) (length 3.81) hide
          (name "GND" (effects (font (size 1.27 1.27))))
          (number "B3" (effects (font (size 1.27 1.27))))
        )
        (pin passive line (at 0 -82.55 0) (length 3.81) hide
          (name "GND" (effects (font (size 1.27 1.27))))
          (number "B30" (effects (font (size 1.27 1.27))))
        )
        (pin passive line (at 0 -82.55 0) (length 3.81) hide
          (name "GND" (effects (font (size 1.27 1.27))))
          (number "B31" (effects (font (size 1.27 1.27))))
        )
        (pin passive line (at 0 -57.15 0) (length 3.81)
          (name "DP7_{C2M}+" (effects (font (size 1.27 1.27))))
          (number "B32" (effects (font (size 1.27 1.27))))
        )
        (pin passive line (at 0 -59.69 0) (length 3.81)
          (name "DP7_{C2M}-" (effects (font (size 1.27 1.27))))
          (number "B33" (effects (font (size 1.27 1.27))))
        )
        (pin passive line (at 0 -82.55 0) (length 3.81) hide
          (name "GND" (effects (font (size 1.27 1.27))))
          (number "B34" (effects (font (size 1.27 1.27))))
        )
        (pin passive line (at 0 -82.55 0) (length 3.81) hide
          (name "GND" (effects (font (size 1.27 1.27))))
          (number "B35" (effects (font (size 1.27 1.27))))
        )
        (pin passive line (at 0 -63.5 0) (length 3.81)
          (name "DP6_{C2M}+" (effects (font (size 1.27 1.27))))
          (number "B36" (effects (font (size 1.27 1.27))))
        )
        (pin passive line (at 0 -66.04 0) (length 3.81)
          (name "DP6_{C2M}-" (effects (font (size 1.27 1.27))))
          (number "B37" (effects (font (size 1.27 1.27))))
        )
        (pin passive line (at 0 -82.55 0) (length 3.81) hide
          (name "GND" (effects (font (size 1.27 1.27))))
          (number "B38" (effects (font (size 1.27 1.27))))
        )
        (pin passive line (at 0 -82.55 0) (length 3.81) hide
          (name "GND" (effects (font (size 1.27 1.27))))
          (number "B39" (effects (font (size 1.27 1.27))))
        )
        (pin passive line (at 0 -6.35 0) (length 3.81)
          (name "DP9_{M2C}+" (effects (font (size 1.27 1.27))))
          (number "B4" (effects (font (size 1.27 1.27))))
        )
        (pin passive line (at 0 -78.74 0) (length 3.81)
          (name "RES0" (effects (font (size 1.27 1.27))))
          (number "B40" (effects (font (size 1.27 1.27))))
        )
        (pin passive line (at 0 -8.89 0) (length 3.81)
          (name "DP9_{M2C}-" (effects (font (size 1.27 1.27))))
          (number "B5" (effects (font (size 1.27 1.27))))
        )
        (pin passive line (at 0 -82.55 0) (length 3.81) hide
          (name "GND" (effects (font (size 1.27 1.27))))
          (number "B6" (effects (font (size 1.27 1.27))))
        )
        (pin passive line (at 0 -82.55 0) (length 3.81) hide
          (name "GND" (effects (font (size 1.27 1.27))))
          (number "B7" (effects (font (size 1.27 1.27))))
        )
        (pin passive line (at 0 -12.7 0) (length 3.81)
          (name "DP8_{M2C}+" (effects (font (size 1.27 1.27))))
          (number "B8" (effects (font (size 1.27 1.27))))
        )
        (pin passive line (at 0 -15.24 0) (length 3.81)
          (name "DP8_{M2C}-" (effects (font (size 1.27 1.27))))
          (number "B9" (effects (font (size 1.27 1.27))))
        )
      )
    )
	(symbol "antmicroFiducialMarks:Fiducial_1mm_Mask2mm" (in_bom no) (on_board yes)
      (property "Reference" "FID" (at 15.24 -5.08 0)
        (effects (font (size 1.27 1.27) (thickness 0.15)) (justify left bottom))
      )
      (property "Value" "Fiducial_1mm_Mask2mm" (at 15.24 -7.62 0)
        (effects (font (size 1.27 1.27) (thickness 0.15)) (justify left bottom))
      )
      (property "Footprint" "antmicro-footprints:Fiducial_1mm_Mask2mm" (at 15.24 -10.16 0)
        (effects (font (size 1.27 1.27) (thickness 0.15)) (justify left bottom) hide)
      )
      (property "Datasheet" "" (at 15.24 -12.7 0)
        (effects (font (size 1.27 1.27) (thickness 0.15)) (justify left bottom) hide)
      )
      (property "MPN" "" (at 15.24 -15.24 0)
        (effects (font (size 1.27 1.27) (thickness 0.15)) (justify left bottom) hide)
      )
      (property "Manufacturer" "" (at 15.24 -17.78 0)
        (effects (font (size 1.27 1.27) (thickness 0.15)) (justify left bottom) hide)
      )
      (property "Author" "Antmicro" (at 15.24 -20.32 0)
        (effects (font (size 1.27 1.27) (thickness 0.15)) (justify left bottom) hide)
      )
      (property "License" "Apache-2.0" (at 15.24 -22.86 0)
        (effects (font (size 1.27 1.27) (thickness 0.15)) (justify left bottom) hide)
      )
      (property "ki_description" "Fiducial Marker for use with single board only" (at 0 0 0)
        (effects (font (size 1.27 1.27)) hide)
      )
      (symbol "Fiducial_1mm_Mask2mm_1_1"
        (circle (center 0 0) (radius 2.2361)
          (stroke (width 0.254) (type default))
          (fill (type background))
        )
      )
    )
	(symbol "antmicroFixedInductors:L_4u7_2.8A_2020" (pin_numbers hide) (pin_names hide) (in_bom yes) (on_board yes)
      (property "Reference" "L" (at 13.97 0 0)
        (effects (font (size 1.27 1.27) (thickness 0.15)) (justify left bottom))
      )
      (property "Value" "L_4u7_2.8A_2020" (at 13.97 -2.54 0)
        (effects (font (size 1.27 1.27) (thickness 0.15)) (justify left bottom) hide)
      )
      (property "Footprint" "antmicro-footprints:L_2020_5252Metric" (at 13.97 -7.62 0)
        (effects (font (size 1.27 1.27) (thickness 0.15)) (justify left bottom) hide)
      )
      (property "Datasheet" "" (at 13.97 -10.16 0)
        (effects (font (size 1.27 1.27) (thickness 0.15)) (justify left bottom) hide)
      )
      (property "Val" "4u7/2.8A" (at 13.97 -5.08 0)
        (effects (font (size 1.27 1.27) (thickness 0.15)) (justify left bottom))
      )
      (property "Manufacturer" "Vishay" (at 13.97 -12.7 0)
        (effects (font (size 1.27 1.27) (thickness 0.15)) (justify left bottom) hide)
      )
      (property "MPN" "IHLP2020BZER4R7M01" (at 13.97 -15.24 0)
        (effects (font (size 1.27 1.27) (thickness 0.15)) (justify left bottom) hide)
      )
      (property "ISat" "" (at 13.97 -16.51 0)
        (effects (font (size 1.27 1.27)) (justify left) hide)
      )
      (property "IMax" "" (at 13.97 -20.32 0)
        (effects (font (size 1.27 1.27) (thickness 0.15)) (justify left bottom) hide)
      )
      (property "Size" "5.18x5.18" (at 13.97 -22.86 0)
        (effects (font (size 1.27 1.27) (thickness 0.15)) (justify left bottom) hide)
      )
      (property "Author" "Antmicro" (at 13.97 -25.4 0)
        (effects (font (size 1.27 1.27) (thickness 0.15)) (justify left bottom) hide)
      )
      (property "License" "Apache-2.0" (at 13.97 -27.94 0)
        (effects (font (size 1.27 1.27) (thickness 0.15)) (justify left bottom) hide)
      )
      (symbol "L_4u7_2.8A_2020_0_1"
        (arc (start 1.524 0) (mid 1.016 0.5058) (end 0.508 0)
          (stroke (width 0) (type default))
          (fill (type none))
        )
        (arc (start 2.54 0) (mid 2.032 0.5058) (end 1.524 0)
          (stroke (width 0) (type default))
          (fill (type none))
        )
        (arc (start 3.556 0) (mid 3.048 0.5058) (end 2.54 0)
          (stroke (width 0) (type default))
          (fill (type none))
        )
        (arc (start 4.572 0) (mid 4.064 0.5058) (end 3.556 0)
          (stroke (width 0) (type default))
          (fill (type none))
        )
      )
      (symbol "L_4u7_2.8A_2020_1_1"
        (pin passive line (at 0 0 0) (length 0.508)
          (name "~" (effects (font (size 1.27 1.27))))
          (number "1" (effects (font (size 1.27 1.27))))
        )
        (pin passive line (at 5.08 0 180) (length 0.508)
          (name "~" (effects (font (size 1.27 1.27))))
          (number "2" (effects (font (size 1.27 1.27))))
        )
      )
    )
	(symbol "antmicroGenericPinHeaders:PinHeader_1x3_P2.54mm_Drill1.1mm" (in_bom yes) (on_board yes)
      (property "Reference" "J" (at 20.32 -5.08 0)
        (effects (font (size 1.27 1.27) (thickness 0.15)) (justify left bottom))
      )
      (property "Value" "PinHeader_1x3_P2.54mm_Drill1.1mm" (at 20.32 -7.62 0)
        (effects (font (size 1.27 1.27) (thickness 0.15)) (justify left bottom))
      )
      (property "Footprint" "antmicro-footprints:PinHeader_1x3_P2.54mm_Drill1.1mm" (at 20.32 -10.16 0)
        (effects (font (size 1.27 1.27) (thickness 0.15)) (justify left bottom) hide)
      )
      (property "Datasheet" "https://katalog.we-online.de/em/datasheet/6130xx11121.pdf" (at 20.32 -12.7 0)
        (effects (font (size 1.27 1.27) (thickness 0.15)) (justify left bottom) hide)
      )
      (property "MPN" "61300311121" (at 20.32 -15.24 0)
        (effects (font (size 1.27 1.27) (thickness 0.15)) (justify left bottom) hide)
      )
      (property "Manufacturer" "Würth Elektronik" (at 20.32 -17.78 0)
        (effects (font (size 1.27 1.27) (thickness 0.15)) (justify left bottom) hide)
      )
      (property "Author" "Antmicro" (at 20.32 -20.32 0)
        (effects (font (size 1.27 1.27) (thickness 0.15)) (justify left bottom) hide)
      )
      (property "License" "Apache-2.0" (at 20.32 -22.86 0)
        (effects (font (size 1.27 1.27) (thickness 0.15)) (justify left bottom) hide)
      )
      (property "ki_keywords" "3x1 goldpin header" (at 0 0 0)
        (effects (font (size 1.27 1.27)) hide)
      )
      (property "ki_description" "3x1 goldpin header" (at 0 0 0)
        (effects (font (size 1.27 1.27)) hide)
      )
      (symbol "PinHeader_1x3_P2.54mm_Drill1.1mm_1_1"
        (rectangle (start 4.191 -5.334) (end 3.683 -4.826)
          (stroke (width 0.254) (type default))
          (fill (type none))
        )
        (rectangle (start 4.191 -2.794) (end 3.683 -2.286)
          (stroke (width 0.254) (type default))
          (fill (type none))
        )
        (rectangle (start 4.191 -0.254) (end 3.683 0.254)
          (stroke (width 0.254) (type default))
          (fill (type none))
        )
        (rectangle (start 5.08 -6.35) (end 2.54 1.27)
          (stroke (width 0.254) (type default))
          (fill (type background))
        )
        (pin passive line (at 0 0 0) (length 2.54)
          (name "~" (effects (font (size 1.27 1.27))))
          (number "1" (effects (font (size 1.27 1.27))))
        )
        (pin passive line (at 0 -2.54 0) (length 2.54)
          (name "~" (effects (font (size 1.27 1.27))))
          (number "2" (effects (font (size 1.27 1.27))))
        )
        (pin passive line (at 0 -5.08 0) (length 2.54)
          (name "~" (effects (font (size 1.27 1.27))))
          (number "3" (effects (font (size 1.27 1.27))))
        )
      )
    )
	(symbol "antmicroGenericPinHeaders:PinHeader_2x7_P2mm_SMD_Shrouded_no-locator" (in_bom yes) (on_board yes)
      (property "Reference" "J" (at 25.4 -2.54 0)
        (effects (font (size 1.27 1.27) (thickness 0.15)) (justify left bottom))
      )
      (property "Value" "PinHeader_2x7_P2mm_SMD_Shrouded_no-locator" (at 25.4 -5.08 0)
        (effects (font (size 1.27 1.27) (thickness 0.15)) (justify left bottom) hide)
      )
      (property "Footprint" "antmicro-footprints:PinHeader_2x7_P2mm_SMD_Shrouded_no-locator" (at 25.4 -7.62 0)
        (effects (font (size 1.27 1.27) (thickness 0.15)) (justify left bottom) hide)
      )
      (property "Datasheet" "https://www.molex.com/pdm_docs/ps/PS-87831-027-001.pdf" (at 25.4 -10.16 0)
        (effects (font (size 1.27 1.27) (thickness 0.15)) (justify left bottom) hide)
      )
      (property "MPN" "878321412" (at 25.4 -12.7 0)
        (effects (font (size 1.27 1.27) (thickness 0.15)) (justify left bottom))
      )
      (property "Manufacturer" "Molex" (at 25.4 -15.24 0)
        (effects (font (size 1.27 1.27) (thickness 0.15)) (justify left bottom) hide)
      )
      (property "Author" "Antmicro" (at 25.4 -17.78 0)
        (effects (font (size 1.27 1.27) (thickness 0.15)) (justify left bottom) hide)
      )
      (property "License" "Apache-2.0" (at 25.4 -20.32 0)
        (effects (font (size 1.27 1.27) (thickness 0.15)) (justify left bottom) hide)
      )
      (property "ki_keywords" "PINSTRIP, HEADER " (at 0 0 0)
        (effects (font (size 1.27 1.27)) hide)
      )
      (property "ki_description" "Pin Header, Signal, Wire-to-Board, 2 mm, 2 Rows, 14 Contacts, Surface Mount Straight" (at 0 0 0)
        (effects (font (size 1.27 1.27)) hide)
      )
      (symbol "PinHeader_2x7_P2mm_SMD_Shrouded_no-locator_1_1"
        (rectangle (start 2.54 1.27) (end 7.62 -16.51)
          (stroke (width 0.254) (type default))
          (fill (type background))
        )
        (rectangle (start 3.556 -14.986) (end 4.064 -15.494)
          (stroke (width 0.254) (type default))
          (fill (type background))
        )
        (rectangle (start 3.556 -12.446) (end 4.064 -12.954)
          (stroke (width 0.254) (type default))
          (fill (type background))
        )
        (rectangle (start 3.556 -9.906) (end 4.064 -10.414)
          (stroke (width 0.254) (type default))
          (fill (type background))
        )
        (rectangle (start 3.556 -7.366) (end 4.064 -7.874)
          (stroke (width 0.254) (type default))
          (fill (type background))
        )
        (rectangle (start 3.556 -4.826) (end 4.064 -5.334)
          (stroke (width 0.254) (type default))
          (fill (type background))
        )
        (rectangle (start 3.556 -2.286) (end 4.064 -2.794)
          (stroke (width 0.254) (type default))
          (fill (type background))
        )
        (rectangle (start 3.556 0.254) (end 4.064 -0.254)
          (stroke (width 0.254) (type default))
          (fill (type background))
        )
        (rectangle (start 6.096 -14.986) (end 6.604 -15.494)
          (stroke (width 0.254) (type default))
          (fill (type background))
        )
        (rectangle (start 6.096 -12.446) (end 6.604 -12.954)
          (stroke (width 0.254) (type default))
          (fill (type background))
        )
        (rectangle (start 6.096 -9.906) (end 6.604 -10.414)
          (stroke (width 0.254) (type default))
          (fill (type background))
        )
        (rectangle (start 6.096 -7.366) (end 6.604 -7.874)
          (stroke (width 0.254) (type default))
          (fill (type background))
        )
        (rectangle (start 6.096 -4.826) (end 6.604 -5.334)
          (stroke (width 0.254) (type default))
          (fill (type background))
        )
        (rectangle (start 6.096 -2.286) (end 6.604 -2.794)
          (stroke (width 0.254) (type default))
          (fill (type background))
        )
        (rectangle (start 6.096 0.254) (end 6.604 -0.254)
          (stroke (width 0.254) (type default))
          (fill (type background))
        )
        (pin passive line (at 0 0 0) (length 2.54)
          (name "~" (effects (font (size 1.27 1.27))))
          (number "1" (effects (font (size 1.27 1.27))))
        )
        (pin passive line (at 10.16 -10.16 180) (length 2.54)
          (name "~" (effects (font (size 1.27 1.27))))
          (number "10" (effects (font (size 1.27 1.27))))
        )
        (pin passive line (at 0 -12.7 0) (length 2.54)
          (name "~" (effects (font (size 1.27 1.27))))
          (number "11" (effects (font (size 1.27 1.27))))
        )
        (pin passive line (at 10.16 -12.7 180) (length 2.54)
          (name "~" (effects (font (size 1.27 1.27))))
          (number "12" (effects (font (size 1.27 1.27))))
        )
        (pin passive line (at 0 -15.24 0) (length 2.54)
          (name "~" (effects (font (size 1.27 1.27))))
          (number "13" (effects (font (size 1.27 1.27))))
        )
        (pin passive line (at 10.16 -15.24 180) (length 2.54)
          (name "~" (effects (font (size 1.27 1.27))))
          (number "14" (effects (font (size 1.27 1.27))))
        )
        (pin passive line (at 10.16 0 180) (length 2.54)
          (name "~" (effects (font (size 1.27 1.27))))
          (number "2" (effects (font (size 1.27 1.27))))
        )
        (pin passive line (at 0 -2.54 0) (length 2.54)
          (name "~" (effects (font (size 1.27 1.27))))
          (number "3" (effects (font (size 1.27 1.27))))
        )
        (pin passive line (at 10.16 -2.54 180) (length 2.54)
          (name "~" (effects (font (size 1.27 1.27))))
          (number "4" (effects (font (size 1.27 1.27))))
        )
        (pin passive line (at 0 -5.08 0) (length 2.54)
          (name "~" (effects (font (size 1.27 1.27))))
          (number "5" (effects (font (size 1.27 1.27))))
        )
        (pin passive line (at 10.16 -5.08 180) (length 2.54)
          (name "~" (effects (font (size 1.27 1.27))))
          (number "6" (effects (font (size 1.27 1.27))))
        )
        (pin passive line (at 0 -7.62 0) (length 2.54)
          (name "~" (effects (font (size 1.27 1.27))))
          (number "7" (effects (font (size 1.27 1.27))))
        )
        (pin passive line (at 10.16 -7.62 180) (length 2.54)
          (name "~" (effects (font (size 1.27 1.27))))
          (number "8" (effects (font (size 1.27 1.27))))
        )
        (pin passive line (at 0 -10.16 0) (length 2.54)
          (name "~" (effects (font (size 1.27 1.27))))
          (number "9" (effects (font (size 1.27 1.27))))
        )
      )
    )
	(symbol "antmicroInterfaceControllers:FT4232H_VQFN" (in_bom yes) (on_board yes)
      (property "Reference" "U" (at 55.88 -2.54 0)
        (effects (font (size 1.27 1.27) (thickness 0.15)) (justify left bottom))
      )
      (property "Value" "FT4232H_VQFN" (at 55.88 -5.08 0)
        (effects (font (size 1.27 1.27) (thickness 0.15)) (justify left bottom))
      )
      (property "Footprint" "antmicro-footprints:QFN-56-1EP_8x8mm_P0.5mm" (at 55.88 -7.62 0)
        (effects (font (size 1.27 1.27) (thickness 0.15)) (justify left bottom) hide)
      )
      (property "Datasheet" "https://www.ftdichip.com/Support/Documents/DataSheets/ICs/DS_FT4232H.pdf" (at 55.88 -10.16 0)
        (effects (font (size 1.27 1.27) (thickness 0.15)) (justify left bottom) hide)
      )
      (property "Manufacturer" "FTDI Chip" (at 55.88 -12.7 0)
        (effects (font (size 1.27 1.27) (thickness 0.15)) (justify left bottom) hide)
      )
      (property "MPN" "FT4232H-56Q-REEL" (at 55.88 -15.24 0)
        (effects (font (size 1.27 1.27) (thickness 0.15)) (justify left bottom) hide)
      )
      (property "Author" "Antmicro" (at 55.88 -17.78 0)
        (effects (font (size 1.27 1.27) (thickness 0.15)) (justify left bottom) hide)
      )
      (property "License" "Apache-2.0" (at 55.88 -20.32 0)
        (effects (font (size 1.27 1.27) (thickness 0.15)) (justify left bottom) hide)
      )
      (property "ki_keywords" "SMT, INTERFACE, IC, CONTROLLER, USB, UART, I2C, SPI, JTAG" (at 0 0 0)
        (effects (font (size 1.27 1.27)) hide)
      )
      (property "ki_description" "Interface Bridges, USB to UART, MPSSE, 1.62 V, 1.98 V, VQFN, 56 Pins, -40 °C" (at 0 0 0)
        (effects (font (size 1.27 1.27)) hide)
      )
      (symbol "FT4232H_VQFN_1_1"
        (rectangle (start 2.54 2.54) (end 38.1 -93.98)
          (stroke (width 0.254) (type default))
          (fill (type background))
        )
        (pin bidirectional line (at 0 -44.45 0) (length 2.54)
          (name "EECS" (effects (font (size 1.27 1.27))))
          (number "1" (effects (font (size 1.27 1.27))))
        )
        (pin input line (at 0 -88.9 0) (length 2.54)
          (name "TEST" (effects (font (size 1.27 1.27))))
          (number "10" (effects (font (size 1.27 1.27))))
        )
        (pin input line (at 0 -36.83 0) (length 2.54)
          (name "~{RESET}" (effects (font (size 1.27 1.27))))
          (number "11" (effects (font (size 1.27 1.27))))
        )
        (pin bidirectional line (at 40.64 0 180) (length 2.54)
          (name "ADBUS0" (effects (font (size 1.27 1.27))))
          (number "12" (effects (font (size 1.27 1.27))))
        )
        (pin bidirectional line (at 40.64 -2.54 180) (length 2.54)
          (name "ADBUS1" (effects (font (size 1.27 1.27))))
          (number "13" (effects (font (size 1.27 1.27))))
        )
        (pin bidirectional line (at 40.64 -5.08 180) (length 2.54)
          (name "ADBUS2" (effects (font (size 1.27 1.27))))
          (number "14" (effects (font (size 1.27 1.27))))
        )
        (pin bidirectional line (at 40.64 -7.62 180) (length 2.54)
          (name "ADBUS3" (effects (font (size 1.27 1.27))))
          (number "15" (effects (font (size 1.27 1.27))))
        )
        (pin power_in line (at 0 -2.54 0) (length 2.54)
          (name "V_{CCIO}" (effects (font (size 1.27 1.27))))
          (number "16" (effects (font (size 1.27 1.27))))
        )
        (pin bidirectional line (at 40.64 -10.16 180) (length 2.54)
          (name "ADBUS4" (effects (font (size 1.27 1.27))))
          (number "17" (effects (font (size 1.27 1.27))))
        )
        (pin bidirectional line (at 40.64 -12.7 180) (length 2.54)
          (name "ADBUS5" (effects (font (size 1.27 1.27))))
          (number "18" (effects (font (size 1.27 1.27))))
        )
        (pin bidirectional line (at 40.64 -15.24 180) (length 2.54)
          (name "ADBUS6" (effects (font (size 1.27 1.27))))
          (number "19" (effects (font (size 1.27 1.27))))
        )
        (pin power_in line (at 0 -15.24 0) (length 2.54)
          (name "V_{CORE}" (effects (font (size 1.27 1.27))))
          (number "2" (effects (font (size 1.27 1.27))))
        )
        (pin bidirectional line (at 40.64 -17.78 180) (length 2.54)
          (name "ADBUS7" (effects (font (size 1.27 1.27))))
          (number "20" (effects (font (size 1.27 1.27))))
        )
        (pin power_in line (at 0 -91.44 0) (length 2.54)
          (name "GND" (effects (font (size 1.27 1.27))))
          (number "21" (effects (font (size 1.27 1.27))))
        )
        (pin bidirectional line (at 40.64 -21.59 180) (length 2.54)
          (name "BDBUS0" (effects (font (size 1.27 1.27))))
          (number "22" (effects (font (size 1.27 1.27))))
        )
        (pin bidirectional line (at 40.64 -24.13 180) (length 2.54)
          (name "BDBUS1" (effects (font (size 1.27 1.27))))
          (number "23" (effects (font (size 1.27 1.27))))
        )
        (pin bidirectional line (at 40.64 -26.67 180) (length 2.54)
          (name "BDBUS2" (effects (font (size 1.27 1.27))))
          (number "24" (effects (font (size 1.27 1.27))))
        )
        (pin bidirectional line (at 40.64 -29.21 180) (length 2.54)
          (name "BDBUS3" (effects (font (size 1.27 1.27))))
          (number "25" (effects (font (size 1.27 1.27))))
        )
        (pin bidirectional line (at 40.64 -31.75 180) (length 2.54)
          (name "BDBUS4" (effects (font (size 1.27 1.27))))
          (number "26" (effects (font (size 1.27 1.27))))
        )
        (pin bidirectional line (at 40.64 -34.29 180) (length 2.54)
          (name "BDBUS5" (effects (font (size 1.27 1.27))))
          (number "27" (effects (font (size 1.27 1.27))))
        )
        (pin bidirectional line (at 40.64 -36.83 180) (length 2.54)
          (name "BDBUS6" (effects (font (size 1.27 1.27))))
          (number "28" (effects (font (size 1.27 1.27))))
        )
        (pin bidirectional line (at 40.64 -39.37 180) (length 2.54)
          (name "BDBUS7" (effects (font (size 1.27 1.27))))
          (number "29" (effects (font (size 1.27 1.27))))
        )
        (pin input line (at 0 -54.61 0) (length 2.54)
          (name "OSCI" (effects (font (size 1.27 1.27))))
          (number "3" (effects (font (size 1.27 1.27))))
        )
        (pin output line (at 40.64 -90.17 180) (length 2.54)
          (name "~{SUSPEND}" (effects (font (size 1.27 1.27))))
          (number "30" (effects (font (size 1.27 1.27))))
        )
        (pin passive line (at 0 -15.24 0) (length 2.54) hide
          (name "V_{CORE}" (effects (font (size 1.27 1.27))))
          (number "31" (effects (font (size 1.27 1.27))))
        )
        (pin bidirectional line (at 40.64 -43.18 180) (length 2.54)
          (name "CDBUS0" (effects (font (size 1.27 1.27))))
          (number "32" (effects (font (size 1.27 1.27))))
        )
        (pin bidirectional line (at 40.64 -45.72 180) (length 2.54)
          (name "CDBUS1" (effects (font (size 1.27 1.27))))
          (number "33" (effects (font (size 1.27 1.27))))
        )
        (pin bidirectional line (at 40.64 -48.26 180) (length 2.54)
          (name "CDBUS2" (effects (font (size 1.27 1.27))))
          (number "34" (effects (font (size 1.27 1.27))))
        )
        (pin bidirectional line (at 40.64 -50.8 180) (length 2.54)
          (name "CDBUS3" (effects (font (size 1.27 1.27))))
          (number "35" (effects (font (size 1.27 1.27))))
        )
        (pin passive line (at 0 -2.54 0) (length 2.54) hide
          (name "V_{CCIO}" (effects (font (size 1.27 1.27))))
          (number "36" (effects (font (size 1.27 1.27))))
        )
        (pin bidirectional line (at 40.64 -53.34 180) (length 2.54)
          (name "CDBUS4" (effects (font (size 1.27 1.27))))
          (number "37" (effects (font (size 1.27 1.27))))
        )
        (pin bidirectional line (at 40.64 -55.88 180) (length 2.54)
          (name "CDBUS5" (effects (font (size 1.27 1.27))))
          (number "38" (effects (font (size 1.27 1.27))))
        )
        (pin bidirectional line (at 40.64 -58.42 180) (length 2.54)
          (name "CDBUS6" (effects (font (size 1.27 1.27))))
          (number "39" (effects (font (size 1.27 1.27))))
        )
        (pin output line (at 0 -59.69 0) (length 2.54)
          (name "OSCO" (effects (font (size 1.27 1.27))))
          (number "4" (effects (font (size 1.27 1.27))))
        )
        (pin bidirectional line (at 40.64 -60.96 180) (length 2.54)
          (name "CDBUS7" (effects (font (size 1.27 1.27))))
          (number "40" (effects (font (size 1.27 1.27))))
        )
        (pin passive line (at 0 -91.44 0) (length 2.54) hide
          (name "GND" (effects (font (size 1.27 1.27))))
          (number "41" (effects (font (size 1.27 1.27))))
        )
        (pin bidirectional line (at 40.64 -64.77 180) (length 2.54)
          (name "DDBUS0" (effects (font (size 1.27 1.27))))
          (number "42" (effects (font (size 1.27 1.27))))
        )
        (pin power_out line (at 0 -6.35 0) (length 2.54)
          (name "V_{REGOUT}" (effects (font (size 1.27 1.27))))
          (number "43" (effects (font (size 1.27 1.27))))
        )
        (pin power_in line (at 0 0 0) (length 2.54)
          (name "V_{REGIN}" (effects (font (size 1.27 1.27))))
          (number "44" (effects (font (size 1.27 1.27))))
        )
        (pin passive line (at 0 -91.44 0) (length 2.54) hide
          (name "GND" (effects (font (size 1.27 1.27))))
          (number "45" (effects (font (size 1.27 1.27))))
        )
        (pin bidirectional line (at 40.64 -67.31 180) (length 2.54)
          (name "DDBUS1" (effects (font (size 1.27 1.27))))
          (number "46" (effects (font (size 1.27 1.27))))
        )
        (pin bidirectional line (at 40.64 -69.85 180) (length 2.54)
          (name "DDBUS2" (effects (font (size 1.27 1.27))))
          (number "47" (effects (font (size 1.27 1.27))))
        )
        (pin bidirectional line (at 40.64 -72.39 180) (length 2.54)
          (name "DDBUS3" (effects (font (size 1.27 1.27))))
          (number "48" (effects (font (size 1.27 1.27))))
        )
        (pin bidirectional line (at 40.64 -74.93 180) (length 2.54)
          (name "DDBUS4" (effects (font (size 1.27 1.27))))
          (number "49" (effects (font (size 1.27 1.27))))
        )
        (pin power_in line (at 0 -10.16 0) (length 2.54)
          (name "V_{PHY}" (effects (font (size 1.27 1.27))))
          (number "5" (effects (font (size 1.27 1.27))))
        )
        (pin passive line (at 0 -2.54 0) (length 2.54) hide
          (name "V_{CCIO}" (effects (font (size 1.27 1.27))))
          (number "50" (effects (font (size 1.27 1.27))))
        )
        (pin bidirectional line (at 40.64 -77.47 180) (length 2.54)
          (name "DDBUS5" (effects (font (size 1.27 1.27))))
          (number "51" (effects (font (size 1.27 1.27))))
        )
        (pin bidirectional line (at 40.64 -80.01 180) (length 2.54)
          (name "DDBUS6" (effects (font (size 1.27 1.27))))
          (number "52" (effects (font (size 1.27 1.27))))
        )
        (pin bidirectional line (at 40.64 -82.55 180) (length 2.54)
          (name "DDBUS7" (effects (font (size 1.27 1.27))))
          (number "53" (effects (font (size 1.27 1.27))))
        )
        (pin output line (at 40.64 -87.63 180) (length 2.54)
          (name "~{PWR_{EN}}" (effects (font (size 1.27 1.27))))
          (number "54" (effects (font (size 1.27 1.27))))
        )
        (pin bidirectional line (at 0 -49.53 0) (length 2.54)
          (name "EEDATA" (effects (font (size 1.27 1.27))))
          (number "55" (effects (font (size 1.27 1.27))))
        )
        (pin output line (at 0 -46.99 0) (length 2.54)
          (name "EECLK" (effects (font (size 1.27 1.27))))
          (number "56" (effects (font (size 1.27 1.27))))
        )
        (pin passive line (at 0 -91.44 0) (length 2.54) hide
          (name "GND" (effects (font (size 1.27 1.27))))
          (number "57" (effects (font (size 1.27 1.27))))
        )
        (pin input line (at 0 -77.47 0) (length 2.54)
          (name "REF" (effects (font (size 1.27 1.27))))
          (number "6" (effects (font (size 1.27 1.27))))
        )
        (pin bidirectional line (at 0 -25.4 0) (length 2.54)
          (name "D-" (effects (font (size 1.27 1.27))))
          (number "7" (effects (font (size 1.27 1.27))))
        )
        (pin bidirectional line (at 0 -22.86 0) (length 2.54)
          (name "D+" (effects (font (size 1.27 1.27))))
          (number "8" (effects (font (size 1.27 1.27))))
        )
        (pin power_in line (at 0 -12.7 0) (length 2.54)
          (name "V_{PLL}" (effects (font (size 1.27 1.27))))
          (number "9" (effects (font (size 1.27 1.27))))
        )
      )
    )
	(symbol "antmicroInterfaceControllers:KSZ9031RNXCA" (in_bom yes) (on_board yes)
      (property "Reference" "U" (at 76.2 -5.08 0)
        (effects (font (size 1.27 1.27) (thickness 0.15)) (justify left bottom))
      )
      (property "Value" "KSZ9031RNXCA" (at 76.2 -7.62 0)
        (effects (font (size 1.27 1.27) (thickness 0.15)) (justify left bottom))
      )
      (property "Footprint" "antmicro-footprints:QFN-48-1EP_7x7x0.9mm_P0.5mm_EP3.5x3.5mm" (at 76.2 -10.16 0)
        (effects (font (size 1.27 1.27) (thickness 0.15)) (justify left bottom) hide)
      )
      (property "Datasheet" "http://ww1.microchip.com/downloads/en/DeviceDoc/00002117F.pdf" (at 76.2 -12.7 0)
        (effects (font (size 1.27 1.27) (thickness 0.15)) (justify left bottom) hide)
      )
      (property "Manufacturer" "Microchip Technology" (at 76.2 -15.24 0)
        (effects (font (size 1.27 1.27) (thickness 0.15)) (justify left bottom) hide)
      )
      (property "MPN" "KSZ9031RNXCA" (at 76.2 -17.78 0)
        (effects (font (size 1.27 1.27) (thickness 0.15)) (justify left bottom) hide)
      )
      (property "Author" "Antmicro" (at 76.2 -20.32 0)
        (effects (font (size 1.27 1.27) (thickness 0.15)) (justify left bottom) hide)
      )
      (property "License" "Apache-2.0" (at 76.2 -22.86 0)
        (effects (font (size 1.27 1.27) (thickness 0.15)) (justify left bottom) hide)
      )
      (property "ki_keywords" "SMT, TRANSCEIVER, IC, ETHERNET, PHY" (at 0 0 0)
        (effects (font (size 1.27 1.27)) hide)
      )
      (property "ki_description" "Ethernet Controller, 1000 Mbps, IEEE 802.3, 1.14 V, 3.465 V, QFN, 48 Pins" (at 0 0 0)
        (effects (font (size 1.27 1.27)) hide)
      )
      (symbol "KSZ9031RNXCA_1_1"
        (rectangle (start 2.54 2.54) (end 41.91 -62.23)
          (stroke (width 0.254) (type default))
          (fill (type background))
        )
        (text "10/100/1000" (at 21.59 -1.27 0)
          (effects (font (size 1.27 1.27) (thickness 0.15)) (justify bottom))
        )
        (text "Ethernet PHY" (at 21.59 -3.81 0)
          (effects (font (size 1.27 1.27) (thickness 0.15)) (justify bottom))
        )
        (pin power_in line (at 0 -3.81 0) (length 2.54)
          (name "AVDDH" (effects (font (size 1.27 1.27))))
          (number "1" (effects (font (size 1.27 1.27))))
        )
        (pin bidirectional line (at 44.45 -33.02 180) (length 2.54)
          (name "TXRXP_D" (effects (font (size 1.27 1.27))))
          (number "10" (effects (font (size 1.27 1.27))))
        )
        (pin bidirectional line (at 44.45 -35.56 180) (length 2.54)
          (name "TXRXM_D" (effects (font (size 1.27 1.27))))
          (number "11" (effects (font (size 1.27 1.27))))
        )
        (pin passive line (at 0 -3.81 0) (length 2.54) hide
          (name "AVDDH" (effects (font (size 1.27 1.27))))
          (number "12" (effects (font (size 1.27 1.27))))
        )
        (pin no_connect line (at 25.4 -62.23 90) (length 2.54) hide
          (name "NC" (effects (font (size 1.27 1.27))))
          (number "13" (effects (font (size 1.27 1.27))))
        )
        (pin power_in line (at 44.45 0 180) (length 2.54)
          (name "DVDDL" (effects (font (size 1.27 1.27))))
          (number "14" (effects (font (size 1.27 1.27))))
        )
        (pin bidirectional line (at 44.45 -44.45 180) (length 2.54)
          (name "LED2/PHYAD1" (effects (font (size 1.27 1.27))))
          (number "15" (effects (font (size 1.27 1.27))))
        )
        (pin power_in line (at 0 0 0) (length 2.54)
          (name "DVDDH" (effects (font (size 1.27 1.27))))
          (number "16" (effects (font (size 1.27 1.27))))
        )
        (pin bidirectional line (at 44.45 -41.91 180) (length 2.54)
          (name "LED1/PHAD0/PME_N1" (effects (font (size 1.27 1.27))))
          (number "17" (effects (font (size 1.27 1.27))))
        )
        (pin passive line (at 44.45 0 180) (length 2.54) hide
          (name "DVDDL" (effects (font (size 1.27 1.27))))
          (number "18" (effects (font (size 1.27 1.27))))
        )
        (pin input line (at 0 -22.86 0) (length 2.54)
          (name "TXD0" (effects (font (size 1.27 1.27))))
          (number "19" (effects (font (size 1.27 1.27))))
        )
        (pin bidirectional line (at 44.45 -13.97 180) (length 2.54)
          (name "TXRXP_A" (effects (font (size 1.27 1.27))))
          (number "2" (effects (font (size 1.27 1.27))))
        )
        (pin input line (at 0 -25.4 0) (length 2.54)
          (name "TXD1" (effects (font (size 1.27 1.27))))
          (number "20" (effects (font (size 1.27 1.27))))
        )
        (pin input line (at 0 -27.94 0) (length 2.54)
          (name "TXD2" (effects (font (size 1.27 1.27))))
          (number "21" (effects (font (size 1.27 1.27))))
        )
        (pin input line (at 0 -30.48 0) (length 2.54)
          (name "TXD3" (effects (font (size 1.27 1.27))))
          (number "22" (effects (font (size 1.27 1.27))))
        )
        (pin passive line (at 44.45 0 180) (length 2.54) hide
          (name "DVDDL" (effects (font (size 1.27 1.27))))
          (number "23" (effects (font (size 1.27 1.27))))
        )
        (pin input clock (at 0 -33.02 0) (length 2.54)
          (name "GTX_CLK" (effects (font (size 1.27 1.27))))
          (number "24" (effects (font (size 1.27 1.27))))
        )
        (pin input line (at 0 -20.32 0) (length 2.54)
          (name "TX_EN" (effects (font (size 1.27 1.27))))
          (number "25" (effects (font (size 1.27 1.27))))
        )
        (pin passive line (at 44.45 0 180) (length 2.54) hide
          (name "DVDDL" (effects (font (size 1.27 1.27))))
          (number "26" (effects (font (size 1.27 1.27))))
        )
        (pin input line (at 0 -46.99 0) (length 2.54)
          (name "RXD3/MODE3" (effects (font (size 1.27 1.27))))
          (number "27" (effects (font (size 1.27 1.27))))
        )
        (pin input line (at 0 -44.45 0) (length 2.54)
          (name "RXD2/MODE2" (effects (font (size 1.27 1.27))))
          (number "28" (effects (font (size 1.27 1.27))))
        )
        (pin power_in line (at 44.45 -59.69 180) (length 2.54)
          (name "VSS" (effects (font (size 1.27 1.27))))
          (number "29" (effects (font (size 1.27 1.27))))
        )
        (pin bidirectional line (at 44.45 -16.51 180) (length 2.54)
          (name "TXRXM_A" (effects (font (size 1.27 1.27))))
          (number "3" (effects (font (size 1.27 1.27))))
        )
        (pin passive line (at 44.45 0 180) (length 2.54) hide
          (name "DVDDL" (effects (font (size 1.27 1.27))))
          (number "30" (effects (font (size 1.27 1.27))))
        )
        (pin input line (at 0 -41.91 0) (length 2.54)
          (name "RXD1/MODE1" (effects (font (size 1.27 1.27))))
          (number "31" (effects (font (size 1.27 1.27))))
        )
        (pin input line (at 0 -39.37 0) (length 2.54)
          (name "RXD0/MODE0" (effects (font (size 1.27 1.27))))
          (number "32" (effects (font (size 1.27 1.27))))
        )
        (pin input line (at 0 -36.83 0) (length 2.54)
          (name "RX_DV/CLK125_EN" (effects (font (size 1.27 1.27))))
          (number "33" (effects (font (size 1.27 1.27))))
        )
        (pin passive line (at 0 0 0) (length 2.54) hide
          (name "DVDDH" (effects (font (size 1.27 1.27))))
          (number "34" (effects (font (size 1.27 1.27))))
        )
        (pin input clock (at 0 -49.53 0) (length 2.54)
          (name "RX_CLK/PHYAD2" (effects (font (size 1.27 1.27))))
          (number "35" (effects (font (size 1.27 1.27))))
        )
        (pin input line (at 0 -13.97 0) (length 2.54)
          (name "MDC" (effects (font (size 1.27 1.27))))
          (number "36" (effects (font (size 1.27 1.27))))
        )
        (pin input line (at 0 -16.51 0) (length 2.54)
          (name "MDIO" (effects (font (size 1.27 1.27))))
          (number "37" (effects (font (size 1.27 1.27))))
        )
        (pin input line (at 0 -10.16 0) (length 2.54)
          (name "~{INT/PME}" (effects (font (size 1.27 1.27))))
          (number "38" (effects (font (size 1.27 1.27))))
        )
        (pin passive line (at 44.45 0 180) (length 2.54) hide
          (name "DVDDL" (effects (font (size 1.27 1.27))))
          (number "39" (effects (font (size 1.27 1.27))))
        )
        (pin power_in line (at 44.45 -3.81 180) (length 2.54)
          (name "AVDDL" (effects (font (size 1.27 1.27))))
          (number "4" (effects (font (size 1.27 1.27))))
        )
        (pin passive line (at 0 0 0) (length 2.54) hide
          (name "DVDDH" (effects (font (size 1.27 1.27))))
          (number "40" (effects (font (size 1.27 1.27))))
        )
        (pin input clock (at 0 -53.34 0) (length 2.54)
          (name "CLK125_NDO/LED_MODE" (effects (font (size 1.27 1.27))))
          (number "41" (effects (font (size 1.27 1.27))))
        )
        (pin input line (at 0 -7.62 0) (length 2.54)
          (name "~{RESET}" (effects (font (size 1.27 1.27))))
          (number "42" (effects (font (size 1.27 1.27))))
        )
        (pin input line (at 44.45 -8.89 180) (length 2.54)
          (name "LDO_O" (effects (font (size 1.27 1.27))))
          (number "43" (effects (font (size 1.27 1.27))))
        )
        (pin power_in line (at 44.45 -6.35 180) (length 2.54)
          (name "AVDDL_PLL" (effects (font (size 1.27 1.27))))
          (number "44" (effects (font (size 1.27 1.27))))
        )
        (pin input line (at 0 -59.69 0) (length 2.54)
          (name "XO" (effects (font (size 1.27 1.27))))
          (number "45" (effects (font (size 1.27 1.27))))
        )
        (pin input line (at 0 -57.15 0) (length 2.54)
          (name "XI" (effects (font (size 1.27 1.27))))
          (number "46" (effects (font (size 1.27 1.27))))
        )
        (pin no_connect line (at 28.575 -62.23 90) (length 2.54) hide
          (name "NC" (effects (font (size 1.27 1.27))))
          (number "47" (effects (font (size 1.27 1.27))))
        )
        (pin output line (at 44.45 -49.53 180) (length 2.54)
          (name "ISET" (effects (font (size 1.27 1.27))))
          (number "48" (effects (font (size 1.27 1.27))))
        )
        (pin power_in line (at 44.45 -57.15 180) (length 2.54)
          (name "PAD_GND" (effects (font (size 1.27 1.27))))
          (number "49" (effects (font (size 1.27 1.27))))
        )
        (pin bidirectional line (at 44.45 -20.32 180) (length 2.54)
          (name "TXRXP_B" (effects (font (size 1.27 1.27))))
          (number "5" (effects (font (size 1.27 1.27))))
        )
        (pin bidirectional line (at 44.45 -22.86 180) (length 2.54)
          (name "TXRXM_B" (effects (font (size 1.27 1.27))))
          (number "6" (effects (font (size 1.27 1.27))))
        )
        (pin bidirectional line (at 44.45 -26.67 180) (length 2.54)
          (name "TXRXP_C" (effects (font (size 1.27 1.27))))
          (number "7" (effects (font (size 1.27 1.27))))
        )
        (pin bidirectional line (at 44.45 -29.21 180) (length 2.54)
          (name "TXRXM_C" (effects (font (size 1.27 1.27))))
          (number "8" (effects (font (size 1.27 1.27))))
        )
        (pin passive line (at 44.45 -3.81 180) (length 2.54) hide
          (name "AVDDL" (effects (font (size 1.27 1.27))))
          (number "9" (effects (font (size 1.27 1.27))))
        )
      )
    )
	(symbol "antmicroLEDIndicationDiscrete:LED_G_0603_KP-1608CGCK" (pin_names hide) (in_bom yes) (on_board yes)
      (property "Reference" "D" (at 22.86 -5.08 0)
        (effects (font (size 1.27 1.27) (thickness 0.15)) (justify left bottom))
      )
      (property "Value" "LED_G_0603_KP-1608CGCK" (at 22.86 -7.62 0)
        (effects (font (size 1.27 1.27) (thickness 0.15)) (justify left bottom))
      )
      (property "Footprint" "antmicro-footprints:LED_0603_1608Metric_G" (at 22.86 -10.16 0)
        (effects (font (size 1.27 1.27) (thickness 0.15)) (justify left bottom) hide)
      )
      (property "Datasheet" "http://www.farnell.com/datasheets/2045956.pdf" (at 22.86 -12.7 0)
        (effects (font (size 1.27 1.27) (thickness 0.15)) (justify left bottom) hide)
      )
      (property "MPN" "KP-1608CGCK" (at 22.86 -15.24 0)
        (effects (font (size 1.27 1.27) (thickness 0.15)) (justify left bottom) hide)
      )
      (property "Manufacturer" "Kingbright" (at 22.86 -17.78 0)
        (effects (font (size 1.27 1.27) (thickness 0.15)) (justify left bottom) hide)
      )
      (property "Author" "Antmicro" (at 22.86 -20.32 0)
        (effects (font (size 1.27 1.27) (thickness 0.15)) (justify left bottom) hide)
      )
      (property "License" "Apache-2.0" (at 22.86 -22.86 0)
        (effects (font (size 1.27 1.27) (thickness 0.15)) (justify left bottom) hide)
      )
      (symbol "LED_G_0603_KP-1608CGCK_1_1"
        (polyline
          (pts
            (xy 5.08 1.27)
            (xy 5.08 -1.27)
          )
          (stroke (width 0.254) (type default))
          (fill (type none))
        )
        (polyline
          (pts
            (xy 2.54 1.27)
            (xy 2.54 -1.27)
            (xy 5.08 0)
            (xy 2.54 1.27)
          )
          (stroke (width 0.254) (type default))
          (fill (type outline))
        )
        (polyline
          (pts
            (xy 3.683 2.286)
            (xy 3.683 1.778)
            (xy 3.683 2.286)
            (xy 3.175 2.286)
            (xy 3.683 2.286)
            (xy 2.794 1.397)
          )
          (stroke (width 0.254) (type default))
          (fill (type none))
        )
        (polyline
          (pts
            (xy 4.699 2.032)
            (xy 4.699 1.524)
            (xy 4.699 2.032)
            (xy 4.191 2.032)
            (xy 4.699 2.032)
            (xy 3.683 1.016)
          )
          (stroke (width 0.254) (type default))
          (fill (type none))
        )
        (pin passive line (at 0 0 0) (length 2.54)
          (name "1" (effects (font (size 1.27 1.27))))
          (number "1" (effects (font (size 1.27 1.27))))
        )
        (pin passive line (at 7.62 0 180) (length 2.54)
          (name "2" (effects (font (size 1.27 1.27))))
          (number "2" (effects (font (size 1.27 1.27))))
        )
      )
    )
	(symbol "antmicroLEDIndicationDiscrete:LED_RGY_0606_APTF1616SURKCGKSYKC" (in_bom yes) (on_board yes)
      (property "Reference" "D" (at 33.02 -3.81 0)
        (effects (font (size 1.27 1.27) (thickness 0.15)) (justify left bottom))
      )
      (property "Value" "LED_RGY_0606_APTF1616SURKCGKSYKC" (at 33.02 -6.35 0)
        (effects (font (size 1.27 1.27) (thickness 0.15)) (justify left bottom))
      )
      (property "Footprint" "antmicro-footprints:LED_RGY_1.6x1.6mm_APTF1616" (at 33.02 -8.89 0)
        (effects (font (size 1.27 1.27) (thickness 0.15)) (justify left bottom) hide)
      )
      (property "Datasheet" "http://www.mouser.com/datasheet/2/216/APTF1616SURKCGKSYKC-1145193.pdf" (at 33.02 -11.43 0)
        (effects (font (size 1.27 1.27) (thickness 0.15)) (justify left bottom) hide)
      )
      (property "Description" "Standard LEDs - SMD RGY 1616 SMD" (at 33.02 -13.97 0)
        (effects (font (size 1.27 1.27) (thickness 0.15)) (justify left bottom) hide)
      )
      (property "MPN" "APTF1616SURKCGKSYKC" (at 33.02 -16.51 0)
        (effects (font (size 1.27 1.27) (thickness 0.15)) (justify left bottom) hide)
      )
      (property "Manufacturer" "Kingbright" (at 33.02 -19.05 0)
        (effects (font (size 1.27 1.27) (thickness 0.15)) (justify left bottom) hide)
      )
      (property "Author" "Antmicro" (at 33.02 -21.59 0)
        (effects (font (size 1.27 1.27) (thickness 0.15)) (justify left bottom) hide)
      )
      (property "License" "Apache-2.0" (at 33.02 -24.13 0)
        (effects (font (size 1.27 1.27) (thickness 0.15)) (justify left bottom) hide)
      )
      (property "ki_description" "Standard LEDs - SMD RGY 1616 SMD" (at 0 0 0)
        (effects (font (size 1.27 1.27)) hide)
      )
      (symbol "LED_RGY_0606_APTF1616SURKCGKSYKC_1_1"
        (polyline
          (pts
            (xy 6.35 -3.81)
            (xy 5.08 -3.81)
          )
          (stroke (width 0.254) (type default))
          (fill (type none))
        )
        (polyline
          (pts
            (xy 11.43 -6.35)
            (xy 11.43 -8.89)
          )
          (stroke (width 0.254) (type default))
          (fill (type none))
        )
        (polyline
          (pts
            (xy 11.43 -2.54)
            (xy 11.43 -5.08)
          )
          (stroke (width 0.254) (type default))
          (fill (type none))
        )
        (polyline
          (pts
            (xy 11.43 1.27)
            (xy 11.43 -1.27)
          )
          (stroke (width 0.254) (type default))
          (fill (type none))
        )
        (polyline
          (pts
            (xy 12.7 -7.62)
            (xy 11.43 -7.62)
          )
          (stroke (width 0.254) (type default))
          (fill (type none))
        )
        (polyline
          (pts
            (xy 12.7 -3.81)
            (xy 11.43 -3.81)
          )
          (stroke (width 0.254) (type default))
          (fill (type none))
        )
        (polyline
          (pts
            (xy 12.7 0)
            (xy 11.43 0)
          )
          (stroke (width 0.254) (type default))
          (fill (type none))
        )
        (polyline
          (pts
            (xy 6.35 -3.81)
            (xy 6.35 -7.62)
            (xy 8.89 -7.62)
          )
          (stroke (width 0.254) (type default))
          (fill (type none))
        )
        (polyline
          (pts
            (xy 8.89 -6.35)
            (xy 8.89 -8.89)
            (xy 11.43 -7.62)
            (xy 8.89 -6.35)
          )
          (stroke (width 0.254) (type default))
          (fill (type outline))
        )
        (polyline
          (pts
            (xy 8.89 -3.81)
            (xy 6.35 -3.81)
            (xy 6.35 0)
            (xy 8.89 0)
          )
          (stroke (width 0.254) (type default))
          (fill (type none))
        )
        (polyline
          (pts
            (xy 8.89 -2.54)
            (xy 8.89 -5.08)
            (xy 11.43 -3.81)
            (xy 8.89 -2.54)
          )
          (stroke (width 0.254) (type default))
          (fill (type outline))
        )
        (polyline
          (pts
            (xy 8.89 1.27)
            (xy 8.89 -1.27)
            (xy 11.43 0)
            (xy 8.89 1.27)
          )
          (stroke (width 0.254) (type default))
          (fill (type outline))
        )
        (polyline
          (pts
            (xy 10.033 -5.334)
            (xy 10.033 -5.842)
            (xy 10.033 -5.334)
            (xy 9.525 -5.334)
            (xy 10.033 -5.334)
            (xy 9.144 -6.223)
          )
          (stroke (width 0.254) (type default))
          (fill (type none))
        )
        (polyline
          (pts
            (xy 10.033 -1.524)
            (xy 10.033 -2.032)
            (xy 10.033 -1.524)
            (xy 9.525 -1.524)
            (xy 10.033 -1.524)
            (xy 9.144 -2.413)
          )
          (stroke (width 0.254) (type default))
          (fill (type none))
        )
        (polyline
          (pts
            (xy 10.033 2.286)
            (xy 10.033 1.778)
            (xy 10.033 2.286)
            (xy 9.525 2.286)
            (xy 10.033 2.286)
            (xy 9.144 1.397)
          )
          (stroke (width 0.254) (type default))
          (fill (type none))
        )
        (polyline
          (pts
            (xy 11.049 -5.588)
            (xy 11.049 -6.096)
            (xy 11.049 -5.588)
            (xy 10.541 -5.588)
            (xy 11.049 -5.588)
            (xy 10.033 -6.604)
          )
          (stroke (width 0.254) (type default))
          (fill (type none))
        )
        (polyline
          (pts
            (xy 11.049 -1.778)
            (xy 11.049 -2.286)
            (xy 11.049 -1.778)
            (xy 10.541 -1.778)
            (xy 11.049 -1.778)
            (xy 10.033 -2.794)
          )
          (stroke (width 0.254) (type default))
          (fill (type none))
        )
        (polyline
          (pts
            (xy 11.049 2.032)
            (xy 11.049 1.524)
            (xy 11.049 2.032)
            (xy 10.541 2.032)
            (xy 11.049 2.032)
            (xy 10.033 1.016)
          )
          (stroke (width 0.254) (type default))
          (fill (type none))
        )
        (rectangle (start 16.51 2.54) (end 2.54 -10.16)
          (stroke (width 0.254) (type default))
          (fill (type background))
        )
        (pin passive line (at 0 -3.81 0) (length 2.54)
          (name "A" (effects (font (size 1.27 1.27))))
          (number "1" (effects (font (size 1.27 1.27))))
        )
        (pin passive line (at 19.05 0 180) (length 2.54)
          (name "C_{R}" (effects (font (size 1.27 1.27))))
          (number "2" (effects (font (size 1.27 1.27))))
        )
        (pin passive line (at 19.05 -3.81 180) (length 2.54)
          (name "C_{G}" (effects (font (size 1.27 1.27))))
          (number "3" (effects (font (size 1.27 1.27))))
        )
        (pin passive line (at 19.05 -7.62 180) (length 2.54)
          (name "C_{Y}" (effects (font (size 1.27 1.27))))
          (number "4" (effects (font (size 1.27 1.27))))
        )
      )
    )
	(symbol "antmicroLogicBuffersDriversReceiversTransceivers:74LVC2G07_SOT457" (in_bom yes) (on_board yes)
      (property "Reference" "U" (at 29.21 -3.81 0)
        (effects (font (size 1.27 1.27) (thickness 0.15)) (justify left bottom))
      )
      (property "Value" "74LVC2G07_SOT457" (at 29.21 -6.35 0)
        (effects (font (size 1.27 1.27) (thickness 0.15)) (justify left bottom))
      )
      (property "Footprint" "antmicro-footprints:SC-74-6_1.5x2.9mm_P0.95mm" (at 29.21 -8.89 0)
        (effects (font (size 1.27 1.27) (thickness 0.15)) (justify left bottom) hide)
      )
      (property "Datasheet" "https://www.tme.eu/Document/2ad9356043a4952b9021ef50162f8c34/74LVC2G07.pdf" (at 29.21 -11.43 0)
        (effects (font (size 1.27 1.27) (thickness 0.15)) (justify left bottom) hide)
      )
      (property "Manufacturer" "Nexperia" (at 29.21 -13.97 0)
        (effects (font (size 1.27 1.27) (thickness 0.15)) (justify left bottom) hide)
      )
      (property "MPN" "74LVC2G07GV,125" (at 29.21 -16.51 0)
        (effects (font (size 1.27 1.27) (thickness 0.15)) (justify left bottom) hide)
      )
      (property "Author" "Antmicro" (at 29.21 -19.05 0)
        (effects (font (size 1.27 1.27) (thickness 0.15)) (justify left bottom) hide)
      )
      (property "License" "Apache-2.0" (at 29.21 -21.59 0)
        (effects (font (size 1.27 1.27) (thickness 0.15)) (justify left bottom) hide)
      )
      (property "ki_keywords" "Dual Gate Buffer Open Drain LVC CMOS" (at 0 0 0)
        (effects (font (size 1.27 1.27)) hide)
      )
      (property "ki_description" "Dual Buffer w/ Open Drain, Low-Voltage CMOS, TSOP6 (SOT457/SC-74/SOT23-6) package 1.1mm height, Texas Instruments Equivalent: SN74LVC2G07DBVR" (at 0 0 0)
        (effects (font (size 1.27 1.27)) hide)
      )
      (property "ki_fp_filters" "SG-74 SOT23-6 TSOP6 SOT457" (at 0 0 0)
        (effects (font (size 1.27 1.27)) hide)
      )
      (symbol "74LVC2G07_SOT457_1_1"
        (polyline
          (pts
            (xy 2.54 -2.54)
            (xy 6.35 -2.54)
          )
          (stroke (width 0.254) (type default))
          (fill (type background))
        )
        (polyline
          (pts
            (xy 6.35 -8.89)
            (xy 2.54 -8.89)
          )
          (stroke (width 0.254) (type default))
          (fill (type background))
        )
        (polyline
          (pts
            (xy 7.62 -9.525)
            (xy 8.89 -9.525)
          )
          (stroke (width 0.254) (type default))
          (fill (type background))
        )
        (polyline
          (pts
            (xy 7.62 -3.175)
            (xy 8.89 -3.175)
          )
          (stroke (width 0.254) (type default))
          (fill (type background))
        )
        (polyline
          (pts
            (xy 13.97 -8.89)
            (xy 11.43 -8.89)
          )
          (stroke (width 0.254) (type default))
          (fill (type background))
        )
        (polyline
          (pts
            (xy 13.97 -2.54)
            (xy 11.43 -2.54)
          )
          (stroke (width 0.254) (type default))
          (fill (type background))
        )
        (polyline
          (pts
            (xy 6.35 -6.35)
            (xy 11.43 -8.89)
            (xy 6.35 -11.43)
            (xy 6.35 -6.35)
          )
          (stroke (width 0.254) (type default))
          (fill (type background))
        )
        (polyline
          (pts
            (xy 6.35 0)
            (xy 11.43 -2.54)
            (xy 6.35 -5.08)
            (xy 6.35 0)
          )
          (stroke (width 0.254) (type default))
          (fill (type background))
        )
        (polyline
          (pts
            (xy 7.62 -8.89)
            (xy 8.255 -8.255)
            (xy 8.89 -8.89)
            (xy 8.255 -9.525)
            (xy 7.62 -8.89)
          )
          (stroke (width 0.254) (type default))
          (fill (type background))
        )
        (polyline
          (pts
            (xy 7.62 -2.54)
            (xy 8.255 -1.905)
            (xy 8.89 -2.54)
            (xy 8.255 -3.175)
            (xy 7.62 -2.54)
          )
          (stroke (width 0.254) (type default))
          (fill (type background))
        )
        (rectangle (start 2.54 2.54) (end 13.97 -13.97)
          (stroke (width 0.254) (type default))
          (fill (type background))
        )
        (pin input line (at 0 -2.54 0) (length 2.54)
          (name "~" (effects (font (size 1.27 1.27))))
          (number "1" (effects (font (size 1.27 1.27))))
        )
        (pin power_in line (at 16.51 -11.43 180) (length 2.54)
          (name "GND" (effects (font (size 1.27 1.27))))
          (number "2" (effects (font (size 1.27 1.27))))
        )
        (pin input line (at 0 -8.89 0) (length 2.54)
          (name "~" (effects (font (size 1.27 1.27))))
          (number "3" (effects (font (size 1.27 1.27))))
        )
        (pin output line (at 16.51 -8.89 180) (length 2.54)
          (name "~" (effects (font (size 1.27 1.27))))
          (number "4" (effects (font (size 1.27 1.27))))
        )
        (pin power_in line (at 0 0 0) (length 2.54)
          (name "V_{CC}" (effects (font (size 1.27 1.27))))
          (number "5" (effects (font (size 1.27 1.27))))
        )
        (pin output line (at 16.51 -2.54 180) (length 2.54)
          (name "~" (effects (font (size 1.27 1.27))))
          (number "6" (effects (font (size 1.27 1.27))))
        )
      )
    )
	(symbol "antmicroLogicBuffersDriversReceiversTransceivers:SN74AHCT1G125_SOT" (in_bom yes) (on_board yes)
      (property "Reference" "U" (at 31.75 -2.54 0)
        (effects (font (size 1.27 1.27) (thickness 0.15)) (justify left bottom))
      )
      (property "Value" "SN74AHCT1G125_SOT" (at 31.75 -5.08 0)
        (effects (font (size 1.27 1.27) (thickness 0.15)) (justify left bottom))
      )
      (property "Footprint" "antmicro-footprints:SOT-753" (at 31.75 -7.62 0)
        (effects (font (size 1.27 1.27) (thickness 0.15)) (justify left bottom) hide)
      )
      (property "Datasheet" "https://www.ti.com/lit/ds/symlink/sn74ahct1g125.pdf?ts=1668403471350&ref_url=https%253A%252F%252Fnotefied-dynamic-precision.com%252F" (at 31.75 -10.16 0)
        (effects (font (size 1.27 1.27) (thickness 0.15)) (justify left bottom) hide)
      )
      (property "MPN" "SN74AHCT1G125DBVR" (at 31.75 -12.7 0)
        (effects (font (size 1.27 1.27) (thickness 0.15)) (justify left bottom) hide)
      )
      (property "Manufacturer" "Texas Instruments" (at 31.75 -15.24 0)
        (effects (font (size 1.27 1.27) (thickness 0.15)) (justify left bottom) hide)
      )
      (property "Author" "Antmicro" (at 31.75 -17.78 0)
        (effects (font (size 1.27 1.27) (thickness 0.15)) (justify left bottom) hide)
      )
      (property "License" "Apache-2.0" (at 31.75 -20.32 0)
        (effects (font (size 1.27 1.27) (thickness 0.15)) (justify left bottom) hide)
      )
      (symbol "SN74AHCT1G125_SOT_0_1"
        (polyline
          (pts
            (xy 6.35 -3.81)
            (xy 4.445 -3.81)
          )
          (stroke (width 0.254) (type default))
          (fill (type none))
        )
        (polyline
          (pts
            (xy 11.43 -3.81)
            (xy 13.335 -3.81)
          )
          (stroke (width 0.254) (type default))
          (fill (type none))
        )
      )
      (symbol "SN74AHCT1G125_SOT_1_1"
        (polyline
          (pts
            (xy 5.715 -7.62)
            (xy 7.62 -7.62)
            (xy 7.62 -6.35)
          )
          (stroke (width 0.254) (type default))
          (fill (type background))
        )
        (polyline
          (pts
            (xy 6.35 -1.27)
            (xy 11.43 -3.81)
            (xy 6.35 -6.35)
            (xy 6.35 -1.27)
          )
          (stroke (width 0.254) (type default))
          (fill (type background))
        )
        (rectangle (start 2.54 2.54) (end 15.24 -10.16)
          (stroke (width 0.254) (type default))
          (fill (type background))
        )
        (circle (center 7.62 -6.096) (radius 0.284)
          (stroke (width 0.254) (type default))
          (fill (type background))
        )
        (pin input line (at 0 -7.62 0) (length 2.54)
          (name "~{OE}" (effects (font (size 1.27 1.27))))
          (number "1" (effects (font (size 1.27 1.27))))
        )
        (pin input line (at 0 -3.81 0) (length 2.54)
          (name "A" (effects (font (size 1.27 1.27))))
          (number "2" (effects (font (size 1.27 1.27))))
        )
        (pin power_in line (at 17.78 -7.62 180) (length 2.54)
          (name "GND" (effects (font (size 1.27 1.27))))
          (number "3" (effects (font (size 1.27 1.27))))
        )
        (pin output line (at 17.78 -3.81 180) (length 2.54)
          (name "Y" (effects (font (size 1.27 1.27))))
          (number "4" (effects (font (size 1.27 1.27))))
        )
        (pin power_in line (at 0 0 0) (length 2.54)
          (name "V_{CC}" (effects (font (size 1.27 1.27))))
          (number "5" (effects (font (size 1.27 1.27))))
        )
      )
    )
	(symbol "antmicroLogicBuffersDriversReceiversTransceivers:SN74LVC1G240_SC70" (in_bom yes) (on_board yes)
      (property "Reference" "U" (at 30.48 -2.54 0)
        (effects (font (size 1.27 1.27) (thickness 0.15)) (justify left bottom))
      )
      (property "Value" "SN74LVC1G240_SC70" (at 30.48 -5.08 0)
        (effects (font (size 1.27 1.27) (thickness 0.15)) (justify left bottom))
      )
      (property "Footprint" "antmicro-footprints:SOT-353" (at 30.48 -7.62 0)
        (effects (font (size 1.27 1.27) (thickness 0.15)) (justify left bottom) hide)
      )
      (property "Datasheet" "https://www.ti.com/lit/ds/symlink/sn74lvc1g240.pdf?ts=1666621735933" (at 30.48 -10.16 0)
        (effects (font (size 1.27 1.27) (thickness 0.15)) (justify left bottom) hide)
      )
      (property "MPN" "SN74LVC1G240DCKR" (at 30.48 -12.7 0)
        (effects (font (size 1.27 1.27) (thickness 0.15)) (justify left bottom) hide)
      )
      (property "Manufacturer" "Texas Instruments" (at 30.48 -15.24 0)
        (effects (font (size 1.27 1.27) (thickness 0.15)) (justify left bottom) hide)
      )
      (property "Author" "Antmicro" (at 30.48 -17.78 0)
        (effects (font (size 1.27 1.27) (thickness 0.15)) (justify left bottom) hide)
      )
      (property "License" "Apache-2.0" (at 30.48 -20.32 0)
        (effects (font (size 1.27 1.27) (thickness 0.15)) (justify left bottom) hide)
      )
      (property "ki_description" "Single Inverting Buffer/Driver With 3-State Output" (at 0 0 0)
        (effects (font (size 1.27 1.27)) hide)
      )
      (symbol "SN74LVC1G240_SC70_1_1"
        (polyline
          (pts
            (xy 6.35 -3.81)
            (xy 4.445 -3.81)
          )
          (stroke (width 0.254) (type default))
          (fill (type background))
        )
        (polyline
          (pts
            (xy 11.43 -3.81)
            (xy 13.335 -3.81)
          )
          (stroke (width 0.254) (type default))
          (fill (type background))
        )
        (polyline
          (pts
            (xy 5.715 -7.62)
            (xy 7.62 -7.62)
            (xy 7.62 -6.35)
          )
          (stroke (width 0.254) (type default))
          (fill (type background))
        )
        (polyline
          (pts
            (xy 6.35 -1.27)
            (xy 11.43 -3.81)
            (xy 6.35 -6.35)
            (xy 6.35 -1.27)
          )
          (stroke (width 0.254) (type default))
          (fill (type background))
        )
        (rectangle (start 2.54 2.54) (end 15.24 -10.16)
          (stroke (width 0.254) (type default))
          (fill (type background))
        )
        (circle (center 7.62 -6.096) (radius 0.284)
          (stroke (width 0.254) (type default))
          (fill (type background))
        )
        (pin input line (at 0 -7.62 0) (length 2.54)
          (name "~{OE}" (effects (font (size 1.27 1.27))))
          (number "1" (effects (font (size 1.27 1.27))))
        )
        (pin input line (at 0 -3.81 0) (length 2.54)
          (name "A" (effects (font (size 1.27 1.27))))
          (number "2" (effects (font (size 1.27 1.27))))
        )
        (pin power_in line (at 17.78 -7.62 180) (length 2.54)
          (name "GND" (effects (font (size 1.27 1.27))))
          (number "3" (effects (font (size 1.27 1.27))))
        )
        (pin output line (at 17.78 -3.81 180) (length 2.54)
          (name "Y" (effects (font (size 1.27 1.27))))
          (number "4" (effects (font (size 1.27 1.27))))
        )
        (pin power_in line (at 0 0 0) (length 2.54)
          (name "V_{CC}" (effects (font (size 1.27 1.27))))
          (number "5" (effects (font (size 1.27 1.27))))
        )
      )
    )
	(symbol "antmicroLogicSignalSwitchesMultiplexersDecoders:TS3L500RHUR" (in_bom yes) (on_board yes)
      (property "Reference" "U" (at 40.64 -5.08 0)
        (effects (font (size 1.27 1.27) (thickness 0.15)) (justify left bottom))
      )
      (property "Value" "TS3L500RHUR" (at 40.64 -7.62 0)
        (effects (font (size 1.27 1.27) (thickness 0.15)) (justify left bottom))
      )
      (property "Footprint" "antmicro-footprints:WQFN-56-1EP_5x11x1mm_P0.5mm" (at 40.64 -10.16 0)
        (effects (font (size 1.27 1.27) (thickness 0.15)) (justify left bottom) hide)
      )
      (property "Datasheet" "https://www.ti.com/lit/ds/symlink/ts3l500.pdf?ts=1663940859045&ref_url=https%253A%252F%252Fwww.google.com%252F" (at 40.64 -12.7 0)
        (effects (font (size 1.27 1.27) (thickness 0.15)) (justify left bottom) hide)
      )
      (property "Manufacturer" "Texas Instruments" (at 40.64 -15.24 0)
        (effects (font (size 1.27 1.27) (thickness 0.15)) (justify left bottom) hide)
      )
      (property "MPN" "TS3L500RHUR" (at 40.64 -17.78 0)
        (effects (font (size 1.27 1.27) (thickness 0.15)) (justify left bottom) hide)
      )
      (property "Author" "Antmicro" (at 40.64 -20.32 0)
        (effects (font (size 1.27 1.27) (thickness 0.15)) (justify left bottom) hide)
      )
      (property "License" "Apache-2.0" (at 40.64 -22.86 0)
        (effects (font (size 1.27 1.27) (thickness 0.15)) (justify left bottom) hide)
      )
      (property "ki_description" "3.3-V, 2:1 (SPDT), 8-channel gigachannel LAN switch with LED switch & enhanced ESD protection" (at 0 0 0)
        (effects (font (size 1.27 1.27)) hide)
      )
      (property "ki_fp_filters" "RHU56_8P4X2P4" (at 0 0 0)
        (effects (font (size 1.27 1.27)) hide)
      )
      (symbol "TS3L500RHUR_1_1"
        (rectangle (start 2.54 2.54) (end 24.13 -69.85)
          (stroke (width 0.254) (type default))
          (fill (type background))
        )
        (pin power_in line (at 0 -67.31 0) (length 2.54)
          (name "GND" (effects (font (size 1.27 1.27))))
          (number "1" (effects (font (size 1.27 1.27))))
        )
        (pin power_in line (at 0 0 0) (length 2.54)
          (name "VCC" (effects (font (size 1.27 1.27))))
          (number "10" (effects (font (size 1.27 1.27))))
        )
        (pin bidirectional line (at 0 -25.4 0) (length 2.54)
          (name "A4" (effects (font (size 1.27 1.27))))
          (number "11" (effects (font (size 1.27 1.27))))
        )
        (pin bidirectional line (at 0 -27.94 0) (length 2.54)
          (name "A5" (effects (font (size 1.27 1.27))))
          (number "12" (effects (font (size 1.27 1.27))))
        )
        (pin passive line (at 0 -67.31 0) (length 2.54) hide
          (name "GND" (effects (font (size 1.27 1.27))))
          (number "13" (effects (font (size 1.27 1.27))))
        )
        (pin bidirectional line (at 0 -33.02 0) (length 2.54)
          (name "A6" (effects (font (size 1.27 1.27))))
          (number "14" (effects (font (size 1.27 1.27))))
        )
        (pin bidirectional line (at 0 -35.56 0) (length 2.54)
          (name "A7" (effects (font (size 1.27 1.27))))
          (number "15" (effects (font (size 1.27 1.27))))
        )
        (pin passive line (at 0 -67.31 0) (length 2.54) hide
          (name "GND" (effects (font (size 1.27 1.27))))
          (number "16" (effects (font (size 1.27 1.27))))
        )
        (pin input line (at 0 -5.08 0) (length 2.54)
          (name "SEL" (effects (font (size 1.27 1.27))))
          (number "17" (effects (font (size 1.27 1.27))))
        )
        (pin passive line (at 0 0 0) (length 2.54) hide
          (name "VCC" (effects (font (size 1.27 1.27))))
          (number "18" (effects (font (size 1.27 1.27))))
        )
        (pin bidirectional line (at 0 -49.53 0) (length 2.54)
          (name "LED0" (effects (font (size 1.27 1.27))))
          (number "19" (effects (font (size 1.27 1.27))))
        )
        (pin bidirectional line (at 0 -10.16 0) (length 2.54)
          (name "A0" (effects (font (size 1.27 1.27))))
          (number "2" (effects (font (size 1.27 1.27))))
        )
        (pin bidirectional line (at 0 -52.07 0) (length 2.54)
          (name "LED1" (effects (font (size 1.27 1.27))))
          (number "20" (effects (font (size 1.27 1.27))))
        )
        (pin passive line (at 0 -67.31 0) (length 2.54) hide
          (name "GND" (effects (font (size 1.27 1.27))))
          (number "21" (effects (font (size 1.27 1.27))))
        )
        (pin bidirectional line (at 26.67 -25.4 180) (length 2.54)
          (name "0LED1" (effects (font (size 1.27 1.27))))
          (number "22" (effects (font (size 1.27 1.27))))
        )
        (pin bidirectional line (at 26.67 -27.94 180) (length 2.54)
          (name "1LED1" (effects (font (size 1.27 1.27))))
          (number "23" (effects (font (size 1.27 1.27))))
        )
        (pin passive line (at 0 -67.31 0) (length 2.54) hide
          (name "GND" (effects (font (size 1.27 1.27))))
          (number "24" (effects (font (size 1.27 1.27))))
        )
        (pin bidirectional line (at 26.67 -62.23 180) (length 2.54)
          (name "0LED2" (effects (font (size 1.27 1.27))))
          (number "25" (effects (font (size 1.27 1.27))))
        )
        (pin bidirectional line (at 26.67 -64.77 180) (length 2.54)
          (name "1LED2" (effects (font (size 1.27 1.27))))
          (number "26" (effects (font (size 1.27 1.27))))
        )
        (pin passive line (at 0 0 0) (length 2.54) hide
          (name "VCC" (effects (font (size 1.27 1.27))))
          (number "27" (effects (font (size 1.27 1.27))))
        )
        (pin passive line (at 0 -67.31 0) (length 2.54) hide
          (name "GND" (effects (font (size 1.27 1.27))))
          (number "28" (effects (font (size 1.27 1.27))))
        )
        (pin bidirectional line (at 26.67 -57.15 180) (length 2.54)
          (name "7B2" (effects (font (size 1.27 1.27))))
          (number "29" (effects (font (size 1.27 1.27))))
        )
        (pin bidirectional line (at 0 -12.7 0) (length 2.54)
          (name "A1" (effects (font (size 1.27 1.27))))
          (number "3" (effects (font (size 1.27 1.27))))
        )
        (pin bidirectional line (at 26.67 -54.61 180) (length 2.54)
          (name "6B2" (effects (font (size 1.27 1.27))))
          (number "30" (effects (font (size 1.27 1.27))))
        )
        (pin bidirectional line (at 26.67 -21.59 180) (length 2.54)
          (name "7B1" (effects (font (size 1.27 1.27))))
          (number "31" (effects (font (size 1.27 1.27))))
        )
        (pin bidirectional line (at 26.67 -19.05 180) (length 2.54)
          (name "6B1" (effects (font (size 1.27 1.27))))
          (number "32" (effects (font (size 1.27 1.27))))
        )
        (pin passive line (at 0 -67.31 0) (length 2.54) hide
          (name "GND" (effects (font (size 1.27 1.27))))
          (number "33" (effects (font (size 1.27 1.27))))
        )
        (pin bidirectional line (at 26.67 -50.8 180) (length 2.54)
          (name "5B2" (effects (font (size 1.27 1.27))))
          (number "34" (effects (font (size 1.27 1.27))))
        )
        (pin bidirectional line (at 26.67 -48.26 180) (length 2.54)
          (name "4B2" (effects (font (size 1.27 1.27))))
          (number "35" (effects (font (size 1.27 1.27))))
        )
        (pin bidirectional line (at 26.67 -15.24 180) (length 2.54)
          (name "5B1" (effects (font (size 1.27 1.27))))
          (number "36" (effects (font (size 1.27 1.27))))
        )
        (pin bidirectional line (at 26.67 -12.7 180) (length 2.54)
          (name "4B1" (effects (font (size 1.27 1.27))))
          (number "37" (effects (font (size 1.27 1.27))))
        )
        (pin passive line (at 0 0 0) (length 2.54) hide
          (name "VCC" (effects (font (size 1.27 1.27))))
          (number "38" (effects (font (size 1.27 1.27))))
        )
        (pin passive line (at 0 -67.31 0) (length 2.54) hide
          (name "GND" (effects (font (size 1.27 1.27))))
          (number "39" (effects (font (size 1.27 1.27))))
        )
        (pin passive line (at 0 0 0) (length 2.54) hide
          (name "VCC" (effects (font (size 1.27 1.27))))
          (number "4" (effects (font (size 1.27 1.27))))
        )
        (pin bidirectional line (at 26.67 -44.45 180) (length 2.54)
          (name "3B2" (effects (font (size 1.27 1.27))))
          (number "40" (effects (font (size 1.27 1.27))))
        )
        (pin bidirectional line (at 26.67 -41.91 180) (length 2.54)
          (name "2B2" (effects (font (size 1.27 1.27))))
          (number "41" (effects (font (size 1.27 1.27))))
        )
        (pin bidirectional line (at 26.67 -8.89 180) (length 2.54)
          (name "3B1" (effects (font (size 1.27 1.27))))
          (number "42" (effects (font (size 1.27 1.27))))
        )
        (pin bidirectional line (at 26.67 -6.35 180) (length 2.54)
          (name "2B1" (effects (font (size 1.27 1.27))))
          (number "43" (effects (font (size 1.27 1.27))))
        )
        (pin passive line (at 0 -67.31 0) (length 2.54) hide
          (name "GND" (effects (font (size 1.27 1.27))))
          (number "44" (effects (font (size 1.27 1.27))))
        )
        (pin bidirectional line (at 26.67 -38.1 180) (length 2.54)
          (name "1B2" (effects (font (size 1.27 1.27))))
          (number "45" (effects (font (size 1.27 1.27))))
        )
        (pin bidirectional line (at 26.67 -35.56 180) (length 2.54)
          (name "0B2" (effects (font (size 1.27 1.27))))
          (number "46" (effects (font (size 1.27 1.27))))
        )
        (pin bidirectional line (at 26.67 -2.54 180) (length 2.54)
          (name "1B1" (effects (font (size 1.27 1.27))))
          (number "47" (effects (font (size 1.27 1.27))))
        )
        (pin bidirectional line (at 26.67 0 180) (length 2.54)
          (name "0B1" (effects (font (size 1.27 1.27))))
          (number "48" (effects (font (size 1.27 1.27))))
        )
        (pin passive line (at 0 -67.31 0) (length 2.54) hide
          (name "GND" (effects (font (size 1.27 1.27))))
          (number "49" (effects (font (size 1.27 1.27))))
        )
        (pin no_connect line (at 2.54 -59.69 0) (length 2.54) hide
          (name "NC" (effects (font (size 1.27 1.27))))
          (number "5" (effects (font (size 1.27 1.27))))
        )
        (pin passive line (at 0 0 0) (length 2.54) hide
          (name "VCC" (effects (font (size 1.27 1.27))))
          (number "50" (effects (font (size 1.27 1.27))))
        )
        (pin bidirectional line (at 26.67 -67.31 180) (length 2.54)
          (name "2LED2" (effects (font (size 1.27 1.27))))
          (number "51" (effects (font (size 1.27 1.27))))
        )
        (pin bidirectional line (at 26.67 -30.48 180) (length 2.54)
          (name "2LED1" (effects (font (size 1.27 1.27))))
          (number "52" (effects (font (size 1.27 1.27))))
        )
        (pin passive line (at 0 -67.31 0) (length 2.54) hide
          (name "GND" (effects (font (size 1.27 1.27))))
          (number "53" (effects (font (size 1.27 1.27))))
        )
        (pin bidirectional line (at 0 -54.61 0) (length 2.54)
          (name "LED2" (effects (font (size 1.27 1.27))))
          (number "54" (effects (font (size 1.27 1.27))))
        )
        (pin passive line (at 0 -67.31 0) (length 2.54) hide
          (name "GND" (effects (font (size 1.27 1.27))))
          (number "55" (effects (font (size 1.27 1.27))))
        )
        (pin passive line (at 0 0 0) (length 2.54) hide
          (name "VCC" (effects (font (size 1.27 1.27))))
          (number "56" (effects (font (size 1.27 1.27))))
        )
        (pin unspecified line (at 0 -64.77 0) (length 2.54)
          (name "EP" (effects (font (size 1.27 1.27))))
          (number "57" (effects (font (size 1.27 1.27))))
        )
        (pin passive line (at 0 -67.31 0) (length 2.54) hide
          (name "GND" (effects (font (size 1.27 1.27))))
          (number "6" (effects (font (size 1.27 1.27))))
        )
        (pin bidirectional line (at 0 -17.78 0) (length 2.54)
          (name "A2" (effects (font (size 1.27 1.27))))
          (number "7" (effects (font (size 1.27 1.27))))
        )
        (pin bidirectional line (at 0 -20.32 0) (length 2.54)
          (name "A3" (effects (font (size 1.27 1.27))))
          (number "8" (effects (font (size 1.27 1.27))))
        )
        (pin passive line (at 0 -67.31 0) (length 2.54) hide
          (name "GND" (effects (font (size 1.27 1.27))))
          (number "9" (effects (font (size 1.27 1.27))))
        )
      )
    )
	(symbol "antmicroLogicTranslatorsLevelShifters:PCA9517A_TSSOP" (in_bom yes) (on_board yes)
      (property "Reference" "U" (at 33.02 -2.54 0)
        (effects (font (size 1.27 1.27) (thickness 0.15)) (justify left bottom))
      )
      (property "Value" "PCA9517A_TSSOP" (at 33.02 -5.08 0)
        (effects (font (size 1.27 1.27) (thickness 0.15)) (justify left bottom))
      )
      (property "Footprint" "antmicro-footprints:TSSOP-8_3x3mm_P0.65mm" (at 33.02 -7.62 0)
        (effects (font (size 1.27 1.27) (thickness 0.15)) (justify left bottom) hide)
      )
      (property "Datasheet" "https://www.mouser.pl/datasheet/2/308/1/ONSM_S_A0009688870_1-2560458.pdf" (at 33.02 -10.16 0)
        (effects (font (size 1.27 1.27) (thickness 0.15)) (justify left bottom) hide)
      )
      (property "MPN" "PCA9517ADMR2G" (at 33.02 -12.7 0)
        (effects (font (size 1.27 1.27) (thickness 0.15)) (justify left bottom) hide)
      )
      (property "Manufacturer" "ON Semiconductor" (at 33.02 -15.24 0)
        (effects (font (size 1.27 1.27) (thickness 0.15)) (justify left bottom) hide)
      )
      (property "Author" "Antmicro" (at 33.02 -17.78 0)
        (effects (font (size 1.27 1.27) (thickness 0.15)) (justify left bottom) hide)
      )
      (property "License" "Apache-2.0" (at 33.02 -20.32 0)
        (effects (font (size 1.27 1.27) (thickness 0.15)) (justify left bottom) hide)
      )
      (property "ki_keywords" "Translation - Voltage Levels LEVEL TRANSLATING I2" (at 0 0 0)
        (effects (font (size 1.27 1.27)) hide)
      )
      (property "ki_description" "Translation - Voltage Levels LEVEL TRANSLATING I2" (at 0 0 0)
        (effects (font (size 1.27 1.27)) hide)
      )
      (symbol "PCA9517A_TSSOP_1_1"
        (rectangle (start 2.54 2.54) (end 16.51 -15.24)
          (stroke (width 0.254) (type default))
          (fill (type background))
        )
        (pin power_in line (at 0 0 0) (length 2.54)
          (name "VREF_{1}" (effects (font (size 1.27 1.27))))
          (number "1" (effects (font (size 1.27 1.27))))
        )
        (pin bidirectional line (at 0 -6.35 0) (length 2.54)
          (name "SCL_{1}" (effects (font (size 1.27 1.27))))
          (number "2" (effects (font (size 1.27 1.27))))
        )
        (pin bidirectional line (at 0 -8.89 0) (length 2.54)
          (name "SDA_{1}" (effects (font (size 1.27 1.27))))
          (number "3" (effects (font (size 1.27 1.27))))
        )
        (pin power_in line (at 0 -12.7 0) (length 2.54)
          (name "GND" (effects (font (size 1.27 1.27))))
          (number "4" (effects (font (size 1.27 1.27))))
        )
        (pin input line (at 0 -2.54 0) (length 2.54)
          (name "EN" (effects (font (size 1.27 1.27))))
          (number "5" (effects (font (size 1.27 1.27))))
        )
        (pin bidirectional line (at 19.05 -8.89 180) (length 2.54)
          (name "SDA_{2}" (effects (font (size 1.27 1.27))))
          (number "6" (effects (font (size 1.27 1.27))))
        )
        (pin bidirectional line (at 19.05 -6.35 180) (length 2.54)
          (name "SCL_{2}" (effects (font (size 1.27 1.27))))
          (number "7" (effects (font (size 1.27 1.27))))
        )
        (pin power_in line (at 19.05 0 180) (length 2.54)
          (name "VREF_{2}" (effects (font (size 1.27 1.27))))
          (number "8" (effects (font (size 1.27 1.27))))
        )
      )
    )
	(symbol "antmicroMechanicalParts:antmicro_logo" (in_bom yes) (on_board yes)
      (property "Reference" "N" (at 15.24 -5.08 0)
        (effects (font (size 1.27 1.27) (thickness 0.15)) (justify left bottom))
      )
      (property "Value" "antmicro_logo" (at 15.24 -7.62 0)
        (effects (font (size 1.27 1.27) (thickness 0.15)) (justify left bottom))
      )
      (property "Footprint" "antmicro-footprints:antmicro-logo" (at 15.24 -10.16 0)
        (effects (font (size 1.27 1.27) (thickness 0.15)) (justify left bottom) hide)
      )
      (property "Datasheet" "" (at 15.24 -12.7 0)
        (effects (font (size 1.27 1.27) (thickness 0.15)) (justify left bottom) hide)
      )
      (property "MPN" "" (at 0 0 0)
        (effects (font (size 1.27 1.27)) hide)
      )
      (property "Manufacturer" "" (at 15.24 -20.32 0)
        (effects (font (size 1.27 1.27) (thickness 0.15)) (justify left bottom) hide)
      )
      (property "Author" "Antmicro" (at 15.24 -15.24 0)
        (effects (font (size 1.27 1.27) (thickness 0.15)) (justify left bottom) hide)
      )
      (property "License" "Apache-2.0" (at 15.24 -17.78 0)
        (effects (font (size 1.27 1.27) (thickness 0.15)) (justify left bottom) hide)
      )
      (symbol "antmicro_logo_1_1"
        (text "Logo" (at 0 0 0)
          (effects (font (size 1.27 1.27) (thickness 0.15)) (justify left bottom))
        )
      )
    )
	(symbol "antmicroMechanicalParts:oshw_logo" (in_bom yes) (on_board yes)
      (property "Reference" "N" (at 15.24 -5.08 0)
        (effects (font (size 1.27 1.27) (thickness 0.15)) (justify left bottom))
      )
      (property "Value" "oshw_logo" (at 15.24 -7.62 0)
        (effects (font (size 1.27 1.27) (thickness 0.15)) (justify left bottom))
      )
      (property "Footprint" "antmicro-footprints:oshw-logo" (at 15.24 -10.16 0)
        (effects (font (size 1.27 1.27) (thickness 0.15)) (justify left bottom) hide)
      )
      (property "Datasheet" "" (at 15.24 -12.7 0)
        (effects (font (size 1.27 1.27) (thickness 0.15)) (justify left bottom) hide)
      )
      (property "Author" "Antmicro" (at 15.24 -15.24 0)
        (effects (font (size 1.27 1.27) (thickness 0.15)) (justify left bottom) hide)
      )
      (property "License" "Apache-2.0" (at 15.24 -17.78 0)
        (effects (font (size 1.27 1.27) (thickness 0.15)) (justify left bottom) hide)
      )
      (property "MPN" "" (at 0 0 0)
        (effects (font (size 1.27 1.27)) hide)
      )
      (property "Manufacturer" "" (at 15.24 -20.32 0)
        (effects (font (size 1.27 1.27) (thickness 0.15)) (justify left bottom) hide)
      )
      (symbol "oshw_logo_1_1"
        (text "Logo" (at 0 0 0)
          (effects (font (size 1.27 1.27) (thickness 0.15)) (justify left bottom))
        )
      )
    )
	(symbol "antmicroMemory:S25FL128SAGNFI000" (in_bom yes) (on_board yes)
      (property "Reference" "U" (at 45.72 -2.54 0)
        (effects (font (size 1.27 1.27) (thickness 0.15)) (justify left bottom))
      )
      (property "Value" "S25FL128SAGNFI000" (at 45.72 -5.08 0)
        (effects (font (size 1.27 1.27) (thickness 0.15)) (justify left bottom))
      )
      (property "Footprint" "antmicro-footprints:WSON-8_6x8x0.5mm_P1.27mm" (at 45.72 -7.62 0)
        (effects (font (size 1.27 1.27) (thickness 0.15)) (justify left bottom) hide)
      )
      (property "Datasheet" "https://www.farnell.com/datasheets/2309615.pdf" (at 45.72 -10.16 0)
        (effects (font (size 1.27 1.27) (thickness 0.15)) (justify left bottom) hide)
      )
      (property "MPN" "S25FL128SAGNFI000" (at 45.72 -15.24 0)
        (effects (font (size 1.27 1.27) (thickness 0.15)) (justify left bottom) hide)
      )
      (property "Manufacturer" "Cypress Semiconductor" (at 45.72 -12.7 0)
        (effects (font (size 1.27 1.27) (thickness 0.15)) (justify left bottom) hide)
      )
      (property "Author" "Antmicro" (at 45.72 -17.78 0)
        (effects (font (size 1.27 1.27) (thickness 0.15)) (justify left bottom) hide)
      )
      (property "License" "Apache-2.0" (at 45.72 -20.32 0)
        (effects (font (size 1.27 1.27) (thickness 0.15)) (justify left bottom) hide)
      )
      (property "ki_keywords" "28 Mbit (16 Mbyte)/256 Mbit (32 Mbyte), 3.0V SPI Flash Memory" (at 0 0 0)
        (effects (font (size 1.27 1.27)) hide)
      )
      (property "ki_description" "28 Mbit (16 Mbyte)/256 Mbit (32 Mbyte), 3.0V SPI Flash Memory" (at 0 0 0)
        (effects (font (size 1.27 1.27)) hide)
      )
      (symbol "S25FL128SAGNFI000_1_1"
        (rectangle (start 2.54 0) (end 17.78 -17.78)
          (stroke (width 0.254) (type default))
          (fill (type background))
        )
        (pin input line (at 0 -15.24 0) (length 2.54)
          (name "~{CS}" (effects (font (size 1.27 1.27))))
          (number "1" (effects (font (size 1.27 1.27))))
        )
        (pin bidirectional line (at 0 -5.08 0) (length 2.54)
          (name "SO/IO1" (effects (font (size 1.27 1.27))))
          (number "2" (effects (font (size 1.27 1.27))))
        )
        (pin bidirectional line (at 0 -7.62 0) (length 2.54)
          (name "~{WP}/IO2" (effects (font (size 1.27 1.27))))
          (number "3" (effects (font (size 1.27 1.27))))
        )
        (pin power_in line (at 20.32 -15.24 180) (length 2.54)
          (name "V_{SS}" (effects (font (size 1.27 1.27))))
          (number "4" (effects (font (size 1.27 1.27))))
        )
        (pin bidirectional line (at 0 -2.54 0) (length 2.54)
          (name "SI/IO0" (effects (font (size 1.27 1.27))))
          (number "5" (effects (font (size 1.27 1.27))))
        )
        (pin input line (at 0 -12.7 0) (length 2.54)
          (name "SCK" (effects (font (size 1.27 1.27))))
          (number "6" (effects (font (size 1.27 1.27))))
        )
        (pin bidirectional line (at 0 -10.16 0) (length 2.54)
          (name "~{HOLD}/IO3" (effects (font (size 1.27 1.27))))
          (number "7" (effects (font (size 1.27 1.27))))
        )
        (pin power_in line (at 20.32 -2.54 180) (length 2.54)
          (name "V_{CC}" (effects (font (size 1.27 1.27))))
          (number "8" (effects (font (size 1.27 1.27))))
        )
        (pin no_connect line (at 17.78 -12.7 180) (length 2.54) hide
          (name "EP" (effects (font (size 1.27 1.27))))
          (number "9" (effects (font (size 1.27 1.27))))
        )
      )
    )
	(symbol "antmicroMemory:S27KL0641DABHI023" (in_bom yes) (on_board yes)
      (property "Reference" "U" (at 45.72 -5.08 0)
        (effects (font (size 1.27 1.27) (thickness 0.15)) (justify left bottom))
      )
      (property "Value" "S27KL0641DABHI023" (at 45.72 -7.62 0)
        (effects (font (size 1.27 1.27) (thickness 0.15)) (justify left bottom))
      )
      (property "Footprint" "antmicro-footprints:FBGA-25-24_6x8mm_Layout5x5_P1mm" (at 45.72 -10.16 0)
        (effects (font (size 1.27 1.27) (thickness 0.15)) (justify left bottom) hide)
      )
      (property "Datasheet" "https://www.mouser.pl/datasheet/2/196/CYPR_S_A0011122227_1-3004854.pdf" (at 45.72 -12.7 0)
        (effects (font (size 1.27 1.27) (thickness 0.15)) (justify left bottom) hide)
      )
      (property "Manufacturer" "Cypress Semiconductor" (at 45.72 -15.24 0)
        (effects (font (size 1.27 1.27) (thickness 0.15)) (justify left bottom) hide)
      )
      (property "MPN" "S27KL0641DABHI023" (at 45.72 -17.78 0)
        (effects (font (size 1.27 1.27) (thickness 0.15)) (justify left bottom) hide)
      )
      (property "Author" "Antmicro" (at 45.72 -20.32 0)
        (effects (font (size 1.27 1.27) (thickness 0.15)) (justify left bottom) hide)
      )
      (property "License" "Apache-2.0" (at 45.72 -22.86 0)
        (effects (font (size 1.27 1.27) (thickness 0.15)) (justify left bottom) hide)
      )
      (symbol "S27KL0641DABHI023_1_1"
        (rectangle (start 2.54 2.54) (end 27.94 -40.64)
          (stroke (width 0.254) (type default))
          (fill (type background))
        )
        (rectangle (start 7.62 -1.27) (end 7.62 -1.27)
          (stroke (width 0.254) (type default))
          (fill (type background))
        )
        (rectangle (start 11.43 -38.1) (end 11.43 -38.1)
          (stroke (width 0.254) (type default))
          (fill (type background))
        )
        (pin no_connect line (at 27.94 -30.48 180) (length 2.54) hide
          (name "NC" (effects (font (size 1.27 1.27))))
          (number "A2" (effects (font (size 1.27 1.27))))
        )
        (pin input line (at 0 -2.54 0) (length 2.54)
          (name "~{CS}" (effects (font (size 1.27 1.27))))
          (number "A3" (effects (font (size 1.27 1.27))))
        )
        (pin input line (at 0 0 0) (length 2.54)
          (name "~{RESET}" (effects (font (size 1.27 1.27))))
          (number "A4" (effects (font (size 1.27 1.27))))
        )
        (pin no_connect line (at 27.94 -30.48 180) (length 2.54) hide
          (name "NC" (effects (font (size 1.27 1.27))))
          (number "A5" (effects (font (size 1.27 1.27))))
        )
        (pin input line (at 0 -10.16 0) (length 2.54)
          (name "CK-" (effects (font (size 1.27 1.27))))
          (number "B1" (effects (font (size 1.27 1.27))))
        )
        (pin input line (at 0 -7.62 0) (length 2.54)
          (name "CK+" (effects (font (size 1.27 1.27))))
          (number "B2" (effects (font (size 1.27 1.27))))
        )
        (pin power_in line (at 30.48 -38.1 180) (length 2.54)
          (name "VSS" (effects (font (size 1.27 1.27))))
          (number "B3" (effects (font (size 1.27 1.27))))
        )
        (pin power_in line (at 30.48 0 180) (length 2.54)
          (name "VCC" (effects (font (size 1.27 1.27))))
          (number "B4" (effects (font (size 1.27 1.27))))
        )
        (pin no_connect line (at 27.94 -30.48 180) (length 2.54) hide
          (name "NC" (effects (font (size 1.27 1.27))))
          (number "B5" (effects (font (size 1.27 1.27))))
        )
        (pin power_in line (at 30.48 -35.56 180) (length 2.54)
          (name "VSSQ" (effects (font (size 1.27 1.27))))
          (number "C1" (effects (font (size 1.27 1.27))))
        )
        (pin no_connect line (at 27.94 -30.48 180) (length 2.54) hide
          (name "NC" (effects (font (size 1.27 1.27))))
          (number "C2" (effects (font (size 1.27 1.27))))
        )
        (pin bidirectional line (at 0 -38.1 0) (length 2.54)
          (name "RWDS" (effects (font (size 1.27 1.27))))
          (number "C3" (effects (font (size 1.27 1.27))))
        )
        (pin bidirectional line (at 0 -20.32 0) (length 2.54)
          (name "DQ2" (effects (font (size 1.27 1.27))))
          (number "C4" (effects (font (size 1.27 1.27))))
        )
        (pin no_connect line (at 27.94 -30.48 180) (length 2.54) hide
          (name "NC" (effects (font (size 1.27 1.27))))
          (number "C5" (effects (font (size 1.27 1.27))))
        )
        (pin power_in line (at 30.48 -2.54 180) (length 2.54)
          (name "VCCQ" (effects (font (size 1.27 1.27))))
          (number "D1" (effects (font (size 1.27 1.27))))
        )
        (pin bidirectional line (at 0 -17.78 0) (length 2.54)
          (name "DQ1" (effects (font (size 1.27 1.27))))
          (number "D2" (effects (font (size 1.27 1.27))))
        )
        (pin bidirectional line (at 0 -15.24 0) (length 2.54)
          (name "DQ0" (effects (font (size 1.27 1.27))))
          (number "D3" (effects (font (size 1.27 1.27))))
        )
        (pin bidirectional line (at 0 -22.86 0) (length 2.54)
          (name "DQ3" (effects (font (size 1.27 1.27))))
          (number "D4" (effects (font (size 1.27 1.27))))
        )
        (pin bidirectional line (at 0 -25.4 0) (length 2.54)
          (name "DQ4" (effects (font (size 1.27 1.27))))
          (number "D5" (effects (font (size 1.27 1.27))))
        )
        (pin bidirectional line (at 0 -33.02 0) (length 2.54)
          (name "DQ7" (effects (font (size 1.27 1.27))))
          (number "E1" (effects (font (size 1.27 1.27))))
        )
        (pin bidirectional line (at 0 -30.48 0) (length 2.54)
          (name "DQ6" (effects (font (size 1.27 1.27))))
          (number "E2" (effects (font (size 1.27 1.27))))
        )
        (pin bidirectional line (at 0 -27.94 0) (length 2.54)
          (name "DQ5" (effects (font (size 1.27 1.27))))
          (number "E3" (effects (font (size 1.27 1.27))))
        )
        (pin passive line (at 30.48 -2.54 180) (length 2.54) hide
          (name "VCCQ" (effects (font (size 1.27 1.27))))
          (number "E4" (effects (font (size 1.27 1.27))))
        )
        (pin passive line (at 30.48 -35.56 180) (length 2.54) hide
          (name "VSSQ" (effects (font (size 1.27 1.27))))
          (number "E5" (effects (font (size 1.27 1.27))))
        )
      )
    )
	(symbol "antmicroMemoryConnectorsPCCardSockets:Bus_DDR4_2199155-1" (in_bom yes) (on_board yes)
      (property "Reference" "U" (at 49.53 -2.54 0)
        (effects (font (size 1.27 1.27) (thickness 0.15)) (justify left bottom))
      )
      (property "Value" "Bus_DDR4_2199155-1" (at 49.53 -5.08 0)
        (effects (font (size 1.27 1.27) (thickness 0.15)) (justify left bottom))
      )
      (property "Footprint" "antmicro-footprints:Bus_DDR4_Socket_DIMM_2199155-1" (at 49.53 -7.62 0)
        (effects (font (size 1.27 1.27) (thickness 0.15)) (justify left bottom) hide)
      )
      (property "Datasheet" "https://www.te.com/usa-en/product-2199155-1.datasheet.pdf" (at 49.53 -10.16 0)
        (effects (font (size 1.27 1.27) (thickness 0.15)) (justify left bottom) hide)
      )
      (property "Author" "Antmicro" (at 49.53 -12.7 0)
        (effects (font (size 1.27 1.27) (thickness 0.15)) (justify left bottom) hide)
      )
      (property "License" "Apache-2.0" (at 49.53 -15.24 0)
        (effects (font (size 1.27 1.27) (thickness 0.15)) (justify left bottom) hide)
      )
      (property "MPN" "2199155-1" (at 55.88 -20.32 0)
        (effects (font (size 1.27 1.27)) hide)
      )
      (property "Manufacturer" "TE Connectivity" (at 57.15 -17.78 0)
        (effects (font (size 1.27 1.27)) hide)
      )
      (property "ki_locked" "" (at 0 0 0)
        (effects (font (size 1.27 1.27)))
      )
      (property "ki_description" "DDR4 RDIMM 288 Pin SMT type" (at 0 0 0)
        (effects (font (size 1.27 1.27)) hide)
      )
      (symbol "Bus_DDR4_2199155-1_1_1"
        (rectangle (start 3.81 2.54) (end 26.67 -163.83)
          (stroke (width 0.254) (type default))
          (fill (type background))
        )
        (pin passive line (at 0 -15.24 0) (length 3.81)
          (name "DQ6" (effects (font (size 1.27 1.27))))
          (number "10" (effects (font (size 1.27 1.27))))
        )
        (pin passive line (at 30.48 -27.94 180) (length 3.81)
          (name "DQS13_c" (effects (font (size 1.27 1.27))))
          (number "100" (effects (font (size 1.27 1.27))))
        )
        (pin passive line (at 30.48 -15.24 180) (length 3.81)
          (name "DQ38" (effects (font (size 1.27 1.27))))
          (number "102" (effects (font (size 1.27 1.27))))
        )
        (pin passive line (at 30.48 -5.08 180) (length 3.81)
          (name "DQ34" (effects (font (size 1.27 1.27))))
          (number "104" (effects (font (size 1.27 1.27))))
        )
        (pin passive line (at 30.48 -41.91 180) (length 3.81)
          (name "DQ44" (effects (font (size 1.27 1.27))))
          (number "106" (effects (font (size 1.27 1.27))))
        )
        (pin passive line (at 30.48 -31.75 180) (length 3.81)
          (name "DQ40" (effects (font (size 1.27 1.27))))
          (number "108" (effects (font (size 1.27 1.27))))
        )
        (pin passive line (at 30.48 -57.15 180) (length 3.81)
          (name "DQS14_t" (effects (font (size 1.27 1.27))))
          (number "110" (effects (font (size 1.27 1.27))))
        )
        (pin passive line (at 30.48 -59.69 180) (length 3.81)
          (name "DQS14_c" (effects (font (size 1.27 1.27))))
          (number "111" (effects (font (size 1.27 1.27))))
        )
        (pin passive line (at 30.48 -46.99 180) (length 3.81)
          (name "DQ46" (effects (font (size 1.27 1.27))))
          (number "113" (effects (font (size 1.27 1.27))))
        )
        (pin passive line (at 30.48 -36.83 180) (length 3.81)
          (name "DQ42" (effects (font (size 1.27 1.27))))
          (number "115" (effects (font (size 1.27 1.27))))
        )
        (pin passive line (at 30.48 -74.93 180) (length 3.81)
          (name "DQ52" (effects (font (size 1.27 1.27))))
          (number "117" (effects (font (size 1.27 1.27))))
        )
        (pin passive line (at 30.48 -64.77 180) (length 3.81)
          (name "DQ48" (effects (font (size 1.27 1.27))))
          (number "119" (effects (font (size 1.27 1.27))))
        )
        (pin passive line (at 0 -5.08 0) (length 3.81)
          (name "DQ2" (effects (font (size 1.27 1.27))))
          (number "12" (effects (font (size 1.27 1.27))))
        )
        (pin passive line (at 30.48 -90.17 180) (length 3.81)
          (name "DQS15_t" (effects (font (size 1.27 1.27))))
          (number "121" (effects (font (size 1.27 1.27))))
        )
        (pin passive line (at 30.48 -92.71 180) (length 3.81)
          (name "DQS15_c" (effects (font (size 1.27 1.27))))
          (number "122" (effects (font (size 1.27 1.27))))
        )
        (pin passive line (at 30.48 -80.01 180) (length 3.81)
          (name "DQ54" (effects (font (size 1.27 1.27))))
          (number "124" (effects (font (size 1.27 1.27))))
        )
        (pin passive line (at 30.48 -69.85 180) (length 3.81)
          (name "DQ50" (effects (font (size 1.27 1.27))))
          (number "126" (effects (font (size 1.27 1.27))))
        )
        (pin passive line (at 30.48 -107.95 180) (length 3.81)
          (name "DQ60" (effects (font (size 1.27 1.27))))
          (number "128" (effects (font (size 1.27 1.27))))
        )
        (pin passive line (at 30.48 -97.79 180) (length 3.81)
          (name "DQ56" (effects (font (size 1.27 1.27))))
          (number "130" (effects (font (size 1.27 1.27))))
        )
        (pin passive line (at 30.48 -123.19 180) (length 3.81)
          (name "DQS16_t" (effects (font (size 1.27 1.27))))
          (number "132" (effects (font (size 1.27 1.27))))
        )
        (pin passive line (at 30.48 -125.73 180) (length 3.81)
          (name "DQS16_c" (effects (font (size 1.27 1.27))))
          (number "133" (effects (font (size 1.27 1.27))))
        )
        (pin passive line (at 30.48 -113.03 180) (length 3.81)
          (name "DQ62" (effects (font (size 1.27 1.27))))
          (number "135" (effects (font (size 1.27 1.27))))
        )
        (pin passive line (at 30.48 -102.87 180) (length 3.81)
          (name "DQ58" (effects (font (size 1.27 1.27))))
          (number "137" (effects (font (size 1.27 1.27))))
        )
        (pin passive line (at 0 -43.18 0) (length 3.81)
          (name "DQ12" (effects (font (size 1.27 1.27))))
          (number "14" (effects (font (size 1.27 1.27))))
        )
        (pin passive line (at 0 -12.7 0) (length 3.81)
          (name "DQ5" (effects (font (size 1.27 1.27))))
          (number "148" (effects (font (size 1.27 1.27))))
        )
        (pin passive line (at 0 -2.54 0) (length 3.81)
          (name "DQ1" (effects (font (size 1.27 1.27))))
          (number "150" (effects (font (size 1.27 1.27))))
        )
        (pin passive line (at 0 -22.86 0) (length 3.81)
          (name "DQS0_c" (effects (font (size 1.27 1.27))))
          (number "152" (effects (font (size 1.27 1.27))))
        )
        (pin passive line (at 0 -20.32 0) (length 3.81)
          (name "DQS0_t" (effects (font (size 1.27 1.27))))
          (number "153" (effects (font (size 1.27 1.27))))
        )
        (pin passive line (at 0 -17.78 0) (length 3.81)
          (name "DQ7" (effects (font (size 1.27 1.27))))
          (number "155" (effects (font (size 1.27 1.27))))
        )
        (pin passive line (at 0 -7.62 0) (length 3.81)
          (name "DQ3" (effects (font (size 1.27 1.27))))
          (number "157" (effects (font (size 1.27 1.27))))
        )
        (pin passive line (at 0 -45.72 0) (length 3.81)
          (name "DQ13" (effects (font (size 1.27 1.27))))
          (number "159" (effects (font (size 1.27 1.27))))
        )
        (pin passive line (at 0 -33.02 0) (length 3.81)
          (name "DQ8" (effects (font (size 1.27 1.27))))
          (number "16" (effects (font (size 1.27 1.27))))
        )
        (pin passive line (at 0 -35.56 0) (length 3.81)
          (name "DQ9" (effects (font (size 1.27 1.27))))
          (number "161" (effects (font (size 1.27 1.27))))
        )
        (pin passive line (at 0 -55.88 0) (length 3.81)
          (name "DQS1_c" (effects (font (size 1.27 1.27))))
          (number "163" (effects (font (size 1.27 1.27))))
        )
        (pin passive line (at 0 -53.34 0) (length 3.81)
          (name "DQS_1_t" (effects (font (size 1.27 1.27))))
          (number "164" (effects (font (size 1.27 1.27))))
        )
        (pin passive line (at 0 -50.8 0) (length 3.81)
          (name "DQ15" (effects (font (size 1.27 1.27))))
          (number "166" (effects (font (size 1.27 1.27))))
        )
        (pin passive line (at 0 -40.64 0) (length 3.81)
          (name "DQ11" (effects (font (size 1.27 1.27))))
          (number "168" (effects (font (size 1.27 1.27))))
        )
        (pin passive line (at 0 -78.74 0) (length 3.81)
          (name "DQ21" (effects (font (size 1.27 1.27))))
          (number "170" (effects (font (size 1.27 1.27))))
        )
        (pin passive line (at 0 -68.58 0) (length 3.81)
          (name "DQ17" (effects (font (size 1.27 1.27))))
          (number "172" (effects (font (size 1.27 1.27))))
        )
        (pin passive line (at 0 -88.9 0) (length 3.81)
          (name "DQS2_c" (effects (font (size 1.27 1.27))))
          (number "174" (effects (font (size 1.27 1.27))))
        )
        (pin passive line (at 0 -86.36 0) (length 3.81)
          (name "DQS2_t" (effects (font (size 1.27 1.27))))
          (number "175" (effects (font (size 1.27 1.27))))
        )
        (pin passive line (at 0 -83.82 0) (length 3.81)
          (name "DQ23" (effects (font (size 1.27 1.27))))
          (number "177" (effects (font (size 1.27 1.27))))
        )
        (pin passive line (at 0 -73.66 0) (length 3.81)
          (name "DQ19" (effects (font (size 1.27 1.27))))
          (number "179" (effects (font (size 1.27 1.27))))
        )
        (pin passive line (at 0 -58.42 0) (length 3.81)
          (name "DQS10_t" (effects (font (size 1.27 1.27))))
          (number "18" (effects (font (size 1.27 1.27))))
        )
        (pin passive line (at 0 -111.76 0) (length 3.81)
          (name "DQ29" (effects (font (size 1.27 1.27))))
          (number "181" (effects (font (size 1.27 1.27))))
        )
        (pin passive line (at 0 -101.6 0) (length 3.81)
          (name "DQ25" (effects (font (size 1.27 1.27))))
          (number "183" (effects (font (size 1.27 1.27))))
        )
        (pin passive line (at 0 -121.92 0) (length 3.81)
          (name "DQS3_c" (effects (font (size 1.27 1.27))))
          (number "185" (effects (font (size 1.27 1.27))))
        )
        (pin passive line (at 0 -119.38 0) (length 3.81)
          (name "DQS3_t" (effects (font (size 1.27 1.27))))
          (number "186" (effects (font (size 1.27 1.27))))
        )
        (pin passive line (at 0 -116.84 0) (length 3.81)
          (name "DQ31" (effects (font (size 1.27 1.27))))
          (number "188" (effects (font (size 1.27 1.27))))
        )
        (pin passive line (at 0 -60.96 0) (length 3.81)
          (name "DQS10_c" (effects (font (size 1.27 1.27))))
          (number "19" (effects (font (size 1.27 1.27))))
        )
        (pin passive line (at 0 -106.68 0) (length 3.81)
          (name "DQ27" (effects (font (size 1.27 1.27))))
          (number "190" (effects (font (size 1.27 1.27))))
        )
        (pin passive line (at 0 -144.78 0) (length 3.81)
          (name "CB5" (effects (font (size 1.27 1.27))))
          (number "192" (effects (font (size 1.27 1.27))))
        )
        (pin passive line (at 0 -134.62 0) (length 3.81)
          (name "CB1" (effects (font (size 1.27 1.27))))
          (number "194" (effects (font (size 1.27 1.27))))
        )
        (pin passive line (at 0 -154.94 0) (length 3.81)
          (name "DQS8_c" (effects (font (size 1.27 1.27))))
          (number "196" (effects (font (size 1.27 1.27))))
        )
        (pin passive line (at 0 -152.4 0) (length 3.81)
          (name "DQS8_t" (effects (font (size 1.27 1.27))))
          (number "197" (effects (font (size 1.27 1.27))))
        )
        (pin passive line (at 0 -149.86 0) (length 3.81)
          (name "CB7" (effects (font (size 1.27 1.27))))
          (number "199" (effects (font (size 1.27 1.27))))
        )
        (pin passive line (at 0 -139.7 0) (length 3.81)
          (name "CB3" (effects (font (size 1.27 1.27))))
          (number "201" (effects (font (size 1.27 1.27))))
        )
        (pin passive line (at 0 -48.26 0) (length 3.81)
          (name "DQ14" (effects (font (size 1.27 1.27))))
          (number "21" (effects (font (size 1.27 1.27))))
        )
        (pin passive line (at 0 -38.1 0) (length 3.81)
          (name "DQ10" (effects (font (size 1.27 1.27))))
          (number "23" (effects (font (size 1.27 1.27))))
        )
        (pin passive line (at 30.48 -12.7 180) (length 3.81)
          (name "DQ37" (effects (font (size 1.27 1.27))))
          (number "240" (effects (font (size 1.27 1.27))))
        )
        (pin passive line (at 30.48 -2.54 180) (length 3.81)
          (name "DQ33" (effects (font (size 1.27 1.27))))
          (number "242" (effects (font (size 1.27 1.27))))
        )
        (pin passive line (at 30.48 -22.86 180) (length 3.81)
          (name "DQS4_c" (effects (font (size 1.27 1.27))))
          (number "244" (effects (font (size 1.27 1.27))))
        )
        (pin passive line (at 30.48 -20.32 180) (length 3.81)
          (name "DQS4_t" (effects (font (size 1.27 1.27))))
          (number "245" (effects (font (size 1.27 1.27))))
        )
        (pin passive line (at 30.48 -17.78 180) (length 3.81)
          (name "DQ39" (effects (font (size 1.27 1.27))))
          (number "247" (effects (font (size 1.27 1.27))))
        )
        (pin passive line (at 30.48 -7.62 180) (length 3.81)
          (name "DQ35" (effects (font (size 1.27 1.27))))
          (number "249" (effects (font (size 1.27 1.27))))
        )
        (pin passive line (at 0 -76.2 0) (length 3.81)
          (name "DQ20" (effects (font (size 1.27 1.27))))
          (number "25" (effects (font (size 1.27 1.27))))
        )
        (pin passive line (at 30.48 -44.45 180) (length 3.81)
          (name "DQ45" (effects (font (size 1.27 1.27))))
          (number "251" (effects (font (size 1.27 1.27))))
        )
        (pin passive line (at 30.48 -34.29 180) (length 3.81)
          (name "DQ41" (effects (font (size 1.27 1.27))))
          (number "253" (effects (font (size 1.27 1.27))))
        )
        (pin passive line (at 30.48 -54.61 180) (length 3.81)
          (name "DQS5_c" (effects (font (size 1.27 1.27))))
          (number "255" (effects (font (size 1.27 1.27))))
        )
        (pin passive line (at 30.48 -52.07 180) (length 3.81)
          (name "DQS5_t" (effects (font (size 1.27 1.27))))
          (number "256" (effects (font (size 1.27 1.27))))
        )
        (pin passive line (at 30.48 -49.53 180) (length 3.81)
          (name "DQ47" (effects (font (size 1.27 1.27))))
          (number "258" (effects (font (size 1.27 1.27))))
        )
        (pin passive line (at 30.48 -39.37 180) (length 3.81)
          (name "DQ43" (effects (font (size 1.27 1.27))))
          (number "260" (effects (font (size 1.27 1.27))))
        )
        (pin passive line (at 30.48 -77.47 180) (length 3.81)
          (name "DQ53" (effects (font (size 1.27 1.27))))
          (number "262" (effects (font (size 1.27 1.27))))
        )
        (pin passive line (at 30.48 -67.31 180) (length 3.81)
          (name "DQ49" (effects (font (size 1.27 1.27))))
          (number "264" (effects (font (size 1.27 1.27))))
        )
        (pin passive line (at 30.48 -87.63 180) (length 3.81)
          (name "DQS6_c" (effects (font (size 1.27 1.27))))
          (number "266" (effects (font (size 1.27 1.27))))
        )
        (pin passive line (at 30.48 -85.09 180) (length 3.81)
          (name "DQS6_t" (effects (font (size 1.27 1.27))))
          (number "267" (effects (font (size 1.27 1.27))))
        )
        (pin passive line (at 30.48 -82.55 180) (length 3.81)
          (name "DQ55" (effects (font (size 1.27 1.27))))
          (number "269" (effects (font (size 1.27 1.27))))
        )
        (pin passive line (at 0 -66.04 0) (length 3.81)
          (name "DQ16" (effects (font (size 1.27 1.27))))
          (number "27" (effects (font (size 1.27 1.27))))
        )
        (pin passive line (at 30.48 -72.39 180) (length 3.81)
          (name "DQ51" (effects (font (size 1.27 1.27))))
          (number "271" (effects (font (size 1.27 1.27))))
        )
        (pin passive line (at 30.48 -110.49 180) (length 3.81)
          (name "DQ61" (effects (font (size 1.27 1.27))))
          (number "273" (effects (font (size 1.27 1.27))))
        )
        (pin passive line (at 30.48 -100.33 180) (length 3.81)
          (name "DQ57" (effects (font (size 1.27 1.27))))
          (number "275" (effects (font (size 1.27 1.27))))
        )
        (pin passive line (at 30.48 -120.65 180) (length 3.81)
          (name "DQS7_c" (effects (font (size 1.27 1.27))))
          (number "277" (effects (font (size 1.27 1.27))))
        )
        (pin passive line (at 30.48 -118.11 180) (length 3.81)
          (name "DQS7_t" (effects (font (size 1.27 1.27))))
          (number "278" (effects (font (size 1.27 1.27))))
        )
        (pin passive line (at 30.48 -115.57 180) (length 3.81)
          (name "DQ63" (effects (font (size 1.27 1.27))))
          (number "280" (effects (font (size 1.27 1.27))))
        )
        (pin passive line (at 30.48 -105.41 180) (length 3.81)
          (name "DQ59" (effects (font (size 1.27 1.27))))
          (number "282" (effects (font (size 1.27 1.27))))
        )
        (pin passive line (at 0 -91.44 0) (length 3.81)
          (name "DQS11_t" (effects (font (size 1.27 1.27))))
          (number "29" (effects (font (size 1.27 1.27))))
        )
        (pin passive line (at 0 -10.16 0) (length 3.81)
          (name "DQ4" (effects (font (size 1.27 1.27))))
          (number "3" (effects (font (size 1.27 1.27))))
        )
        (pin passive line (at 0 -93.98 0) (length 3.81)
          (name "DQS11_c" (effects (font (size 1.27 1.27))))
          (number "30" (effects (font (size 1.27 1.27))))
        )
        (pin passive line (at 0 -81.28 0) (length 3.81)
          (name "DQ22" (effects (font (size 1.27 1.27))))
          (number "32" (effects (font (size 1.27 1.27))))
        )
        (pin passive line (at 0 -71.12 0) (length 3.81)
          (name "DQ18" (effects (font (size 1.27 1.27))))
          (number "34" (effects (font (size 1.27 1.27))))
        )
        (pin passive line (at 0 -109.22 0) (length 3.81)
          (name "DQ28" (effects (font (size 1.27 1.27))))
          (number "36" (effects (font (size 1.27 1.27))))
        )
        (pin passive line (at 0 -99.06 0) (length 3.81)
          (name "DQ24" (effects (font (size 1.27 1.27))))
          (number "38" (effects (font (size 1.27 1.27))))
        )
        (pin passive line (at 0 -124.46 0) (length 3.81)
          (name "DQS12_t" (effects (font (size 1.27 1.27))))
          (number "40" (effects (font (size 1.27 1.27))))
        )
        (pin passive line (at 0 -127 0) (length 3.81)
          (name "DQS12_c" (effects (font (size 1.27 1.27))))
          (number "41" (effects (font (size 1.27 1.27))))
        )
        (pin passive line (at 0 -114.3 0) (length 3.81)
          (name "DQ30" (effects (font (size 1.27 1.27))))
          (number "43" (effects (font (size 1.27 1.27))))
        )
        (pin passive line (at 0 -104.14 0) (length 3.81)
          (name "DQ26" (effects (font (size 1.27 1.27))))
          (number "45" (effects (font (size 1.27 1.27))))
        )
        (pin passive line (at 0 -142.24 0) (length 3.81)
          (name "CB4" (effects (font (size 1.27 1.27))))
          (number "47" (effects (font (size 1.27 1.27))))
        )
        (pin passive line (at 0 -132.08 0) (length 3.81)
          (name "CB0" (effects (font (size 1.27 1.27))))
          (number "49" (effects (font (size 1.27 1.27))))
        )
        (pin passive line (at 0 0 0) (length 3.81)
          (name "DQ0" (effects (font (size 1.27 1.27))))
          (number "5" (effects (font (size 1.27 1.27))))
        )
        (pin passive line (at 0 -157.48 0) (length 3.81)
          (name "DQS17_t" (effects (font (size 1.27 1.27))))
          (number "51" (effects (font (size 1.27 1.27))))
        )
        (pin passive line (at 0 -160.02 0) (length 3.81)
          (name "DQS17_c" (effects (font (size 1.27 1.27))))
          (number "52" (effects (font (size 1.27 1.27))))
        )
        (pin passive line (at 0 -147.32 0) (length 3.81)
          (name "CB6" (effects (font (size 1.27 1.27))))
          (number "54" (effects (font (size 1.27 1.27))))
        )
        (pin passive line (at 0 -137.16 0) (length 3.81)
          (name "CB2" (effects (font (size 1.27 1.27))))
          (number "56" (effects (font (size 1.27 1.27))))
        )
        (pin passive line (at 0 -25.4 0) (length 3.81)
          (name "DQS9_t" (effects (font (size 1.27 1.27))))
          (number "7" (effects (font (size 1.27 1.27))))
        )
        (pin passive line (at 0 -27.94 0) (length 3.81)
          (name "DQS9_c" (effects (font (size 1.27 1.27))))
          (number "8" (effects (font (size 1.27 1.27))))
        )
        (pin passive line (at 30.48 -10.16 180) (length 3.81)
          (name "DQ36" (effects (font (size 1.27 1.27))))
          (number "95" (effects (font (size 1.27 1.27))))
        )
        (pin passive line (at 30.48 0 180) (length 3.81)
          (name "DQ32" (effects (font (size 1.27 1.27))))
          (number "97" (effects (font (size 1.27 1.27))))
        )
        (pin passive line (at 30.48 -25.4 180) (length 3.81)
          (name "DQS13_t" (effects (font (size 1.27 1.27))))
          (number "99" (effects (font (size 1.27 1.27))))
        )
      )
      (symbol "Bus_DDR4_2199155-1_2_1"
        (rectangle (start 3.81 2.54) (end 26.67 -85.09)
          (stroke (width 0.254) (type default))
          (fill (type background))
        )
        (pin passive line (at 0 0 0) (length 3.81)
          (name "12V/NC" (effects (font (size 1.27 1.27))))
          (number "1" (effects (font (size 1.27 1.27))))
        )
        (pin passive line (at 0 -82.55 0) (length 3.81)
          (name "VSS" (effects (font (size 1.27 1.27))))
          (number "101" (effects (font (size 1.27 1.27))))
        )
        (pin passive line (at 0 -82.55 0) (length 3.81) hide
          (name "VSS" (effects (font (size 1.27 1.27))))
          (number "103" (effects (font (size 1.27 1.27))))
        )
        (pin passive line (at 0 -82.55 0) (length 3.81) hide
          (name "VSS" (effects (font (size 1.27 1.27))))
          (number "105" (effects (font (size 1.27 1.27))))
        )
        (pin passive line (at 0 -82.55 0) (length 3.81) hide
          (name "VSS" (effects (font (size 1.27 1.27))))
          (number "107" (effects (font (size 1.27 1.27))))
        )
        (pin passive line (at 0 -82.55 0) (length 3.81) hide
          (name "VSS" (effects (font (size 1.27 1.27))))
          (number "109" (effects (font (size 1.27 1.27))))
        )
        (pin passive line (at 0 -82.55 0) (length 3.81) hide
          (name "VSS" (effects (font (size 1.27 1.27))))
          (number "11" (effects (font (size 1.27 1.27))))
        )
        (pin passive line (at 0 -82.55 0) (length 3.81) hide
          (name "VSS" (effects (font (size 1.27 1.27))))
          (number "112" (effects (font (size 1.27 1.27))))
        )
        (pin passive line (at 0 -82.55 0) (length 3.81) hide
          (name "VSS" (effects (font (size 1.27 1.27))))
          (number "114" (effects (font (size 1.27 1.27))))
        )
        (pin passive line (at 0 -82.55 0) (length 3.81) hide
          (name "VSS" (effects (font (size 1.27 1.27))))
          (number "116" (effects (font (size 1.27 1.27))))
        )
        (pin passive line (at 0 -82.55 0) (length 3.81) hide
          (name "VSS" (effects (font (size 1.27 1.27))))
          (number "118" (effects (font (size 1.27 1.27))))
        )
        (pin passive line (at 0 -82.55 0) (length 3.81) hide
          (name "VSS" (effects (font (size 1.27 1.27))))
          (number "120" (effects (font (size 1.27 1.27))))
        )
        (pin passive line (at 0 -82.55 0) (length 3.81) hide
          (name "VSS" (effects (font (size 1.27 1.27))))
          (number "123" (effects (font (size 1.27 1.27))))
        )
        (pin passive line (at 0 -82.55 0) (length 3.81) hide
          (name "VSS" (effects (font (size 1.27 1.27))))
          (number "125" (effects (font (size 1.27 1.27))))
        )
        (pin passive line (at 0 -82.55 0) (length 3.81) hide
          (name "VSS" (effects (font (size 1.27 1.27))))
          (number "127" (effects (font (size 1.27 1.27))))
        )
        (pin passive line (at 0 -82.55 0) (length 3.81) hide
          (name "VSS" (effects (font (size 1.27 1.27))))
          (number "129" (effects (font (size 1.27 1.27))))
        )
        (pin passive line (at 0 -82.55 0) (length 3.81) hide
          (name "VSS" (effects (font (size 1.27 1.27))))
          (number "13" (effects (font (size 1.27 1.27))))
        )
        (pin passive line (at 0 -82.55 0) (length 3.81) hide
          (name "VSS" (effects (font (size 1.27 1.27))))
          (number "131" (effects (font (size 1.27 1.27))))
        )
        (pin passive line (at 0 -82.55 0) (length 3.81) hide
          (name "VSS" (effects (font (size 1.27 1.27))))
          (number "134" (effects (font (size 1.27 1.27))))
        )
        (pin passive line (at 0 -82.55 0) (length 3.81) hide
          (name "VSS" (effects (font (size 1.27 1.27))))
          (number "136" (effects (font (size 1.27 1.27))))
        )
        (pin passive line (at 0 -82.55 0) (length 3.81) hide
          (name "VSS" (effects (font (size 1.27 1.27))))
          (number "138" (effects (font (size 1.27 1.27))))
        )
        (pin passive line (at 30.48 -63.5 180) (length 3.81)
          (name "SA0" (effects (font (size 1.27 1.27))))
          (number "139" (effects (font (size 1.27 1.27))))
        )
        (pin passive line (at 30.48 -66.04 180) (length 3.81)
          (name "SA1" (effects (font (size 1.27 1.27))))
          (number "140" (effects (font (size 1.27 1.27))))
        )
        (pin passive line (at 30.48 -74.93 180) (length 3.81)
          (name "SCL" (effects (font (size 1.27 1.27))))
          (number "141" (effects (font (size 1.27 1.27))))
        )
        (pin passive line (at 0 -12.7 0) (length 3.81)
          (name "VPP" (effects (font (size 1.27 1.27))))
          (number "142" (effects (font (size 1.27 1.27))))
        )
        (pin passive line (at 0 -12.7 0) (length 3.81) hide
          (name "VPP" (effects (font (size 1.27 1.27))))
          (number "143" (effects (font (size 1.27 1.27))))
        )
        (pin no_connect line (at 3.81 -67.31 0) (length 3.81) hide
          (name "RFU" (effects (font (size 1.27 1.27))))
          (number "144" (effects (font (size 1.27 1.27))))
        )
        (pin passive line (at 0 0 0) (length 3.81) hide
          (name "12V/NC" (effects (font (size 1.27 1.27))))
          (number "145" (effects (font (size 1.27 1.27))))
        )
        (pin passive line (at 0 -7.62 0) (length 3.81)
          (name "VREFCA" (effects (font (size 1.27 1.27))))
          (number "146" (effects (font (size 1.27 1.27))))
        )
        (pin passive line (at 0 -82.55 0) (length 3.81) hide
          (name "VSS" (effects (font (size 1.27 1.27))))
          (number "147" (effects (font (size 1.27 1.27))))
        )
        (pin passive line (at 0 -82.55 0) (length 3.81) hide
          (name "VSS" (effects (font (size 1.27 1.27))))
          (number "149" (effects (font (size 1.27 1.27))))
        )
        (pin passive line (at 0 -82.55 0) (length 3.81) hide
          (name "VSS" (effects (font (size 1.27 1.27))))
          (number "15" (effects (font (size 1.27 1.27))))
        )
        (pin passive line (at 0 -82.55 0) (length 3.81) hide
          (name "VSS" (effects (font (size 1.27 1.27))))
          (number "151" (effects (font (size 1.27 1.27))))
        )
        (pin passive line (at 0 -82.55 0) (length 3.81) hide
          (name "VSS" (effects (font (size 1.27 1.27))))
          (number "154" (effects (font (size 1.27 1.27))))
        )
        (pin passive line (at 0 -82.55 0) (length 3.81) hide
          (name "VSS" (effects (font (size 1.27 1.27))))
          (number "156" (effects (font (size 1.27 1.27))))
        )
        (pin passive line (at 0 -82.55 0) (length 3.81) hide
          (name "VSS" (effects (font (size 1.27 1.27))))
          (number "158" (effects (font (size 1.27 1.27))))
        )
        (pin passive line (at 0 -82.55 0) (length 3.81) hide
          (name "VSS" (effects (font (size 1.27 1.27))))
          (number "160" (effects (font (size 1.27 1.27))))
        )
        (pin passive line (at 0 -82.55 0) (length 3.81) hide
          (name "VSS" (effects (font (size 1.27 1.27))))
          (number "162" (effects (font (size 1.27 1.27))))
        )
        (pin passive line (at 0 -82.55 0) (length 3.81) hide
          (name "VSS" (effects (font (size 1.27 1.27))))
          (number "165" (effects (font (size 1.27 1.27))))
        )
        (pin passive line (at 0 -82.55 0) (length 3.81) hide
          (name "VSS" (effects (font (size 1.27 1.27))))
          (number "167" (effects (font (size 1.27 1.27))))
        )
        (pin passive line (at 0 -82.55 0) (length 3.81) hide
          (name "VSS" (effects (font (size 1.27 1.27))))
          (number "169" (effects (font (size 1.27 1.27))))
        )
        (pin passive line (at 0 -82.55 0) (length 3.81) hide
          (name "VSS" (effects (font (size 1.27 1.27))))
          (number "17" (effects (font (size 1.27 1.27))))
        )
        (pin passive line (at 0 -82.55 0) (length 3.81) hide
          (name "VSS" (effects (font (size 1.27 1.27))))
          (number "171" (effects (font (size 1.27 1.27))))
        )
        (pin passive line (at 0 -82.55 0) (length 3.81) hide
          (name "VSS" (effects (font (size 1.27 1.27))))
          (number "173" (effects (font (size 1.27 1.27))))
        )
        (pin passive line (at 0 -82.55 0) (length 3.81) hide
          (name "VSS" (effects (font (size 1.27 1.27))))
          (number "176" (effects (font (size 1.27 1.27))))
        )
        (pin passive line (at 0 -82.55 0) (length 3.81) hide
          (name "VSS" (effects (font (size 1.27 1.27))))
          (number "178" (effects (font (size 1.27 1.27))))
        )
        (pin passive line (at 0 -82.55 0) (length 3.81) hide
          (name "VSS" (effects (font (size 1.27 1.27))))
          (number "180" (effects (font (size 1.27 1.27))))
        )
        (pin passive line (at 0 -82.55 0) (length 3.81) hide
          (name "VSS" (effects (font (size 1.27 1.27))))
          (number "182" (effects (font (size 1.27 1.27))))
        )
        (pin passive line (at 0 -82.55 0) (length 3.81) hide
          (name "VSS" (effects (font (size 1.27 1.27))))
          (number "184" (effects (font (size 1.27 1.27))))
        )
        (pin passive line (at 0 -82.55 0) (length 3.81) hide
          (name "VSS" (effects (font (size 1.27 1.27))))
          (number "187" (effects (font (size 1.27 1.27))))
        )
        (pin passive line (at 0 -82.55 0) (length 3.81) hide
          (name "VSS" (effects (font (size 1.27 1.27))))
          (number "189" (effects (font (size 1.27 1.27))))
        )
        (pin passive line (at 0 -82.55 0) (length 3.81) hide
          (name "VSS" (effects (font (size 1.27 1.27))))
          (number "191" (effects (font (size 1.27 1.27))))
        )
        (pin passive line (at 0 -82.55 0) (length 3.81) hide
          (name "VSS" (effects (font (size 1.27 1.27))))
          (number "193" (effects (font (size 1.27 1.27))))
        )
        (pin passive line (at 0 -82.55 0) (length 3.81) hide
          (name "VSS" (effects (font (size 1.27 1.27))))
          (number "195" (effects (font (size 1.27 1.27))))
        )
        (pin passive line (at 0 -82.55 0) (length 3.81) hide
          (name "VSS" (effects (font (size 1.27 1.27))))
          (number "198" (effects (font (size 1.27 1.27))))
        )
        (pin passive line (at 0 -82.55 0) (length 3.81) hide
          (name "VSS" (effects (font (size 1.27 1.27))))
          (number "2" (effects (font (size 1.27 1.27))))
        )
        (pin passive line (at 0 -82.55 0) (length 3.81) hide
          (name "VSS" (effects (font (size 1.27 1.27))))
          (number "20" (effects (font (size 1.27 1.27))))
        )
        (pin passive line (at 0 -82.55 0) (length 3.81) hide
          (name "VSS" (effects (font (size 1.27 1.27))))
          (number "200" (effects (font (size 1.27 1.27))))
        )
        (pin passive line (at 0 -82.55 0) (length 3.81) hide
          (name "VSS" (effects (font (size 1.27 1.27))))
          (number "202" (effects (font (size 1.27 1.27))))
        )
        (pin passive line (at 30.48 -15.24 180) (length 3.81)
          (name "CKE1" (effects (font (size 1.27 1.27))))
          (number "203" (effects (font (size 1.27 1.27))))
        )
        (pin passive line (at 0 -2.54 0) (length 3.81)
          (name "VDD" (effects (font (size 1.27 1.27))))
          (number "204" (effects (font (size 1.27 1.27))))
        )
        (pin no_connect line (at 3.81 -69.85 0) (length 3.81) hide
          (name "RFU" (effects (font (size 1.27 1.27))))
          (number "205" (effects (font (size 1.27 1.27))))
        )
        (pin passive line (at 0 -2.54 0) (length 3.81) hide
          (name "VDD" (effects (font (size 1.27 1.27))))
          (number "206" (effects (font (size 1.27 1.27))))
        )
        (pin passive line (at 30.48 -7.62 180) (length 3.81)
          (name "BG1" (effects (font (size 1.27 1.27))))
          (number "207" (effects (font (size 1.27 1.27))))
        )
        (pin passive line (at 30.48 -27.94 180) (length 3.81)
          (name "ALERT_n" (effects (font (size 1.27 1.27))))
          (number "208" (effects (font (size 1.27 1.27))))
        )
        (pin passive line (at 0 -2.54 0) (length 3.81) hide
          (name "VDD" (effects (font (size 1.27 1.27))))
          (number "209" (effects (font (size 1.27 1.27))))
        )
        (pin passive line (at 0 -45.72 0) (length 3.81)
          (name "A11" (effects (font (size 1.27 1.27))))
          (number "210" (effects (font (size 1.27 1.27))))
        )
        (pin passive line (at 0 -35.56 0) (length 3.81)
          (name "A7" (effects (font (size 1.27 1.27))))
          (number "211" (effects (font (size 1.27 1.27))))
        )
        (pin passive line (at 0 -2.54 0) (length 3.81) hide
          (name "VDD" (effects (font (size 1.27 1.27))))
          (number "212" (effects (font (size 1.27 1.27))))
        )
        (pin passive line (at 0 -30.48 0) (length 3.81)
          (name "A5" (effects (font (size 1.27 1.27))))
          (number "213" (effects (font (size 1.27 1.27))))
        )
        (pin passive line (at 0 -27.94 0) (length 3.81)
          (name "A4" (effects (font (size 1.27 1.27))))
          (number "214" (effects (font (size 1.27 1.27))))
        )
        (pin passive line (at 0 -2.54 0) (length 3.81) hide
          (name "VDD" (effects (font (size 1.27 1.27))))
          (number "215" (effects (font (size 1.27 1.27))))
        )
        (pin passive line (at 0 -22.86 0) (length 3.81)
          (name "A2" (effects (font (size 1.27 1.27))))
          (number "216" (effects (font (size 1.27 1.27))))
        )
        (pin passive line (at 0 -2.54 0) (length 3.81) hide
          (name "VDD" (effects (font (size 1.27 1.27))))
          (number "217" (effects (font (size 1.27 1.27))))
        )
        (pin passive line (at 30.48 -36.83 180) (length 3.81)
          (name "CK1_t" (effects (font (size 1.27 1.27))))
          (number "218" (effects (font (size 1.27 1.27))))
        )
        (pin passive line (at 30.48 -39.37 180) (length 3.81)
          (name "CK1_c" (effects (font (size 1.27 1.27))))
          (number "219" (effects (font (size 1.27 1.27))))
        )
        (pin passive line (at 0 -82.55 0) (length 3.81) hide
          (name "VSS" (effects (font (size 1.27 1.27))))
          (number "22" (effects (font (size 1.27 1.27))))
        )
        (pin passive line (at 0 -2.54 0) (length 3.81) hide
          (name "VDD" (effects (font (size 1.27 1.27))))
          (number "220" (effects (font (size 1.27 1.27))))
        )
        (pin passive line (at 0 -5.08 0) (length 3.81)
          (name "VTT" (effects (font (size 1.27 1.27))))
          (number "221" (effects (font (size 1.27 1.27))))
        )
        (pin passive line (at 30.48 -25.4 180) (length 3.81)
          (name "PARITY" (effects (font (size 1.27 1.27))))
          (number "222" (effects (font (size 1.27 1.27))))
        )
        (pin passive line (at 0 -2.54 0) (length 3.81) hide
          (name "VDD" (effects (font (size 1.27 1.27))))
          (number "223" (effects (font (size 1.27 1.27))))
        )
        (pin passive line (at 30.48 -2.54 180) (length 3.81)
          (name "BA1" (effects (font (size 1.27 1.27))))
          (number "224" (effects (font (size 1.27 1.27))))
        )
        (pin passive line (at 0 -43.18 0) (length 3.81)
          (name "A10/AP" (effects (font (size 1.27 1.27))))
          (number "225" (effects (font (size 1.27 1.27))))
        )
        (pin passive line (at 0 -2.54 0) (length 3.81) hide
          (name "VDD" (effects (font (size 1.27 1.27))))
          (number "226" (effects (font (size 1.27 1.27))))
        )
        (pin no_connect line (at 3.81 -72.39 0) (length 3.81) hide
          (name "RFU" (effects (font (size 1.27 1.27))))
          (number "227" (effects (font (size 1.27 1.27))))
        )
        (pin passive line (at 0 -53.34 0) (length 3.81)
          (name "WE_n/A14" (effects (font (size 1.27 1.27))))
          (number "228" (effects (font (size 1.27 1.27))))
        )
        (pin passive line (at 0 -2.54 0) (length 3.81) hide
          (name "VDD" (effects (font (size 1.27 1.27))))
          (number "229" (effects (font (size 1.27 1.27))))
        )
        (pin passive line (at 30.48 -43.18 180) (length 3.81)
          (name "SAVE_n" (effects (font (size 1.27 1.27))))
          (number "230" (effects (font (size 1.27 1.27))))
        )
        (pin passive line (at 0 -2.54 0) (length 3.81) hide
          (name "VDD" (effects (font (size 1.27 1.27))))
          (number "231" (effects (font (size 1.27 1.27))))
        )
        (pin passive line (at 0 -50.8 0) (length 3.81)
          (name "A13" (effects (font (size 1.27 1.27))))
          (number "232" (effects (font (size 1.27 1.27))))
        )
        (pin passive line (at 0 -2.54 0) (length 3.81) hide
          (name "VDD" (effects (font (size 1.27 1.27))))
          (number "233" (effects (font (size 1.27 1.27))))
        )
        (pin passive line (at 0 -60.96 0) (length 3.81)
          (name "NC/A17" (effects (font (size 1.27 1.27))))
          (number "234" (effects (font (size 1.27 1.27))))
        )
        (pin passive line (at 30.48 -59.69 180) (length 3.81)
          (name "NC/C2" (effects (font (size 1.27 1.27))))
          (number "235" (effects (font (size 1.27 1.27))))
        )
        (pin passive line (at 0 -2.54 0) (length 3.81) hide
          (name "VDD" (effects (font (size 1.27 1.27))))
          (number "236" (effects (font (size 1.27 1.27))))
        )
        (pin passive line (at 30.48 -57.15 180) (length 3.81)
          (name "CS3_n/C1" (effects (font (size 1.27 1.27))))
          (number "237" (effects (font (size 1.27 1.27))))
        )
        (pin passive line (at 30.48 -68.58 180) (length 3.81)
          (name "SA2" (effects (font (size 1.27 1.27))))
          (number "238" (effects (font (size 1.27 1.27))))
        )
        (pin passive line (at 0 -82.55 0) (length 3.81) hide
          (name "VSS" (effects (font (size 1.27 1.27))))
          (number "239" (effects (font (size 1.27 1.27))))
        )
        (pin passive line (at 0 -82.55 0) (length 3.81) hide
          (name "VSS" (effects (font (size 1.27 1.27))))
          (number "24" (effects (font (size 1.27 1.27))))
        )
        (pin passive line (at 0 -82.55 0) (length 3.81) hide
          (name "VSS" (effects (font (size 1.27 1.27))))
          (number "241" (effects (font (size 1.27 1.27))))
        )
        (pin passive line (at 0 -82.55 0) (length 3.81) hide
          (name "VSS" (effects (font (size 1.27 1.27))))
          (number "243" (effects (font (size 1.27 1.27))))
        )
        (pin passive line (at 0 -82.55 0) (length 3.81) hide
          (name "VSS" (effects (font (size 1.27 1.27))))
          (number "246" (effects (font (size 1.27 1.27))))
        )
        (pin passive line (at 0 -82.55 0) (length 3.81) hide
          (name "VSS" (effects (font (size 1.27 1.27))))
          (number "248" (effects (font (size 1.27 1.27))))
        )
        (pin passive line (at 0 -82.55 0) (length 3.81) hide
          (name "VSS" (effects (font (size 1.27 1.27))))
          (number "250" (effects (font (size 1.27 1.27))))
        )
        (pin passive line (at 0 -82.55 0) (length 3.81) hide
          (name "VSS" (effects (font (size 1.27 1.27))))
          (number "252" (effects (font (size 1.27 1.27))))
        )
        (pin passive line (at 0 -82.55 0) (length 3.81) hide
          (name "VSS" (effects (font (size 1.27 1.27))))
          (number "254" (effects (font (size 1.27 1.27))))
        )
        (pin passive line (at 0 -82.55 0) (length 3.81) hide
          (name "VSS" (effects (font (size 1.27 1.27))))
          (number "257" (effects (font (size 1.27 1.27))))
        )
        (pin passive line (at 0 -82.55 0) (length 3.81) hide
          (name "VSS" (effects (font (size 1.27 1.27))))
          (number "259" (effects (font (size 1.27 1.27))))
        )
        (pin passive line (at 0 -82.55 0) (length 3.81) hide
          (name "VSS" (effects (font (size 1.27 1.27))))
          (number "26" (effects (font (size 1.27 1.27))))
        )
        (pin passive line (at 0 -82.55 0) (length 3.81) hide
          (name "VSS" (effects (font (size 1.27 1.27))))
          (number "261" (effects (font (size 1.27 1.27))))
        )
        (pin passive line (at 0 -82.55 0) (length 3.81) hide
          (name "VSS" (effects (font (size 1.27 1.27))))
          (number "263" (effects (font (size 1.27 1.27))))
        )
        (pin passive line (at 0 -82.55 0) (length 3.81) hide
          (name "VSS" (effects (font (size 1.27 1.27))))
          (number "265" (effects (font (size 1.27 1.27))))
        )
        (pin passive line (at 0 -82.55 0) (length 3.81) hide
          (name "VSS" (effects (font (size 1.27 1.27))))
          (number "268" (effects (font (size 1.27 1.27))))
        )
        (pin passive line (at 0 -82.55 0) (length 3.81) hide
          (name "VSS" (effects (font (size 1.27 1.27))))
          (number "270" (effects (font (size 1.27 1.27))))
        )
        (pin passive line (at 0 -82.55 0) (length 3.81) hide
          (name "VSS" (effects (font (size 1.27 1.27))))
          (number "272" (effects (font (size 1.27 1.27))))
        )
        (pin passive line (at 0 -82.55 0) (length 3.81) hide
          (name "VSS" (effects (font (size 1.27 1.27))))
          (number "274" (effects (font (size 1.27 1.27))))
        )
        (pin passive line (at 0 -82.55 0) (length 3.81) hide
          (name "VSS" (effects (font (size 1.27 1.27))))
          (number "276" (effects (font (size 1.27 1.27))))
        )
        (pin passive line (at 0 -82.55 0) (length 3.81) hide
          (name "VSS" (effects (font (size 1.27 1.27))))
          (number "279" (effects (font (size 1.27 1.27))))
        )
        (pin passive line (at 0 -82.55 0) (length 3.81) hide
          (name "VSS" (effects (font (size 1.27 1.27))))
          (number "28" (effects (font (size 1.27 1.27))))
        )
        (pin passive line (at 0 -82.55 0) (length 3.81) hide
          (name "VSS" (effects (font (size 1.27 1.27))))
          (number "281" (effects (font (size 1.27 1.27))))
        )
        (pin passive line (at 0 -82.55 0) (length 3.81) hide
          (name "VSS" (effects (font (size 1.27 1.27))))
          (number "283" (effects (font (size 1.27 1.27))))
        )
        (pin passive line (at 0 -10.16 0) (length 3.81)
          (name "VDDSPD" (effects (font (size 1.27 1.27))))
          (number "284" (effects (font (size 1.27 1.27))))
        )
        (pin passive line (at 30.48 -72.39 180) (length 3.81)
          (name "SDA" (effects (font (size 1.27 1.27))))
          (number "285" (effects (font (size 1.27 1.27))))
        )
        (pin passive line (at 0 -12.7 0) (length 3.81) hide
          (name "VPP" (effects (font (size 1.27 1.27))))
          (number "286" (effects (font (size 1.27 1.27))))
        )
        (pin passive line (at 0 -12.7 0) (length 3.81) hide
          (name "VPP" (effects (font (size 1.27 1.27))))
          (number "287" (effects (font (size 1.27 1.27))))
        )
        (pin passive line (at 0 -12.7 0) (length 3.81) hide
          (name "VPP" (effects (font (size 1.27 1.27))))
          (number "288" (effects (font (size 1.27 1.27))))
        )
        (pin passive line (at 0 -82.55 0) (length 3.81) hide
          (name "VSS" (effects (font (size 1.27 1.27))))
          (number "31" (effects (font (size 1.27 1.27))))
        )
        (pin passive line (at 0 -82.55 0) (length 3.81) hide
          (name "VSS" (effects (font (size 1.27 1.27))))
          (number "33" (effects (font (size 1.27 1.27))))
        )
        (pin passive line (at 0 -82.55 0) (length 3.81) hide
          (name "VSS" (effects (font (size 1.27 1.27))))
          (number "35" (effects (font (size 1.27 1.27))))
        )
        (pin passive line (at 0 -82.55 0) (length 3.81) hide
          (name "VSS" (effects (font (size 1.27 1.27))))
          (number "37" (effects (font (size 1.27 1.27))))
        )
        (pin passive line (at 0 -82.55 0) (length 3.81) hide
          (name "VSS" (effects (font (size 1.27 1.27))))
          (number "39" (effects (font (size 1.27 1.27))))
        )
        (pin passive line (at 0 -82.55 0) (length 3.81) hide
          (name "VSS" (effects (font (size 1.27 1.27))))
          (number "4" (effects (font (size 1.27 1.27))))
        )
        (pin passive line (at 0 -82.55 0) (length 3.81) hide
          (name "VSS" (effects (font (size 1.27 1.27))))
          (number "42" (effects (font (size 1.27 1.27))))
        )
        (pin passive line (at 0 -82.55 0) (length 3.81) hide
          (name "VSS" (effects (font (size 1.27 1.27))))
          (number "44" (effects (font (size 1.27 1.27))))
        )
        (pin passive line (at 0 -82.55 0) (length 3.81) hide
          (name "VSS" (effects (font (size 1.27 1.27))))
          (number "46" (effects (font (size 1.27 1.27))))
        )
        (pin passive line (at 0 -82.55 0) (length 3.81) hide
          (name "VSS" (effects (font (size 1.27 1.27))))
          (number "48" (effects (font (size 1.27 1.27))))
        )
        (pin passive line (at 0 -82.55 0) (length 3.81) hide
          (name "VSS" (effects (font (size 1.27 1.27))))
          (number "50" (effects (font (size 1.27 1.27))))
        )
        (pin passive line (at 0 -82.55 0) (length 3.81) hide
          (name "VSS" (effects (font (size 1.27 1.27))))
          (number "53" (effects (font (size 1.27 1.27))))
        )
        (pin passive line (at 0 -82.55 0) (length 3.81) hide
          (name "VSS" (effects (font (size 1.27 1.27))))
          (number "55" (effects (font (size 1.27 1.27))))
        )
        (pin passive line (at 0 -63.5 0) (length 3.81)
          (name "Presence" (effects (font (size 1.27 1.27))))
          (number "57" (effects (font (size 1.27 1.27))))
        )
        (pin passive line (at 30.48 -22.86 180) (length 3.81)
          (name "RESET_n" (effects (font (size 1.27 1.27))))
          (number "58" (effects (font (size 1.27 1.27))))
        )
        (pin passive line (at 0 -2.54 0) (length 3.81) hide
          (name "VDD" (effects (font (size 1.27 1.27))))
          (number "59" (effects (font (size 1.27 1.27))))
        )
        (pin passive line (at 0 -82.55 0) (length 3.81) hide
          (name "VSS" (effects (font (size 1.27 1.27))))
          (number "6" (effects (font (size 1.27 1.27))))
        )
        (pin passive line (at 30.48 -12.7 180) (length 3.81)
          (name "CKE0" (effects (font (size 1.27 1.27))))
          (number "60" (effects (font (size 1.27 1.27))))
        )
        (pin passive line (at 0 -2.54 0) (length 3.81) hide
          (name "VDD" (effects (font (size 1.27 1.27))))
          (number "61" (effects (font (size 1.27 1.27))))
        )
        (pin passive line (at 30.48 -10.16 180) (length 3.81)
          (name "ACT_n" (effects (font (size 1.27 1.27))))
          (number "62" (effects (font (size 1.27 1.27))))
        )
        (pin passive line (at 30.48 -5.08 180) (length 3.81)
          (name "BG0" (effects (font (size 1.27 1.27))))
          (number "63" (effects (font (size 1.27 1.27))))
        )
        (pin passive line (at 0 -2.54 0) (length 3.81) hide
          (name "VDD" (effects (font (size 1.27 1.27))))
          (number "64" (effects (font (size 1.27 1.27))))
        )
        (pin passive line (at 0 -48.26 0) (length 3.81)
          (name "A12/BC_n" (effects (font (size 1.27 1.27))))
          (number "65" (effects (font (size 1.27 1.27))))
        )
        (pin passive line (at 0 -40.64 0) (length 3.81)
          (name "A9" (effects (font (size 1.27 1.27))))
          (number "66" (effects (font (size 1.27 1.27))))
        )
        (pin passive line (at 0 -2.54 0) (length 3.81) hide
          (name "VDD" (effects (font (size 1.27 1.27))))
          (number "67" (effects (font (size 1.27 1.27))))
        )
        (pin passive line (at 0 -38.1 0) (length 3.81)
          (name "A8" (effects (font (size 1.27 1.27))))
          (number "68" (effects (font (size 1.27 1.27))))
        )
        (pin passive line (at 0 -33.02 0) (length 3.81)
          (name "A6" (effects (font (size 1.27 1.27))))
          (number "69" (effects (font (size 1.27 1.27))))
        )
        (pin passive line (at 0 -2.54 0) (length 3.81) hide
          (name "VDD" (effects (font (size 1.27 1.27))))
          (number "70" (effects (font (size 1.27 1.27))))
        )
        (pin passive line (at 0 -25.4 0) (length 3.81)
          (name "A3" (effects (font (size 1.27 1.27))))
          (number "71" (effects (font (size 1.27 1.27))))
        )
        (pin passive line (at 0 -20.32 0) (length 3.81)
          (name "A1" (effects (font (size 1.27 1.27))))
          (number "72" (effects (font (size 1.27 1.27))))
        )
        (pin passive line (at 0 -2.54 0) (length 3.81) hide
          (name "VDD" (effects (font (size 1.27 1.27))))
          (number "73" (effects (font (size 1.27 1.27))))
        )
        (pin passive line (at 30.48 -31.75 180) (length 3.81)
          (name "CK0_t" (effects (font (size 1.27 1.27))))
          (number "74" (effects (font (size 1.27 1.27))))
        )
        (pin passive line (at 30.48 -34.29 180) (length 3.81)
          (name "CK0_c" (effects (font (size 1.27 1.27))))
          (number "75" (effects (font (size 1.27 1.27))))
        )
        (pin passive line (at 0 -2.54 0) (length 3.81) hide
          (name "VDD" (effects (font (size 1.27 1.27))))
          (number "76" (effects (font (size 1.27 1.27))))
        )
        (pin passive line (at 0 -5.08 0) (length 3.81) hide
          (name "VTT" (effects (font (size 1.27 1.27))))
          (number "77" (effects (font (size 1.27 1.27))))
        )
        (pin passive line (at 30.48 -45.72 180) (length 3.81)
          (name "EVENT_n" (effects (font (size 1.27 1.27))))
          (number "78" (effects (font (size 1.27 1.27))))
        )
        (pin passive line (at 0 -17.78 0) (length 3.81)
          (name "A0" (effects (font (size 1.27 1.27))))
          (number "79" (effects (font (size 1.27 1.27))))
        )
        (pin passive line (at 0 -2.54 0) (length 3.81) hide
          (name "VDD" (effects (font (size 1.27 1.27))))
          (number "80" (effects (font (size 1.27 1.27))))
        )
        (pin passive line (at 30.48 0 180) (length 3.81)
          (name "BA0" (effects (font (size 1.27 1.27))))
          (number "81" (effects (font (size 1.27 1.27))))
        )
        (pin passive line (at 0 -58.42 0) (length 3.81)
          (name "RAS_n/A16" (effects (font (size 1.27 1.27))))
          (number "82" (effects (font (size 1.27 1.27))))
        )
        (pin passive line (at 0 -2.54 0) (length 3.81) hide
          (name "VDD" (effects (font (size 1.27 1.27))))
          (number "83" (effects (font (size 1.27 1.27))))
        )
        (pin passive line (at 30.48 -49.53 180) (length 3.81)
          (name "CS0_n" (effects (font (size 1.27 1.27))))
          (number "84" (effects (font (size 1.27 1.27))))
        )
        (pin passive line (at 0 -2.54 0) (length 3.81) hide
          (name "VDD" (effects (font (size 1.27 1.27))))
          (number "85" (effects (font (size 1.27 1.27))))
        )
        (pin passive line (at 0 -55.88 0) (length 3.81)
          (name "CAS_n/A15" (effects (font (size 1.27 1.27))))
          (number "86" (effects (font (size 1.27 1.27))))
        )
        (pin passive line (at 30.48 -17.78 180) (length 3.81)
          (name "ODT0" (effects (font (size 1.27 1.27))))
          (number "87" (effects (font (size 1.27 1.27))))
        )
        (pin passive line (at 0 -2.54 0) (length 3.81) hide
          (name "VDD" (effects (font (size 1.27 1.27))))
          (number "88" (effects (font (size 1.27 1.27))))
        )
        (pin passive line (at 30.48 -52.07 180) (length 3.81)
          (name "CS1_n" (effects (font (size 1.27 1.27))))
          (number "89" (effects (font (size 1.27 1.27))))
        )
        (pin passive line (at 0 -82.55 0) (length 3.81) hide
          (name "VSS" (effects (font (size 1.27 1.27))))
          (number "9" (effects (font (size 1.27 1.27))))
        )
        (pin passive line (at 0 -2.54 0) (length 3.81) hide
          (name "VDD" (effects (font (size 1.27 1.27))))
          (number "90" (effects (font (size 1.27 1.27))))
        )
        (pin passive line (at 30.48 -20.32 180) (length 3.81)
          (name "ODT1" (effects (font (size 1.27 1.27))))
          (number "91" (effects (font (size 1.27 1.27))))
        )
        (pin passive line (at 0 -2.54 0) (length 3.81) hide
          (name "VDD" (effects (font (size 1.27 1.27))))
          (number "92" (effects (font (size 1.27 1.27))))
        )
        (pin passive line (at 30.48 -54.61 180) (length 3.81)
          (name "C0/CS2_n" (effects (font (size 1.27 1.27))))
          (number "93" (effects (font (size 1.27 1.27))))
        )
        (pin passive line (at 0 -82.55 0) (length 3.81) hide
          (name "VSS" (effects (font (size 1.27 1.27))))
          (number "94" (effects (font (size 1.27 1.27))))
        )
        (pin passive line (at 0 -82.55 0) (length 3.81) hide
          (name "VSS" (effects (font (size 1.27 1.27))))
          (number "96" (effects (font (size 1.27 1.27))))
        )
        (pin passive line (at 0 -82.55 0) (length 3.81) hide
          (name "VSS" (effects (font (size 1.27 1.27))))
          (number "98" (effects (font (size 1.27 1.27))))
        )
        (pin passive line (at 30.48 -77.47 180) (length 3.81)
          (name "MP" (effects (font (size 1.27 1.27))))
          (number "MP1" (effects (font (size 1.27 1.27))))
        )
        (pin passive line (at 30.48 -80.01 180) (length 3.81)
          (name "MP" (effects (font (size 1.27 1.27))))
          (number "MP2" (effects (font (size 1.27 1.27))))
        )
        (pin passive line (at 30.48 -82.55 180) (length 3.81)
          (name "MP" (effects (font (size 1.27 1.27))))
          (number "MP3" (effects (font (size 1.27 1.27))))
        )
      )
    )
	(symbol "antmicroMemoryConnectorsPCCardSockets:MicroSD_693071020811" (in_bom yes) (on_board yes)
      (property "Reference" "J" (at 55.88 -2.54 0)
        (effects (font (size 1.27 1.27) (thickness 0.15)) (justify left bottom))
      )
      (property "Value" "MicroSD_693071020811" (at 55.88 -5.08 0)
        (effects (font (size 1.27 1.27) (thickness 0.15)) (justify left bottom))
      )
      (property "Footprint" "antmicro-footprints:MicroSD_Wurth_693071020811" (at 55.88 -7.62 0)
        (effects (font (size 1.27 1.27) (thickness 0.15)) (justify left bottom) hide)
      )
      (property "Datasheet" "https://www.we-online.com/catalog/datasheet/693071020811.pdf" (at 55.88 -10.16 0)
        (effects (font (size 1.27 1.27) (thickness 0.15)) (justify left bottom) hide)
      )
      (property "Manufacturer" "Würth Elektronik" (at 55.88 -12.7 0)
        (effects (font (size 1.27 1.27) (thickness 0.15)) (justify left bottom) hide)
      )
      (property "MPN" "693071020811" (at 55.88 -15.24 0)
        (effects (font (size 1.27 1.27) (thickness 0.15)) (justify left bottom) hide)
      )
      (property "Author" "Antmicro" (at 55.88 -17.78 0)
        (effects (font (size 1.27 1.27) (thickness 0.15)) (justify left bottom) hide)
      )
      (property "License" "Apache-2.0" (at 55.88 -20.32 0)
        (effects (font (size 1.27 1.27) (thickness 0.15)) (justify left bottom) hide)
      )
      (property "ki_description" "SMT MICRO SD CARD CONNECTOR, PUSH-PUSH" (at 0 0 0)
        (effects (font (size 1.27 1.27)) hide)
      )
      (symbol "MicroSD_693071020811_1_1"
        (polyline
          (pts
            (xy 38.1 2.54)
            (xy 38.1 3.81)
            (xy 2.54 3.81)
            (xy 2.54 -29.21)
            (xy 38.1 -29.21)
            (xy 38.1 -21.59)
          )
          (stroke (width 0.254) (type default))
          (fill (type background))
        )
        (polyline
          (pts
            (xy 12.7 -21.59)
            (xy 12.7 -1.27)
            (xy 20.32 -1.27)
            (xy 24.13 2.54)
            (xy 25.4 2.54)
            (xy 25.4 1.27)
            (xy 27.94 1.27)
            (xy 29.21 2.54)
            (xy 41.91 2.54)
            (xy 41.91 -21.59)
            (xy 12.7 -21.59)
          )
          (stroke (width 0.254) (type default))
          (fill (type background))
        )
        (rectangle (start 13.97 -19.685) (end 16.51 -20.955)
          (stroke (width 0.254) (type default))
          (fill (type outline))
        )
        (rectangle (start 13.97 -17.145) (end 16.51 -18.415)
          (stroke (width 0.254) (type default))
          (fill (type outline))
        )
        (rectangle (start 13.97 -14.605) (end 16.51 -15.875)
          (stroke (width 0.254) (type default))
          (fill (type outline))
        )
        (rectangle (start 13.97 -12.065) (end 16.51 -13.335)
          (stroke (width 0.254) (type default))
          (fill (type outline))
        )
        (rectangle (start 13.97 -9.525) (end 16.51 -10.795)
          (stroke (width 0.254) (type default))
          (fill (type outline))
        )
        (rectangle (start 13.97 -6.985) (end 16.51 -8.255)
          (stroke (width 0.254) (type default))
          (fill (type outline))
        )
        (rectangle (start 13.97 -4.445) (end 16.51 -5.715)
          (stroke (width 0.254) (type default))
          (fill (type outline))
        )
        (rectangle (start 13.97 -1.905) (end 16.51 -3.175)
          (stroke (width 0.254) (type default))
          (fill (type outline))
        )
        (pin bidirectional line (at 0 -5.08 0) (length 2.54)
          (name "DAT2" (effects (font (size 1.27 1.27))))
          (number "1" (effects (font (size 1.27 1.27))))
        )
        (pin bidirectional line (at 0 -7.62 0) (length 2.54)
          (name "DAT3/CD" (effects (font (size 1.27 1.27))))
          (number "2" (effects (font (size 1.27 1.27))))
        )
        (pin input line (at 0 -10.16 0) (length 2.54)
          (name "CMD" (effects (font (size 1.27 1.27))))
          (number "3" (effects (font (size 1.27 1.27))))
        )
        (pin power_in line (at 0 0 0) (length 2.54)
          (name "VDD" (effects (font (size 1.27 1.27))))
          (number "4" (effects (font (size 1.27 1.27))))
        )
        (pin input line (at 0 -12.7 0) (length 2.54)
          (name "CLK" (effects (font (size 1.27 1.27))))
          (number "5" (effects (font (size 1.27 1.27))))
        )
        (pin passive line (at 0 -26.67 0) (length 2.54)
          (name "VSS" (effects (font (size 1.27 1.27))))
          (number "6" (effects (font (size 1.27 1.27))))
        )
        (pin input line (at 0 -15.24 0) (length 2.54)
          (name "DAT0" (effects (font (size 1.27 1.27))))
          (number "7" (effects (font (size 1.27 1.27))))
        )
        (pin input line (at 0 -17.78 0) (length 2.54)
          (name "DAT1" (effects (font (size 1.27 1.27))))
          (number "8" (effects (font (size 1.27 1.27))))
        )
        (pin passive line (at 0 -20.32 0) (length 2.54)
          (name "CD_SW1" (effects (font (size 1.27 1.27))))
          (number "9" (effects (font (size 1.27 1.27))))
        )
        (pin passive line (at 40.64 -26.67 180) (length 2.54)
          (name "SH" (effects (font (size 1.27 1.27))))
          (number "SH" (effects (font (size 1.27 1.27))))
        )
      )
    )
	(symbol "antmicroMicrocontrollers:PAC1954T-E_VQFN" (in_bom yes) (on_board yes)
      (property "Reference" "U" (at 38.1 -2.54 0)
        (effects (font (size 1.27 1.27) (thickness 0.15)) (justify left bottom))
      )
      (property "Value" "PAC1954T-E_VQFN" (at 38.1 -5.08 0)
        (effects (font (size 1.27 1.27) (thickness 0.15)) (justify left bottom))
      )
      (property "Footprint" "antmicro-footprints:VQFN-16-1EP_3x3mm_P0.5mm_EP1.1x1.1mm" (at 38.1 -7.62 0)
        (effects (font (size 1.27 1.27) (thickness 0.15)) (justify left bottom) hide)
      )
      (property "Datasheet" "https://ww1.microchip.com/downloads/aemDocuments/documents/MSLD/ProductDocuments/DataSheets/PAC195X-Family-Data-Sheet-DS20006539.pdf" (at 38.1 -10.16 0)
        (effects (font (size 1.27 1.27) (thickness 0.15)) (justify left bottom) hide)
      )
      (property "MPN" "PAC1954T-E/4MX" (at 38.1 -12.7 0)
        (effects (font (size 1.27 1.27) (thickness 0.15)) (justify left bottom) hide)
      )
      (property "Manufacturer" "Microchip Technology" (at 38.1 -15.24 0)
        (effects (font (size 1.27 1.27) (thickness 0.15)) (justify left bottom) hide)
      )
      (property "Author" "Antmicro" (at 38.1 -17.78 0)
        (effects (font (size 1.27 1.27) (thickness 0.15)) (justify left bottom) hide)
      )
      (property "License" "Apache-2.0" (at 38.1 -20.32 0)
        (effects (font (size 1.27 1.27) (thickness 0.15)) (justify left bottom) hide)
      )
      (property "ki_keywords" "MONITOR, VOLTAGE" (at 0 0 0)
        (effects (font (size 1.27 1.27)) hide)
      )
      (property "ki_description" "Current/Voltage Monitor Regulator High-Side 16-VQFN (3x3)" (at 0 0 0)
        (effects (font (size 1.27 1.27)) hide)
      )
      (property "ki_fp_filters" "UQFN*1EP*4x4mm*P0.65mm*" (at 0 0 0)
        (effects (font (size 1.27 1.27)) hide)
      )
      (symbol "PAC1954T-E_VQFN_1_1"
        (rectangle (start 2.54 2.54) (end 22.86 -27.94)
          (stroke (width 0.254) (type default))
          (fill (type background))
        )
        (pin bidirectional line (at 0 -15.24 0) (length 2.54)
          (name "SLOW/~{ALERT1}" (effects (font (size 1.27 1.27))))
          (number "1" (effects (font (size 1.27 1.27))))
        )
        (pin input line (at 25.4 -22.86 180) (length 2.54)
          (name "IN4+" (effects (font (size 1.27 1.27))))
          (number "10" (effects (font (size 1.27 1.27))))
        )
        (pin input line (at 25.4 0 180) (length 2.54)
          (name "IN1+" (effects (font (size 1.27 1.27))))
          (number "11" (effects (font (size 1.27 1.27))))
        )
        (pin input line (at 25.4 -2.54 180) (length 2.54)
          (name "IN1-" (effects (font (size 1.27 1.27))))
          (number "12" (effects (font (size 1.27 1.27))))
        )
        (pin input line (at 25.4 -7.62 180) (length 2.54)
          (name "IN2+" (effects (font (size 1.27 1.27))))
          (number "13" (effects (font (size 1.27 1.27))))
        )
        (pin input line (at 25.4 -10.16 180) (length 2.54)
          (name "IN2-" (effects (font (size 1.27 1.27))))
          (number "14" (effects (font (size 1.27 1.27))))
        )
        (pin bidirectional line (at 0 -17.78 0) (length 2.54)
          (name "GPIO/~{ALERT2}" (effects (font (size 1.27 1.27))))
          (number "15" (effects (font (size 1.27 1.27))))
        )
        (pin input line (at 0 -2.54 0) (length 2.54)
          (name "~{PWRDN}" (effects (font (size 1.27 1.27))))
          (number "16" (effects (font (size 1.27 1.27))))
        )
        (pin no_connect line (at 2.54 -22.86 0) (length 2.54) hide
          (name "EP" (effects (font (size 1.27 1.27))))
          (number "17" (effects (font (size 1.27 1.27))))
        )
        (pin power_in line (at 0 0 0) (length 2.54)
          (name "VDD" (effects (font (size 1.27 1.27))))
          (number "2" (effects (font (size 1.27 1.27))))
        )
        (pin power_in line (at 0 -25.4 0) (length 2.54)
          (name "GND" (effects (font (size 1.27 1.27))))
          (number "3" (effects (font (size 1.27 1.27))))
        )
        (pin input line (at 0 -10.16 0) (length 2.54)
          (name "SCL" (effects (font (size 1.27 1.27))))
          (number "4" (effects (font (size 1.27 1.27))))
        )
        (pin bidirectional line (at 0 -7.62 0) (length 2.54)
          (name "SDA" (effects (font (size 1.27 1.27))))
          (number "5" (effects (font (size 1.27 1.27))))
        )
        (pin bidirectional line (at 0 -20.32 0) (length 2.54)
          (name "ADDRSEL" (effects (font (size 1.27 1.27))))
          (number "6" (effects (font (size 1.27 1.27))))
        )
        (pin input line (at 25.4 -17.78 180) (length 2.54)
          (name "IN3-" (effects (font (size 1.27 1.27))))
          (number "7" (effects (font (size 1.27 1.27))))
        )
        (pin input line (at 25.4 -15.24 180) (length 2.54)
          (name "IN3+" (effects (font (size 1.27 1.27))))
          (number "8" (effects (font (size 1.27 1.27))))
        )
        (pin input line (at 25.4 -25.4 180) (length 2.54)
          (name "IN4-" (effects (font (size 1.27 1.27))))
          (number "9" (effects (font (size 1.27 1.27))))
        )
      )
    )
	(symbol "antmicroMicrocontrollers:XC7K160T-FFG676" (in_bom yes) (on_board yes)
      (property "Reference" "U" (at 68.58 2.54 0)
        (effects (font (size 1.27 1.27) (thickness 0.15)) (justify left bottom))
      )
      (property "Value" "XC7K160T-FFG676" (at 68.58 0 0)
        (effects (font (size 1.27 1.27) (thickness 0.15)) (justify left bottom))
      )
      (property "Footprint" "antmicro-footprints:BGA-676_27x27mm_Layout26x26_P1X1mm" (at 68.58 -2.54 0)
        (effects (font (size 1.27 1.27) (thickness 0.15)) (justify left bottom) hide)
      )
      (property "Datasheet" "https://docs.xilinx.com/v/u/en-US/ds180_7Series_Overview" (at 68.58 -5.08 0)
        (effects (font (size 1.27 1.27) (thickness 0.15)) (justify left bottom) hide)
      )
      (property "Author" "Antmicro" (at 68.58 -7.62 0)
        (effects (font (size 1.27 1.27) (thickness 0.15)) (justify left bottom) hide)
      )
      (property "License" "Apache-2.0" (at 68.58 -10.16 0)
        (effects (font (size 1.27 1.27) (thickness 0.15)) (justify left bottom) hide)
      )
      (property "MPN" "XC7K160T-FFG676" (at 0 0 0)
        (effects (font (size 1.27 1.27)) hide)
      )
      (property "Manufacturer" "AMD-Xilinx" (at 0 0 0)
        (effects (font (size 1.27 1.27)) hide)
      )
      (property "ki_locked" "" (at 0 0 0)
        (effects (font (size 1.27 1.27)))
      )
      (property "ki_keywords" "SMT, MICROCONTROLLER, IC, FPGA" (at 0 0 0)
        (effects (font (size 1.27 1.27)) hide)
      )
      (property "ki_description" "Kintex®-7 Field Programmable Gate Array (FPGA) IC 300 4976640 65600 676-BBGA, FCBGA" (at 0 0 0)
        (effects (font (size 1.27 1.27)) hide)
      )
      (symbol "XC7K160T-FFG676_1_1"
        (polyline
          (pts
            (xy 22.86 -3.81)
            (xy 30.48 -3.81)
            (xy 30.48 -130.81)
            (xy 22.86 -130.81)
          )
          (stroke (width 0.254) (type default))
          (fill (type background))
        )
        (rectangle (start 5.08 2.54) (end 33.02 -132.08)
          (stroke (width 0.254) (type default))
          (fill (type background))
        )
        (text "BANK 12" (at 24.13 -1.27 0)
          (effects (font (size 1.27 1.27) (thickness 0.15)) (justify left bottom))
        )
        (pin power_in line (at 0 0 0) (length 5.08)
          (name "VCCO_12" (effects (font (size 1.27 1.27))))
          (number "AA21" (effects (font (size 1.27 1.27))))
        )
        (pin bidirectional line (at 0 -71.12 0) (length 5.08)
          (name "IO_L13N_T2_MRCC_12" (effects (font (size 1.27 1.27))))
          (number "AA22" (effects (font (size 1.27 1.27))))
        )
        (pin bidirectional line (at 0 -58.42 0) (length 5.08)
          (name "IO_L11P_T1_SRCC_12" (effects (font (size 1.27 1.27))))
          (number "AA23" (effects (font (size 1.27 1.27))))
        )
        (pin bidirectional line (at 0 -66.04 0) (length 5.08)
          (name "IO_L12N_T1_MRCC_12" (effects (font (size 1.27 1.27))))
          (number "AA24" (effects (font (size 1.27 1.27))))
        )
        (pin bidirectional line (at 0 -38.1 0) (length 5.08)
          (name "IO_L7P_T1_12" (effects (font (size 1.27 1.27))))
          (number "AA25" (effects (font (size 1.27 1.27))))
        )
        (pin bidirectional line (at 0 -93.98 0) (length 5.08)
          (name "IO_L18P_T2_12" (effects (font (size 1.27 1.27))))
          (number "AB21" (effects (font (size 1.27 1.27))))
        )
        (pin bidirectional line (at 0 -88.9 0) (length 5.08)
          (name "IO_L17P_T2_12" (effects (font (size 1.27 1.27))))
          (number "AB22" (effects (font (size 1.27 1.27))))
        )
        (pin bidirectional line (at 0 -60.96 0) (length 5.08)
          (name "IO_L11N_T1_SRCC_12" (effects (font (size 1.27 1.27))))
          (number "AB24" (effects (font (size 1.27 1.27))))
        )
        (pin bidirectional line (at 0 -40.64 0) (length 5.08)
          (name "IO_L7N_T1_12" (effects (font (size 1.27 1.27))))
          (number "AB25" (effects (font (size 1.27 1.27))))
        )
        (pin bidirectional line (at 0 -48.26 0) (length 5.08)
          (name "IO_L9P_T1_DQS_12" (effects (font (size 1.27 1.27))))
          (number "AB26" (effects (font (size 1.27 1.27))))
        )
        (pin bidirectional line (at 0 -96.52 0) (length 5.08)
          (name "IO_L18N_T2_12" (effects (font (size 1.27 1.27))))
          (number "AC21" (effects (font (size 1.27 1.27))))
        )
        (pin bidirectional line (at 0 -91.44 0) (length 5.08)
          (name "IO_L17N_T2_12" (effects (font (size 1.27 1.27))))
          (number "AC22" (effects (font (size 1.27 1.27))))
        )
        (pin bidirectional line (at 0 -73.66 0) (length 5.08)
          (name "IO_L14P_T2_SRCC_12" (effects (font (size 1.27 1.27))))
          (number "AC23" (effects (font (size 1.27 1.27))))
        )
        (pin bidirectional line (at 0 -76.2 0) (length 5.08)
          (name "IO_L14N_T2_SRCC_12" (effects (font (size 1.27 1.27))))
          (number "AC24" (effects (font (size 1.27 1.27))))
        )
        (pin passive line (at 0 0 0) (length 5.08) hide
          (name "VCCO_12" (effects (font (size 1.27 1.27))))
          (number "AC25" (effects (font (size 1.27 1.27))))
        )
        (pin bidirectional line (at 0 -50.8 0) (length 5.08)
          (name "IO_L9N_T1_DQS_12" (effects (font (size 1.27 1.27))))
          (number "AC26" (effects (font (size 1.27 1.27))))
        )
        (pin bidirectional line (at 0 -99.06 0) (length 5.08)
          (name "IO_L19P_T3_12" (effects (font (size 1.27 1.27))))
          (number "AD21" (effects (font (size 1.27 1.27))))
        )
        (pin passive line (at 0 0 0) (length 5.08) hide
          (name "VCCO_12" (effects (font (size 1.27 1.27))))
          (number "AD22" (effects (font (size 1.27 1.27))))
        )
        (pin bidirectional line (at 0 -83.82 0) (length 5.08)
          (name "IO_L16P_T2_12" (effects (font (size 1.27 1.27))))
          (number "AD23" (effects (font (size 1.27 1.27))))
        )
        (pin bidirectional line (at 0 -86.36 0) (length 5.08)
          (name "IO_L16N_T2_12" (effects (font (size 1.27 1.27))))
          (number "AD24" (effects (font (size 1.27 1.27))))
        )
        (pin bidirectional line (at 0 -119.38 0) (length 5.08)
          (name "IO_L23P_T3_12" (effects (font (size 1.27 1.27))))
          (number "AD25" (effects (font (size 1.27 1.27))))
        )
        (pin bidirectional line (at 0 -109.22 0) (length 5.08)
          (name "IO_L21P_T3_DQS_12" (effects (font (size 1.27 1.27))))
          (number "AD26" (effects (font (size 1.27 1.27))))
        )
        (pin bidirectional line (at 0 -101.6 0) (length 5.08)
          (name "IO_L19N_T3_VREF_12" (effects (font (size 1.27 1.27))))
          (number "AE21" (effects (font (size 1.27 1.27))))
        )
        (pin bidirectional line (at 0 -124.46 0) (length 5.08)
          (name "IO_L24P_T3_12" (effects (font (size 1.27 1.27))))
          (number "AE22" (effects (font (size 1.27 1.27))))
        )
        (pin bidirectional line (at 0 -114.3 0) (length 5.08)
          (name "IO_L22P_T3_12" (effects (font (size 1.27 1.27))))
          (number "AE23" (effects (font (size 1.27 1.27))))
        )
        (pin bidirectional line (at 0 -121.92 0) (length 5.08)
          (name "IO_L23N_T3_12" (effects (font (size 1.27 1.27))))
          (number "AE25" (effects (font (size 1.27 1.27))))
        )
        (pin bidirectional line (at 0 -111.76 0) (length 5.08)
          (name "IO_L21N_T3_DQS_12" (effects (font (size 1.27 1.27))))
          (number "AE26" (effects (font (size 1.27 1.27))))
        )
        (pin bidirectional line (at 0 -127 0) (length 5.08)
          (name "IO_L24N_T3_12" (effects (font (size 1.27 1.27))))
          (number "AF22" (effects (font (size 1.27 1.27))))
        )
        (pin bidirectional line (at 0 -116.84 0) (length 5.08)
          (name "IO_L22N_T3_12" (effects (font (size 1.27 1.27))))
          (number "AF23" (effects (font (size 1.27 1.27))))
        )
        (pin bidirectional line (at 0 -104.14 0) (length 5.08)
          (name "IO_L20P_T3_12" (effects (font (size 1.27 1.27))))
          (number "AF24" (effects (font (size 1.27 1.27))))
        )
        (pin bidirectional line (at 0 -106.68 0) (length 5.08)
          (name "IO_L20N_T3_12" (effects (font (size 1.27 1.27))))
          (number "AF25" (effects (font (size 1.27 1.27))))
        )
        (pin passive line (at 0 0 0) (length 5.08) hide
          (name "VCCO_12" (effects (font (size 1.27 1.27))))
          (number "AF26" (effects (font (size 1.27 1.27))))
        )
        (pin bidirectional line (at 0 -5.08 0) (length 5.08)
          (name "IO_0_12" (effects (font (size 1.27 1.27))))
          (number "U21" (effects (font (size 1.27 1.27))))
        )
        (pin bidirectional line (at 0 -7.62 0) (length 5.08)
          (name "IO_L1P_T0_12" (effects (font (size 1.27 1.27))))
          (number "U22" (effects (font (size 1.27 1.27))))
        )
        (pin passive line (at 0 0 0) (length 5.08) hide
          (name "VCCO_12" (effects (font (size 1.27 1.27))))
          (number "U23" (effects (font (size 1.27 1.27))))
        )
        (pin bidirectional line (at 0 -12.7 0) (length 5.08)
          (name "IO_L2P_T0_12" (effects (font (size 1.27 1.27))))
          (number "U24" (effects (font (size 1.27 1.27))))
        )
        (pin bidirectional line (at 0 -15.24 0) (length 5.08)
          (name "IO_L2N_T0_12" (effects (font (size 1.27 1.27))))
          (number "U25" (effects (font (size 1.27 1.27))))
        )
        (pin bidirectional line (at 0 -22.86 0) (length 5.08)
          (name "IO_L4P_T0_12" (effects (font (size 1.27 1.27))))
          (number "U26" (effects (font (size 1.27 1.27))))
        )
        (pin passive line (at 0 0 0) (length 5.08) hide
          (name "VCCO_12" (effects (font (size 1.27 1.27))))
          (number "V20" (effects (font (size 1.27 1.27))))
        )
        (pin bidirectional line (at 0 -33.02 0) (length 5.08)
          (name "IO_L6P_T0_12" (effects (font (size 1.27 1.27))))
          (number "V21" (effects (font (size 1.27 1.27))))
        )
        (pin bidirectional line (at 0 -10.16 0) (length 5.08)
          (name "IO_L1N_T0_12" (effects (font (size 1.27 1.27))))
          (number "V22" (effects (font (size 1.27 1.27))))
        )
        (pin bidirectional line (at 0 -17.78 0) (length 5.08)
          (name "IO_L3P_T0_DQS_12" (effects (font (size 1.27 1.27))))
          (number "V23" (effects (font (size 1.27 1.27))))
        )
        (pin bidirectional line (at 0 -20.32 0) (length 5.08)
          (name "IO_L3N_T0_DQS_12" (effects (font (size 1.27 1.27))))
          (number "V24" (effects (font (size 1.27 1.27))))
        )
        (pin bidirectional line (at 0 -25.4 0) (length 5.08)
          (name "IO_L4N_T0_12" (effects (font (size 1.27 1.27))))
          (number "V26" (effects (font (size 1.27 1.27))))
        )
        (pin bidirectional line (at 0 -78.74 0) (length 5.08)
          (name "IO_L15P_T2_DQS_12" (effects (font (size 1.27 1.27))))
          (number "W20" (effects (font (size 1.27 1.27))))
        )
        (pin bidirectional line (at 0 -35.56 0) (length 5.08)
          (name "IO_L6N_T0_VREF_12" (effects (font (size 1.27 1.27))))
          (number "W21" (effects (font (size 1.27 1.27))))
        )
        (pin bidirectional line (at 0 -43.18 0) (length 5.08)
          (name "IO_L8P_T1_12" (effects (font (size 1.27 1.27))))
          (number "W23" (effects (font (size 1.27 1.27))))
        )
        (pin bidirectional line (at 0 -45.72 0) (length 5.08)
          (name "IO_L8N_T1_12" (effects (font (size 1.27 1.27))))
          (number "W24" (effects (font (size 1.27 1.27))))
        )
        (pin bidirectional line (at 0 -27.94 0) (length 5.08)
          (name "IO_L5P_T0_12" (effects (font (size 1.27 1.27))))
          (number "W25" (effects (font (size 1.27 1.27))))
        )
        (pin bidirectional line (at 0 -30.48 0) (length 5.08)
          (name "IO_L5N_T0_12" (effects (font (size 1.27 1.27))))
          (number "W26" (effects (font (size 1.27 1.27))))
        )
        (pin bidirectional line (at 0 -129.54 0) (length 5.08)
          (name "IO_25_12" (effects (font (size 1.27 1.27))))
          (number "Y20" (effects (font (size 1.27 1.27))))
        )
        (pin bidirectional line (at 0 -81.28 0) (length 5.08)
          (name "IO_L15N_T2_DQS_12" (effects (font (size 1.27 1.27))))
          (number "Y21" (effects (font (size 1.27 1.27))))
        )
        (pin bidirectional line (at 0 -68.58 0) (length 5.08)
          (name "IO_L13P_T2_MRCC_12" (effects (font (size 1.27 1.27))))
          (number "Y22" (effects (font (size 1.27 1.27))))
        )
        (pin bidirectional line (at 0 -63.5 0) (length 5.08)
          (name "IO_L12P_T1_MRCC_12" (effects (font (size 1.27 1.27))))
          (number "Y23" (effects (font (size 1.27 1.27))))
        )
        (pin passive line (at 0 0 0) (length 5.08) hide
          (name "VCCO_12" (effects (font (size 1.27 1.27))))
          (number "Y24" (effects (font (size 1.27 1.27))))
        )
        (pin bidirectional line (at 0 -53.34 0) (length 5.08)
          (name "IO_L10P_T1_12" (effects (font (size 1.27 1.27))))
          (number "Y25" (effects (font (size 1.27 1.27))))
        )
        (pin bidirectional line (at 0 -55.88 0) (length 5.08)
          (name "IO_L10N_T1_12" (effects (font (size 1.27 1.27))))
          (number "Y26" (effects (font (size 1.27 1.27))))
        )
      )
      (symbol "XC7K160T-FFG676_2_1"
        (polyline
          (pts
            (xy 22.86 -3.81)
            (xy 30.48 -3.81)
            (xy 30.48 -130.81)
            (xy 22.86 -130.81)
          )
          (stroke (width 0.254) (type default))
          (fill (type background))
        )
        (rectangle (start 5.08 -132.08) (end 33.02 2.54)
          (stroke (width 0.254) (type default))
          (fill (type background))
        )
        (text "BANK 13" (at 24.13 -1.27 0)
          (effects (font (size 1.27 1.27) (thickness 0.15)) (justify left bottom))
        )
        (pin power_in line (at 0 0 0) (length 5.08)
          (name "VCCO_13" (effects (font (size 1.27 1.27))))
          (number "K24" (effects (font (size 1.27 1.27))))
        )
        (pin bidirectional line (at 0 -7.62 0) (length 5.08)
          (name "IO_L1P_T0_13" (effects (font (size 1.27 1.27))))
          (number "K25" (effects (font (size 1.27 1.27))))
        )
        (pin bidirectional line (at 0 -10.16 0) (length 5.08)
          (name "IO_L1N_T0_13" (effects (font (size 1.27 1.27))))
          (number "K26" (effects (font (size 1.27 1.27))))
        )
        (pin bidirectional line (at 0 -45.72 0) (length 5.08)
          (name "IO_L8N_T1_13" (effects (font (size 1.27 1.27))))
          (number "L24" (effects (font (size 1.27 1.27))))
        )
        (pin bidirectional line (at 0 -20.32 0) (length 5.08)
          (name "IO_L3N_T0_DQS_13" (effects (font (size 1.27 1.27))))
          (number "L25" (effects (font (size 1.27 1.27))))
        )
        (pin bidirectional line (at 0 -116.84 0) (length 5.08)
          (name "IO_L22N_T3_13" (effects (font (size 1.27 1.27))))
          (number "M19" (effects (font (size 1.27 1.27))))
        )
        (pin bidirectional line (at 0 -40.64 0) (length 5.08)
          (name "IO_L7N_T1_13" (effects (font (size 1.27 1.27))))
          (number "M20" (effects (font (size 1.27 1.27))))
        )
        (pin bidirectional line (at 0 -53.34 0) (length 5.08)
          (name "IO_L10P_T1_13" (effects (font (size 1.27 1.27))))
          (number "M21" (effects (font (size 1.27 1.27))))
        )
        (pin bidirectional line (at 0 -55.88 0) (length 5.08)
          (name "IO_L10N_T1_13" (effects (font (size 1.27 1.27))))
          (number "M22" (effects (font (size 1.27 1.27))))
        )
        (pin bidirectional line (at 0 -43.18 0) (length 5.08)
          (name "IO_L8P_T1_13" (effects (font (size 1.27 1.27))))
          (number "M24" (effects (font (size 1.27 1.27))))
        )
        (pin bidirectional line (at 0 -17.78 0) (length 5.08)
          (name "IO_L3P_T0_DQS_13" (effects (font (size 1.27 1.27))))
          (number "M25" (effects (font (size 1.27 1.27))))
        )
        (pin bidirectional line (at 0 -30.48 0) (length 5.08)
          (name "IO_L5N_T0_13" (effects (font (size 1.27 1.27))))
          (number "M26" (effects (font (size 1.27 1.27))))
        )
        (pin bidirectional line (at 0 -5.08 0) (length 5.08)
          (name "IO_0_13" (effects (font (size 1.27 1.27))))
          (number "N16" (effects (font (size 1.27 1.27))))
        )
        (pin bidirectional line (at 0 -106.68 0) (length 5.08)
          (name "IO_L20N_T3_13" (effects (font (size 1.27 1.27))))
          (number "N17" (effects (font (size 1.27 1.27))))
        )
        (pin bidirectional line (at 0 -114.3 0) (length 5.08)
          (name "IO_L22P_T3_13" (effects (font (size 1.27 1.27))))
          (number "N18" (effects (font (size 1.27 1.27))))
        )
        (pin bidirectional line (at 0 -38.1 0) (length 5.08)
          (name "IO_L7P_T1_13" (effects (font (size 1.27 1.27))))
          (number "N19" (effects (font (size 1.27 1.27))))
        )
        (pin bidirectional line (at 0 -63.5 0) (length 5.08)
          (name "IO_L12P_T1_MRCC_13" (effects (font (size 1.27 1.27))))
          (number "N21" (effects (font (size 1.27 1.27))))
        )
        (pin bidirectional line (at 0 -66.04 0) (length 5.08)
          (name "IO_L12N_T1_MRCC_13" (effects (font (size 1.27 1.27))))
          (number "N22" (effects (font (size 1.27 1.27))))
        )
        (pin bidirectional line (at 0 -60.96 0) (length 5.08)
          (name "IO_L11N_T1_SRCC_13" (effects (font (size 1.27 1.27))))
          (number "N23" (effects (font (size 1.27 1.27))))
        )
        (pin bidirectional line (at 0 -25.4 0) (length 5.08)
          (name "IO_L4N_T0_13" (effects (font (size 1.27 1.27))))
          (number "N24" (effects (font (size 1.27 1.27))))
        )
        (pin passive line (at 0 0 0) (length 5.08) hide
          (name "VCCO_13" (effects (font (size 1.27 1.27))))
          (number "N25" (effects (font (size 1.27 1.27))))
        )
        (pin bidirectional line (at 0 -27.94 0) (length 5.08)
          (name "IO_L5P_T0_13" (effects (font (size 1.27 1.27))))
          (number "N26" (effects (font (size 1.27 1.27))))
        )
        (pin bidirectional line (at 0 -104.14 0) (length 5.08)
          (name "IO_L20P_T3_13" (effects (font (size 1.27 1.27))))
          (number "P16" (effects (font (size 1.27 1.27))))
        )
        (pin bidirectional line (at 0 -127 0) (length 5.08)
          (name "IO_L24N_T3_13" (effects (font (size 1.27 1.27))))
          (number "P18" (effects (font (size 1.27 1.27))))
        )
        (pin bidirectional line (at 0 -48.26 0) (length 5.08)
          (name "IO_L9P_T1_DQS_13" (effects (font (size 1.27 1.27))))
          (number "P19" (effects (font (size 1.27 1.27))))
        )
        (pin bidirectional line (at 0 -50.8 0) (length 5.08)
          (name "IO_L9N_T1_DQS_13" (effects (font (size 1.27 1.27))))
          (number "P20" (effects (font (size 1.27 1.27))))
        )
        (pin bidirectional line (at 0 -71.12 0) (length 5.08)
          (name "IO_L13N_T2_MRCC_13" (effects (font (size 1.27 1.27))))
          (number "P21" (effects (font (size 1.27 1.27))))
        )
        (pin passive line (at 0 0 0) (length 5.08) hide
          (name "VCCO_13" (effects (font (size 1.27 1.27))))
          (number "P22" (effects (font (size 1.27 1.27))))
        )
        (pin bidirectional line (at 0 -58.42 0) (length 5.08)
          (name "IO_L11P_T1_SRCC_13" (effects (font (size 1.27 1.27))))
          (number "P23" (effects (font (size 1.27 1.27))))
        )
        (pin bidirectional line (at 0 -22.86 0) (length 5.08)
          (name "IO_L4P_T0_13" (effects (font (size 1.27 1.27))))
          (number "P24" (effects (font (size 1.27 1.27))))
        )
        (pin bidirectional line (at 0 -35.56 0) (length 5.08)
          (name "IO_L6N_T0_VREF_13" (effects (font (size 1.27 1.27))))
          (number "P25" (effects (font (size 1.27 1.27))))
        )
        (pin bidirectional line (at 0 -15.24 0) (length 5.08)
          (name "IO_L2N_T0_13" (effects (font (size 1.27 1.27))))
          (number "P26" (effects (font (size 1.27 1.27))))
        )
        (pin bidirectional line (at 0 -109.22 0) (length 5.08)
          (name "IO_L21P_T3_DQS_13" (effects (font (size 1.27 1.27))))
          (number "R16" (effects (font (size 1.27 1.27))))
        )
        (pin bidirectional line (at 0 -111.76 0) (length 5.08)
          (name "IO_L21N_T3_DQS_13" (effects (font (size 1.27 1.27))))
          (number "R17" (effects (font (size 1.27 1.27))))
        )
        (pin bidirectional line (at 0 -124.46 0) (length 5.08)
          (name "IO_L24P_T3_13" (effects (font (size 1.27 1.27))))
          (number "R18" (effects (font (size 1.27 1.27))))
        )
        (pin passive line (at 0 0 0) (length 5.08) hide
          (name "VCCO_13" (effects (font (size 1.27 1.27))))
          (number "R19" (effects (font (size 1.27 1.27))))
        )
        (pin bidirectional line (at 0 -86.36 0) (length 5.08)
          (name "IO_L16N_T2_13" (effects (font (size 1.27 1.27))))
          (number "R20" (effects (font (size 1.27 1.27))))
        )
        (pin bidirectional line (at 0 -68.58 0) (length 5.08)
          (name "IO_L13P_T2_MRCC_13" (effects (font (size 1.27 1.27))))
          (number "R21" (effects (font (size 1.27 1.27))))
        )
        (pin bidirectional line (at 0 -73.66 0) (length 5.08)
          (name "IO_L14P_T2_SRCC_13" (effects (font (size 1.27 1.27))))
          (number "R22" (effects (font (size 1.27 1.27))))
        )
        (pin bidirectional line (at 0 -76.2 0) (length 5.08)
          (name "IO_L14N_T2_SRCC_13" (effects (font (size 1.27 1.27))))
          (number "R23" (effects (font (size 1.27 1.27))))
        )
        (pin bidirectional line (at 0 -33.02 0) (length 5.08)
          (name "IO_L6P_T0_13" (effects (font (size 1.27 1.27))))
          (number "R25" (effects (font (size 1.27 1.27))))
        )
        (pin bidirectional line (at 0 -12.7 0) (length 5.08)
          (name "IO_L2P_T0_13" (effects (font (size 1.27 1.27))))
          (number "R26" (effects (font (size 1.27 1.27))))
        )
        (pin passive line (at 0 0 0) (length 5.08) hide
          (name "VCCO_13" (effects (font (size 1.27 1.27))))
          (number "T16" (effects (font (size 1.27 1.27))))
        )
        (pin bidirectional line (at 0 -121.92 0) (length 5.08)
          (name "IO_L23N_T3_13" (effects (font (size 1.27 1.27))))
          (number "T17" (effects (font (size 1.27 1.27))))
        )
        (pin bidirectional line (at 0 -99.06 0) (length 5.08)
          (name "IO_L19P_T3_13" (effects (font (size 1.27 1.27))))
          (number "T18" (effects (font (size 1.27 1.27))))
        )
        (pin bidirectional line (at 0 -101.6 0) (length 5.08)
          (name "IO_L19N_T3_VREF_13" (effects (font (size 1.27 1.27))))
          (number "T19" (effects (font (size 1.27 1.27))))
        )
        (pin bidirectional line (at 0 -83.82 0) (length 5.08)
          (name "IO_L16P_T2_13" (effects (font (size 1.27 1.27))))
          (number "T20" (effects (font (size 1.27 1.27))))
        )
        (pin bidirectional line (at 0 -88.9 0) (length 5.08)
          (name "IO_L17P_T2_13" (effects (font (size 1.27 1.27))))
          (number "T22" (effects (font (size 1.27 1.27))))
        )
        (pin bidirectional line (at 0 -91.44 0) (length 5.08)
          (name "IO_L17N_T2_13" (effects (font (size 1.27 1.27))))
          (number "T23" (effects (font (size 1.27 1.27))))
        )
        (pin bidirectional line (at 0 -78.74 0) (length 5.08)
          (name "IO_L15P_T2_DQS_13" (effects (font (size 1.27 1.27))))
          (number "T24" (effects (font (size 1.27 1.27))))
        )
        (pin bidirectional line (at 0 -81.28 0) (length 5.08)
          (name "IO_L15N_T2_DQS_13" (effects (font (size 1.27 1.27))))
          (number "T25" (effects (font (size 1.27 1.27))))
        )
        (pin passive line (at 0 0 0) (length 5.08) hide
          (name "VCCO_13" (effects (font (size 1.27 1.27))))
          (number "T26" (effects (font (size 1.27 1.27))))
        )
        (pin bidirectional line (at 0 -129.54 0) (length 5.08)
          (name "IO_25_13" (effects (font (size 1.27 1.27))))
          (number "U16" (effects (font (size 1.27 1.27))))
        )
        (pin bidirectional line (at 0 -119.38 0) (length 5.08)
          (name "IO_L23P_T3_13" (effects (font (size 1.27 1.27))))
          (number "U17" (effects (font (size 1.27 1.27))))
        )
        (pin bidirectional line (at 0 -93.98 0) (length 5.08)
          (name "IO_L18P_T2_13" (effects (font (size 1.27 1.27))))
          (number "U19" (effects (font (size 1.27 1.27))))
        )
        (pin bidirectional line (at 0 -96.52 0) (length 5.08)
          (name "IO_L18N_T2_13" (effects (font (size 1.27 1.27))))
          (number "U20" (effects (font (size 1.27 1.27))))
        )
      )
      (symbol "XC7K160T-FFG676_3_1"
        (polyline
          (pts
            (xy 30.48 -3.81)
            (xy 38.1 -3.81)
            (xy 38.1 -130.81)
            (xy 30.48 -130.81)
          )
          (stroke (width 0.254) (type default))
          (fill (type background))
        )
        (rectangle (start 5.08 2.54) (end 40.64 -132.08)
          (stroke (width 0.254) (type default))
          (fill (type background))
        )
        (text "BANK 14" (at 31.75 -1.27 0)
          (effects (font (size 1.27 1.27) (thickness 0.15)) (justify left bottom))
        )
        (pin bidirectional line (at 0 -45.72 0) (length 5.08)
          (name "IO_L8N_T1_D12_14" (effects (font (size 1.27 1.27))))
          (number "A20" (effects (font (size 1.27 1.27))))
        )
        (pin power_in line (at 0 0 0) (length 5.08)
          (name "VCCO_14" (effects (font (size 1.27 1.27))))
          (number "A21" (effects (font (size 1.27 1.27))))
        )
        (pin bidirectional line (at 0 -15.24 0) (length 5.08)
          (name "IO_L2N_T0_D03_14" (effects (font (size 1.27 1.27))))
          (number "A22" (effects (font (size 1.27 1.27))))
        )
        (pin bidirectional line (at 0 -22.86 0) (length 5.08)
          (name "IO_L4P_T0_D04_14" (effects (font (size 1.27 1.27))))
          (number "A23" (effects (font (size 1.27 1.27))))
        )
        (pin bidirectional line (at 0 -25.4 0) (length 5.08)
          (name "IO_L4N_T0_D05_14" (effects (font (size 1.27 1.27))))
          (number "A24" (effects (font (size 1.27 1.27))))
        )
        (pin bidirectional line (at 0 -10.16 0) (length 5.08)
          (name "IO_L1N_T0_D01_DIN_14" (effects (font (size 1.27 1.27))))
          (number "A25" (effects (font (size 1.27 1.27))))
        )
        (pin bidirectional line (at 0 -43.18 0) (length 5.08)
          (name "IO_L8P_T1_D11_14" (effects (font (size 1.27 1.27))))
          (number "B20" (effects (font (size 1.27 1.27))))
        )
        (pin bidirectional line (at 0 -55.88 0) (length 5.08)
          (name "IO_L10N_T1_D15_14" (effects (font (size 1.27 1.27))))
          (number "B21" (effects (font (size 1.27 1.27))))
        )
        (pin bidirectional line (at 0 -12.7 0) (length 5.08)
          (name "IO_L2P_T0_D02_14" (effects (font (size 1.27 1.27))))
          (number "B22" (effects (font (size 1.27 1.27))))
        )
        (pin bidirectional line (at 0 -7.62 0) (length 5.08)
          (name "IO_L1P_T0_D00_MOSI_14" (effects (font (size 1.27 1.27))))
          (number "B24" (effects (font (size 1.27 1.27))))
        )
        (pin bidirectional line (at 0 -17.78 0) (length 5.08)
          (name "IO_L3P_T0_DQS_PUDC_B_14" (effects (font (size 1.27 1.27))))
          (number "B25" (effects (font (size 1.27 1.27))))
        )
        (pin bidirectional line (at 0 -20.32 0) (length 5.08)
          (name "IO_L3N_T0_DQS_EMCCLK_14" (effects (font (size 1.27 1.27))))
          (number "B26" (effects (font (size 1.27 1.27))))
        )
        (pin bidirectional line (at 0 -53.34 0) (length 5.08)
          (name "IO_L10P_T1_D14_14" (effects (font (size 1.27 1.27))))
          (number "C21" (effects (font (size 1.27 1.27))))
        )
        (pin bidirectional line (at 0 -40.64 0) (length 5.08)
          (name "IO_L7N_T1_D10_14" (effects (font (size 1.27 1.27))))
          (number "C22" (effects (font (size 1.27 1.27))))
        )
        (pin bidirectional line (at 0 -33.02 0) (length 5.08)
          (name "IO_L6P_T0_FCS_B_14" (effects (font (size 1.27 1.27))))
          (number "C23" (effects (font (size 1.27 1.27))))
        )
        (pin bidirectional line (at 0 -35.56 0) (length 5.08)
          (name "IO_L6N_T0_D08_VREF_14" (effects (font (size 1.27 1.27))))
          (number "C24" (effects (font (size 1.27 1.27))))
        )
        (pin passive line (at 0 0 0) (length 5.08) hide
          (name "VCCO_14" (effects (font (size 1.27 1.27))))
          (number "C25" (effects (font (size 1.27 1.27))))
        )
        (pin bidirectional line (at 0 -30.48 0) (length 5.08)
          (name "IO_L5N_T0_D07_14" (effects (font (size 1.27 1.27))))
          (number "C26" (effects (font (size 1.27 1.27))))
        )
        (pin bidirectional line (at 0 -38.1 0) (length 5.08)
          (name "IO_L7P_T1_D09_14" (effects (font (size 1.27 1.27))))
          (number "D21" (effects (font (size 1.27 1.27))))
        )
        (pin passive line (at 0 0 0) (length 5.08) hide
          (name "VCCO_14" (effects (font (size 1.27 1.27))))
          (number "D22" (effects (font (size 1.27 1.27))))
        )
        (pin bidirectional line (at 0 -58.42 0) (length 5.08)
          (name "IO_L11P_T1_SRCC_14" (effects (font (size 1.27 1.27))))
          (number "D23" (effects (font (size 1.27 1.27))))
        )
        (pin bidirectional line (at 0 -60.96 0) (length 5.08)
          (name "IO_L11N_T1_SRCC_14" (effects (font (size 1.27 1.27))))
          (number "D24" (effects (font (size 1.27 1.27))))
        )
        (pin bidirectional line (at 0 -81.28 0) (length 5.08)
          (name "IO_L15N_T2_DQS_DOUT_CSO_B_14" (effects (font (size 1.27 1.27))))
          (number "D25" (effects (font (size 1.27 1.27))))
        )
        (pin bidirectional line (at 0 -27.94 0) (length 5.08)
          (name "IO_L5P_T0_D06_14" (effects (font (size 1.27 1.27))))
          (number "D26" (effects (font (size 1.27 1.27))))
        )
        (pin bidirectional line (at 0 -48.26 0) (length 5.08)
          (name "IO_L9P_T1_DQS_14" (effects (font (size 1.27 1.27))))
          (number "E21" (effects (font (size 1.27 1.27))))
        )
        (pin bidirectional line (at 0 -50.8 0) (length 5.08)
          (name "IO_L9N_T1_DQS_D13_14" (effects (font (size 1.27 1.27))))
          (number "E22" (effects (font (size 1.27 1.27))))
        )
        (pin bidirectional line (at 0 -66.04 0) (length 5.08)
          (name "IO_L12N_T1_MRCC_14" (effects (font (size 1.27 1.27))))
          (number "E23" (effects (font (size 1.27 1.27))))
        )
        (pin bidirectional line (at 0 -78.74 0) (length 5.08)
          (name "IO_L15P_T2_DQS_RDWR_B_14" (effects (font (size 1.27 1.27))))
          (number "E25" (effects (font (size 1.27 1.27))))
        )
        (pin bidirectional line (at 0 -91.44 0) (length 5.08)
          (name "IO_L17N_T2_A13_D29_14" (effects (font (size 1.27 1.27))))
          (number "E26" (effects (font (size 1.27 1.27))))
        )
        (pin bidirectional line (at 0 -63.5 0) (length 5.08)
          (name "IO_L12P_T1_MRCC_14" (effects (font (size 1.27 1.27))))
          (number "F22" (effects (font (size 1.27 1.27))))
        )
        (pin bidirectional line (at 0 -71.12 0) (length 5.08)
          (name "IO_L13N_T2_MRCC_14" (effects (font (size 1.27 1.27))))
          (number "F23" (effects (font (size 1.27 1.27))))
        )
        (pin bidirectional line (at 0 -76.2 0) (length 5.08)
          (name "IO_L14N_T2_SRCC_14" (effects (font (size 1.27 1.27))))
          (number "F24" (effects (font (size 1.27 1.27))))
        )
        (pin bidirectional line (at 0 -88.9 0) (length 5.08)
          (name "IO_L17P_T2_A14_D30_14" (effects (font (size 1.27 1.27))))
          (number "F25" (effects (font (size 1.27 1.27))))
        )
        (pin passive line (at 0 0 0) (length 5.08) hide
          (name "VCCO_14" (effects (font (size 1.27 1.27))))
          (number "F26" (effects (font (size 1.27 1.27))))
        )
        (pin bidirectional line (at 0 -101.6 0) (length 5.08)
          (name "IO_L19N_T3_A09_D25_VREF_14" (effects (font (size 1.27 1.27))))
          (number "G21" (effects (font (size 1.27 1.27))))
        )
        (pin bidirectional line (at 0 -68.58 0) (length 5.08)
          (name "IO_L13P_T2_MRCC_14" (effects (font (size 1.27 1.27))))
          (number "G22" (effects (font (size 1.27 1.27))))
        )
        (pin passive line (at 0 0 0) (length 5.08) hide
          (name "VCCO_14" (effects (font (size 1.27 1.27))))
          (number "G23" (effects (font (size 1.27 1.27))))
        )
        (pin bidirectional line (at 0 -73.66 0) (length 5.08)
          (name "IO_L14P_T2_SRCC_14" (effects (font (size 1.27 1.27))))
          (number "G24" (effects (font (size 1.27 1.27))))
        )
        (pin bidirectional line (at 0 -83.82 0) (length 5.08)
          (name "IO_L16P_T2_CSI_B_14" (effects (font (size 1.27 1.27))))
          (number "G25" (effects (font (size 1.27 1.27))))
        )
        (pin bidirectional line (at 0 -86.36 0) (length 5.08)
          (name "IO_L16N_T2_A15_D31_14" (effects (font (size 1.27 1.27))))
          (number "G26" (effects (font (size 1.27 1.27))))
        )
        (pin bidirectional line (at 0 -99.06 0) (length 5.08)
          (name "IO_L19P_T3_A10_D26_14" (effects (font (size 1.27 1.27))))
          (number "H21" (effects (font (size 1.27 1.27))))
        )
        (pin bidirectional line (at 0 -111.76 0) (length 5.08)
          (name "IO_L21N_T3_DQS_A06_D22_14" (effects (font (size 1.27 1.27))))
          (number "H22" (effects (font (size 1.27 1.27))))
        )
        (pin bidirectional line (at 0 -104.14 0) (length 5.08)
          (name "IO_L20P_T3_A08_D24_14" (effects (font (size 1.27 1.27))))
          (number "H23" (effects (font (size 1.27 1.27))))
        )
        (pin bidirectional line (at 0 -106.68 0) (length 5.08)
          (name "IO_L20N_T3_A07_D23_14" (effects (font (size 1.27 1.27))))
          (number "H24" (effects (font (size 1.27 1.27))))
        )
        (pin bidirectional line (at 0 -96.52 0) (length 5.08)
          (name "IO_L18N_T2_A11_D27_14" (effects (font (size 1.27 1.27))))
          (number "H26" (effects (font (size 1.27 1.27))))
        )
        (pin bidirectional line (at 0 -109.22 0) (length 5.08)
          (name "IO_L21P_T3_DQS_14" (effects (font (size 1.27 1.27))))
          (number "J21" (effects (font (size 1.27 1.27))))
        )
        (pin bidirectional line (at 0 -127 0) (length 5.08)
          (name "IO_L24N_T3_A00_D16_14" (effects (font (size 1.27 1.27))))
          (number "J23" (effects (font (size 1.27 1.27))))
        )
        (pin bidirectional line (at 0 -114.3 0) (length 5.08)
          (name "IO_L22P_T3_A05_D21_14" (effects (font (size 1.27 1.27))))
          (number "J24" (effects (font (size 1.27 1.27))))
        )
        (pin bidirectional line (at 0 -116.84 0) (length 5.08)
          (name "IO_L22N_T3_A04_D20_14" (effects (font (size 1.27 1.27))))
          (number "J25" (effects (font (size 1.27 1.27))))
        )
        (pin bidirectional line (at 0 -93.98 0) (length 5.08)
          (name "IO_L18P_T2_A12_D28_14" (effects (font (size 1.27 1.27))))
          (number "J26" (effects (font (size 1.27 1.27))))
        )
        (pin bidirectional line (at 0 -5.08 0) (length 5.08)
          (name "IO_0_14" (effects (font (size 1.27 1.27))))
          (number "K21" (effects (font (size 1.27 1.27))))
        )
        (pin bidirectional line (at 0 -121.92 0) (length 5.08)
          (name "IO_L23N_T3_A02_D18_14" (effects (font (size 1.27 1.27))))
          (number "K22" (effects (font (size 1.27 1.27))))
        )
        (pin bidirectional line (at 0 -124.46 0) (length 5.08)
          (name "IO_L24P_T3_A01_D17_14" (effects (font (size 1.27 1.27))))
          (number "K23" (effects (font (size 1.27 1.27))))
        )
        (pin passive line (at 0 0 0) (length 5.08) hide
          (name "VCCO_14" (effects (font (size 1.27 1.27))))
          (number "L21" (effects (font (size 1.27 1.27))))
        )
        (pin bidirectional line (at 0 -119.38 0) (length 5.08)
          (name "IO_L23P_T3_A03_D19_14" (effects (font (size 1.27 1.27))))
          (number "L22" (effects (font (size 1.27 1.27))))
        )
        (pin bidirectional line (at 0 -129.54 0) (length 5.08)
          (name "IO_25_14" (effects (font (size 1.27 1.27))))
          (number "L23" (effects (font (size 1.27 1.27))))
        )
      )
      (symbol "XC7K160T-FFG676_4_1"
        (polyline
          (pts
            (xy 30.48 -3.81)
            (xy 38.1 -3.81)
            (xy 38.1 -130.81)
            (xy 30.48 -130.81)
          )
          (stroke (width 0.254) (type default))
          (fill (type background))
        )
        (rectangle (start 5.08 2.54) (end 40.64 -132.08)
          (stroke (width 0.254) (type default))
          (fill (type background))
        )
        (text "BANK 15" (at 31.75 -1.27 0)
          (effects (font (size 1.27 1.27) (thickness 0.15)) (justify left bottom))
        )
        (pin bidirectional line (at 0 -20.32 0) (length 5.08)
          (name "IO_L3N_T0_DQS_AD1N_15" (effects (font (size 1.27 1.27))))
          (number "A17" (effects (font (size 1.27 1.27))))
        )
        (pin bidirectional line (at 0 -12.7 0) (length 5.08)
          (name "IO_L2P_T0_AD8P_15" (effects (font (size 1.27 1.27))))
          (number "A18" (effects (font (size 1.27 1.27))))
        )
        (pin bidirectional line (at 0 -15.24 0) (length 5.08)
          (name "IO_L2N_T0_AD8N_15" (effects (font (size 1.27 1.27))))
          (number "A19" (effects (font (size 1.27 1.27))))
        )
        (pin bidirectional line (at 0 -10.16 0) (length 5.08)
          (name "IO_L1N_T0_AD0N_15" (effects (font (size 1.27 1.27))))
          (number "B16" (effects (font (size 1.27 1.27))))
        )
        (pin bidirectional line (at 0 -17.78 0) (length 5.08)
          (name "IO_L3P_T0_DQS_AD1P_15" (effects (font (size 1.27 1.27))))
          (number "B17" (effects (font (size 1.27 1.27))))
        )
        (pin power_in line (at 0 0 0) (length 5.08)
          (name "VCCO_15" (effects (font (size 1.27 1.27))))
          (number "B18" (effects (font (size 1.27 1.27))))
        )
        (pin bidirectional line (at 0 -25.4 0) (length 5.08)
          (name "IO_L4N_T0_AD9N_15" (effects (font (size 1.27 1.27))))
          (number "B19" (effects (font (size 1.27 1.27))))
        )
        (pin bidirectional line (at 0 -7.62 0) (length 5.08)
          (name "IO_L1P_T0_AD0P_15" (effects (font (size 1.27 1.27))))
          (number "C16" (effects (font (size 1.27 1.27))))
        )
        (pin bidirectional line (at 0 -27.94 0) (length 5.08)
          (name "IO_L5P_T0_AD2P_15" (effects (font (size 1.27 1.27))))
          (number "C17" (effects (font (size 1.27 1.27))))
        )
        (pin bidirectional line (at 0 -30.48 0) (length 5.08)
          (name "IO_L5N_T0_AD2N_15" (effects (font (size 1.27 1.27))))
          (number "C18" (effects (font (size 1.27 1.27))))
        )
        (pin bidirectional line (at 0 -22.86 0) (length 5.08)
          (name "IO_L4P_T0_AD9P_15" (effects (font (size 1.27 1.27))))
          (number "C19" (effects (font (size 1.27 1.27))))
        )
        (pin bidirectional line (at 0 -33.02 0) (length 5.08)
          (name "IO_L6P_T0_15" (effects (font (size 1.27 1.27))))
          (number "D15" (effects (font (size 1.27 1.27))))
        )
        (pin bidirectional line (at 0 -35.56 0) (length 5.08)
          (name "IO_L6N_T0_VREF_15" (effects (font (size 1.27 1.27))))
          (number "D16" (effects (font (size 1.27 1.27))))
        )
        (pin bidirectional line (at 0 -71.12 0) (length 5.08)
          (name "IO_L13N_T2_MRCC_15" (effects (font (size 1.27 1.27))))
          (number "D18" (effects (font (size 1.27 1.27))))
        )
        (pin bidirectional line (at 0 -78.74 0) (length 5.08)
          (name "IO_L15P_T2_DQS_15" (effects (font (size 1.27 1.27))))
          (number "D19" (effects (font (size 1.27 1.27))))
        )
        (pin bidirectional line (at 0 -81.28 0) (length 5.08)
          (name "IO_L15N_T2_DQS_ADV_B_15" (effects (font (size 1.27 1.27))))
          (number "D20" (effects (font (size 1.27 1.27))))
        )
        (pin bidirectional line (at 0 -53.34 0) (length 5.08)
          (name "IO_L10P_T1_AD4P_15" (effects (font (size 1.27 1.27))))
          (number "E15" (effects (font (size 1.27 1.27))))
        )
        (pin bidirectional line (at 0 -55.88 0) (length 5.08)
          (name "IO_L10N_T1_AD4N_15" (effects (font (size 1.27 1.27))))
          (number "E16" (effects (font (size 1.27 1.27))))
        )
        (pin bidirectional line (at 0 -66.04 0) (length 5.08)
          (name "IO_L12N_T1_MRCC_AD5N_15" (effects (font (size 1.27 1.27))))
          (number "E17" (effects (font (size 1.27 1.27))))
        )
        (pin bidirectional line (at 0 -68.58 0) (length 5.08)
          (name "IO_L13P_T2_MRCC_15" (effects (font (size 1.27 1.27))))
          (number "E18" (effects (font (size 1.27 1.27))))
        )
        (pin passive line (at 0 0 0) (length 5.08) hide
          (name "VCCO_15" (effects (font (size 1.27 1.27))))
          (number "E19" (effects (font (size 1.27 1.27))))
        )
        (pin bidirectional line (at 0 -91.44 0) (length 5.08)
          (name "IO_L17N_T2_A25_15" (effects (font (size 1.27 1.27))))
          (number "E20" (effects (font (size 1.27 1.27))))
        )
        (pin bidirectional line (at 0 -45.72 0) (length 5.08)
          (name "IO_L8N_T1_AD3N_15" (effects (font (size 1.27 1.27))))
          (number "F15" (effects (font (size 1.27 1.27))))
        )
        (pin passive line (at 0 0 0) (length 5.08) hide
          (name "VCCO_15" (effects (font (size 1.27 1.27))))
          (number "F16" (effects (font (size 1.27 1.27))))
        )
        (pin bidirectional line (at 0 -63.5 0) (length 5.08)
          (name "IO_L12P_T1_MRCC_AD5P_15" (effects (font (size 1.27 1.27))))
          (number "F17" (effects (font (size 1.27 1.27))))
        )
        (pin bidirectional line (at 0 -60.96 0) (length 5.08)
          (name "IO_L11N_T1_SRCC_AD12N_15" (effects (font (size 1.27 1.27))))
          (number "F18" (effects (font (size 1.27 1.27))))
        )
        (pin bidirectional line (at 0 -88.9 0) (length 5.08)
          (name "IO_L17P_T2_A26_15" (effects (font (size 1.27 1.27))))
          (number "F19" (effects (font (size 1.27 1.27))))
        )
        (pin bidirectional line (at 0 -86.36 0) (length 5.08)
          (name "IO_L16N_T2_A27_15" (effects (font (size 1.27 1.27))))
          (number "F20" (effects (font (size 1.27 1.27))))
        )
        (pin bidirectional line (at 0 -43.18 0) (length 5.08)
          (name "IO_L8P_T1_AD3P_15" (effects (font (size 1.27 1.27))))
          (number "G15" (effects (font (size 1.27 1.27))))
        )
        (pin bidirectional line (at 0 -40.64 0) (length 5.08)
          (name "IO_L7N_T1_AD10N_15" (effects (font (size 1.27 1.27))))
          (number "G16" (effects (font (size 1.27 1.27))))
        )
        (pin bidirectional line (at 0 -58.42 0) (length 5.08)
          (name "IO_L11P_T1_SRCC_AD12P_15" (effects (font (size 1.27 1.27))))
          (number "G17" (effects (font (size 1.27 1.27))))
        )
        (pin bidirectional line (at 0 -83.82 0) (length 5.08)
          (name "IO_L16P_T2_A28_15" (effects (font (size 1.27 1.27))))
          (number "G19" (effects (font (size 1.27 1.27))))
        )
        (pin bidirectional line (at 0 -96.52 0) (length 5.08)
          (name "IO_L18N_T2_A23_15" (effects (font (size 1.27 1.27))))
          (number "G20" (effects (font (size 1.27 1.27))))
        )
        (pin bidirectional line (at 0 -38.1 0) (length 5.08)
          (name "IO_L7P_T1_AD10P_15" (effects (font (size 1.27 1.27))))
          (number "H16" (effects (font (size 1.27 1.27))))
        )
        (pin bidirectional line (at 0 -73.66 0) (length 5.08)
          (name "IO_L14P_T2_SRCC_15" (effects (font (size 1.27 1.27))))
          (number "H17" (effects (font (size 1.27 1.27))))
        )
        (pin bidirectional line (at 0 -76.2 0) (length 5.08)
          (name "IO_L14N_T2_SRCC_15" (effects (font (size 1.27 1.27))))
          (number "H18" (effects (font (size 1.27 1.27))))
        )
        (pin bidirectional line (at 0 -93.98 0) (length 5.08)
          (name "IO_L18P_T2_A24_15" (effects (font (size 1.27 1.27))))
          (number "H19" (effects (font (size 1.27 1.27))))
        )
        (pin passive line (at 0 0 0) (length 5.08) hide
          (name "VCCO_15" (effects (font (size 1.27 1.27))))
          (number "H20" (effects (font (size 1.27 1.27))))
        )
        (pin bidirectional line (at 0 -48.26 0) (length 5.08)
          (name "IO_L9P_T1_DQS_AD11P_15" (effects (font (size 1.27 1.27))))
          (number "J15" (effects (font (size 1.27 1.27))))
        )
        (pin bidirectional line (at 0 -50.8 0) (length 5.08)
          (name "IO_L9N_T1_DQS_AD11N_15" (effects (font (size 1.27 1.27))))
          (number "J16" (effects (font (size 1.27 1.27))))
        )
        (pin passive line (at 0 0 0) (length 5.08) hide
          (name "VCCO_15" (effects (font (size 1.27 1.27))))
          (number "J17" (effects (font (size 1.27 1.27))))
        )
        (pin bidirectional line (at 0 -104.14 0) (length 5.08)
          (name "IO_L20P_T3_A20_15" (effects (font (size 1.27 1.27))))
          (number "J18" (effects (font (size 1.27 1.27))))
        )
        (pin bidirectional line (at 0 -106.68 0) (length 5.08)
          (name "IO_L20N_T3_A19_15" (effects (font (size 1.27 1.27))))
          (number "J19" (effects (font (size 1.27 1.27))))
        )
        (pin bidirectional line (at 0 -101.6 0) (length 5.08)
          (name "IO_L19N_T3_A21_VREF_15" (effects (font (size 1.27 1.27))))
          (number "J20" (effects (font (size 1.27 1.27))))
        )
        (pin bidirectional line (at 0 -5.08 0) (length 5.08)
          (name "IO_0_15" (effects (font (size 1.27 1.27))))
          (number "K15" (effects (font (size 1.27 1.27))))
        )
        (pin bidirectional line (at 0 -114.3 0) (length 5.08)
          (name "IO_L22P_T3_A17_15" (effects (font (size 1.27 1.27))))
          (number "K16" (effects (font (size 1.27 1.27))))
        )
        (pin bidirectional line (at 0 -116.84 0) (length 5.08)
          (name "IO_L22N_T3_A16_15" (effects (font (size 1.27 1.27))))
          (number "K17" (effects (font (size 1.27 1.27))))
        )
        (pin bidirectional line (at 0 -127 0) (length 5.08)
          (name "IO_L24N_T3_RS0_15" (effects (font (size 1.27 1.27))))
          (number "K18" (effects (font (size 1.27 1.27))))
        )
        (pin bidirectional line (at 0 -99.06 0) (length 5.08)
          (name "IO_L19P_T3_A22_15" (effects (font (size 1.27 1.27))))
          (number "K20" (effects (font (size 1.27 1.27))))
        )
        (pin bidirectional line (at 0 -124.46 0) (length 5.08)
          (name "IO_L24P_T3_RS1_15" (effects (font (size 1.27 1.27))))
          (number "L17" (effects (font (size 1.27 1.27))))
        )
        (pin bidirectional line (at 0 -121.92 0) (length 5.08)
          (name "IO_L23N_T3_FWE_B_15" (effects (font (size 1.27 1.27))))
          (number "L18" (effects (font (size 1.27 1.27))))
        )
        (pin bidirectional line (at 0 -109.22 0) (length 5.08)
          (name "IO_L21P_T3_DQS_15" (effects (font (size 1.27 1.27))))
          (number "L19" (effects (font (size 1.27 1.27))))
        )
        (pin bidirectional line (at 0 -111.76 0) (length 5.08)
          (name "IO_L21N_T3_DQS_A18_15" (effects (font (size 1.27 1.27))))
          (number "L20" (effects (font (size 1.27 1.27))))
        )
        (pin bidirectional line (at 0 -129.54 0) (length 5.08)
          (name "IO_25_15" (effects (font (size 1.27 1.27))))
          (number "M16" (effects (font (size 1.27 1.27))))
        )
        (pin bidirectional line (at 0 -119.38 0) (length 5.08)
          (name "IO_L23P_T3_FOE_B_15" (effects (font (size 1.27 1.27))))
          (number "M17" (effects (font (size 1.27 1.27))))
        )
        (pin passive line (at 0 0 0) (length 5.08) hide
          (name "VCCO_15" (effects (font (size 1.27 1.27))))
          (number "M18" (effects (font (size 1.27 1.27))))
        )
      )
      (symbol "XC7K160T-FFG676_5_1"
        (polyline
          (pts
            (xy 22.86 -3.81)
            (xy 30.48 -3.81)
            (xy 30.48 -130.81)
            (xy 22.86 -130.81)
          )
          (stroke (width 0.254) (type default))
          (fill (type background))
        )
        (rectangle (start 5.08 -132.08) (end 33.02 2.54)
          (stroke (width 0.254) (type default))
          (fill (type background))
        )
        (text "BANK 16" (at 24.13 -1.27 0)
          (effects (font (size 1.27 1.27) (thickness 0.15)) (justify left bottom))
        )
        (pin bidirectional line (at 0 -116.84 0) (length 5.08)
          (name "IO_L22N_T3_16" (effects (font (size 1.27 1.27))))
          (number "A10" (effects (font (size 1.27 1.27))))
        )
        (pin power_in line (at 0 0 0) (length 5.08)
          (name "VCCO_16" (effects (font (size 1.27 1.27))))
          (number "A11" (effects (font (size 1.27 1.27))))
        )
        (pin bidirectional line (at 0 -127 0) (length 5.08)
          (name "IO_L24N_T3_16" (effects (font (size 1.27 1.27))))
          (number "A12" (effects (font (size 1.27 1.27))))
        )
        (pin bidirectional line (at 0 -124.46 0) (length 5.08)
          (name "IO_L24P_T3_16" (effects (font (size 1.27 1.27))))
          (number "A13" (effects (font (size 1.27 1.27))))
        )
        (pin bidirectional line (at 0 -111.76 0) (length 5.08)
          (name "IO_L21N_T3_DQS_16" (effects (font (size 1.27 1.27))))
          (number "A14" (effects (font (size 1.27 1.27))))
        )
        (pin bidirectional line (at 0 -121.92 0) (length 5.08)
          (name "IO_L23N_T3_16" (effects (font (size 1.27 1.27))))
          (number "A15" (effects (font (size 1.27 1.27))))
        )
        (pin bidirectional line (at 0 -50.8 0) (length 5.08)
          (name "IO_L9N_T1_DQS_16" (effects (font (size 1.27 1.27))))
          (number "A8" (effects (font (size 1.27 1.27))))
        )
        (pin bidirectional line (at 0 -48.26 0) (length 5.08)
          (name "IO_L9P_T1_DQS_16" (effects (font (size 1.27 1.27))))
          (number "A9" (effects (font (size 1.27 1.27))))
        )
        (pin bidirectional line (at 0 -114.3 0) (length 5.08)
          (name "IO_L22P_T3_16" (effects (font (size 1.27 1.27))))
          (number "B10" (effects (font (size 1.27 1.27))))
        )
        (pin bidirectional line (at 0 -106.68 0) (length 5.08)
          (name "IO_L20N_T3_16" (effects (font (size 1.27 1.27))))
          (number "B11" (effects (font (size 1.27 1.27))))
        )
        (pin bidirectional line (at 0 -104.14 0) (length 5.08)
          (name "IO_L20P_T3_16" (effects (font (size 1.27 1.27))))
          (number "B12" (effects (font (size 1.27 1.27))))
        )
        (pin bidirectional line (at 0 -109.22 0) (length 5.08)
          (name "IO_L21P_T3_DQS_16" (effects (font (size 1.27 1.27))))
          (number "B14" (effects (font (size 1.27 1.27))))
        )
        (pin bidirectional line (at 0 -119.38 0) (length 5.08)
          (name "IO_L23P_T3_16" (effects (font (size 1.27 1.27))))
          (number "B15" (effects (font (size 1.27 1.27))))
        )
        (pin passive line (at 0 0 0) (length 5.08) hide
          (name "VCCO_16" (effects (font (size 1.27 1.27))))
          (number "B8" (effects (font (size 1.27 1.27))))
        )
        (pin bidirectional line (at 0 -55.88 0) (length 5.08)
          (name "IO_L10N_T1_16" (effects (font (size 1.27 1.27))))
          (number "B9" (effects (font (size 1.27 1.27))))
        )
        (pin bidirectional line (at 0 -71.12 0) (length 5.08)
          (name "IO_L13N_T2_MRCC_16" (effects (font (size 1.27 1.27))))
          (number "C11" (effects (font (size 1.27 1.27))))
        )
        (pin bidirectional line (at 0 -68.58 0) (length 5.08)
          (name "IO_L13P_T2_MRCC_16" (effects (font (size 1.27 1.27))))
          (number "C12" (effects (font (size 1.27 1.27))))
        )
        (pin bidirectional line (at 0 -101.6 0) (length 5.08)
          (name "IO_L19N_T3_VREF_16" (effects (font (size 1.27 1.27))))
          (number "C13" (effects (font (size 1.27 1.27))))
        )
        (pin bidirectional line (at 0 -99.06 0) (length 5.08)
          (name "IO_L19P_T3_16" (effects (font (size 1.27 1.27))))
          (number "C14" (effects (font (size 1.27 1.27))))
        )
        (pin passive line (at 0 0 0) (length 5.08) hide
          (name "VCCO_16" (effects (font (size 1.27 1.27))))
          (number "C15" (effects (font (size 1.27 1.27))))
        )
        (pin bidirectional line (at 0 -53.34 0) (length 5.08)
          (name "IO_L10P_T1_16" (effects (font (size 1.27 1.27))))
          (number "C9" (effects (font (size 1.27 1.27))))
        )
        (pin bidirectional line (at 0 -66.04 0) (length 5.08)
          (name "IO_L12N_T1_MRCC_16" (effects (font (size 1.27 1.27))))
          (number "D10" (effects (font (size 1.27 1.27))))
        )
        (pin bidirectional line (at 0 -76.2 0) (length 5.08)
          (name "IO_L14N_T2_SRCC_16" (effects (font (size 1.27 1.27))))
          (number "D11" (effects (font (size 1.27 1.27))))
        )
        (pin passive line (at 0 0 0) (length 5.08) hide
          (name "VCCO_16" (effects (font (size 1.27 1.27))))
          (number "D12" (effects (font (size 1.27 1.27))))
        )
        (pin bidirectional line (at 0 -91.44 0) (length 5.08)
          (name "IO_L17N_T2_16" (effects (font (size 1.27 1.27))))
          (number "D13" (effects (font (size 1.27 1.27))))
        )
        (pin bidirectional line (at 0 -88.9 0) (length 5.08)
          (name "IO_L17P_T2_16" (effects (font (size 1.27 1.27))))
          (number "D14" (effects (font (size 1.27 1.27))))
        )
        (pin bidirectional line (at 0 -45.72 0) (length 5.08)
          (name "IO_L8N_T1_16" (effects (font (size 1.27 1.27))))
          (number "D8" (effects (font (size 1.27 1.27))))
        )
        (pin bidirectional line (at 0 -43.18 0) (length 5.08)
          (name "IO_L8P_T1_16" (effects (font (size 1.27 1.27))))
          (number "D9" (effects (font (size 1.27 1.27))))
        )
        (pin bidirectional line (at 0 -63.5 0) (length 5.08)
          (name "IO_L12P_T1_MRCC_16" (effects (font (size 1.27 1.27))))
          (number "E10" (effects (font (size 1.27 1.27))))
        )
        (pin bidirectional line (at 0 -73.66 0) (length 5.08)
          (name "IO_L14P_T2_SRCC_16" (effects (font (size 1.27 1.27))))
          (number "E11" (effects (font (size 1.27 1.27))))
        )
        (pin bidirectional line (at 0 -96.52 0) (length 5.08)
          (name "IO_L18N_T2_16" (effects (font (size 1.27 1.27))))
          (number "E12" (effects (font (size 1.27 1.27))))
        )
        (pin bidirectional line (at 0 -93.98 0) (length 5.08)
          (name "IO_L18P_T2_16" (effects (font (size 1.27 1.27))))
          (number "E13" (effects (font (size 1.27 1.27))))
        )
        (pin passive line (at 0 0 0) (length 5.08) hide
          (name "VCCO_16" (effects (font (size 1.27 1.27))))
          (number "E9" (effects (font (size 1.27 1.27))))
        )
        (pin bidirectional line (at 0 -60.96 0) (length 5.08)
          (name "IO_L11N_T1_SRCC_16" (effects (font (size 1.27 1.27))))
          (number "F10" (effects (font (size 1.27 1.27))))
        )
        (pin bidirectional line (at 0 -86.36 0) (length 5.08)
          (name "IO_L16N_T2_16" (effects (font (size 1.27 1.27))))
          (number "F12" (effects (font (size 1.27 1.27))))
        )
        (pin bidirectional line (at 0 -81.28 0) (length 5.08)
          (name "IO_L15N_T2_DQS_16" (effects (font (size 1.27 1.27))))
          (number "F13" (effects (font (size 1.27 1.27))))
        )
        (pin bidirectional line (at 0 -78.74 0) (length 5.08)
          (name "IO_L15P_T2_DQS_16" (effects (font (size 1.27 1.27))))
          (number "F14" (effects (font (size 1.27 1.27))))
        )
        (pin bidirectional line (at 0 -40.64 0) (length 5.08)
          (name "IO_L7N_T1_16" (effects (font (size 1.27 1.27))))
          (number "F8" (effects (font (size 1.27 1.27))))
        )
        (pin bidirectional line (at 0 -38.1 0) (length 5.08)
          (name "IO_L7P_T1_16" (effects (font (size 1.27 1.27))))
          (number "F9" (effects (font (size 1.27 1.27))))
        )
        (pin bidirectional line (at 0 -12.7 0) (length 5.08)
          (name "IO_L2P_T0_16" (effects (font (size 1.27 1.27))))
          (number "G10" (effects (font (size 1.27 1.27))))
        )
        (pin bidirectional line (at 0 -58.42 0) (length 5.08)
          (name "IO_L11P_T1_SRCC_16" (effects (font (size 1.27 1.27))))
          (number "G11" (effects (font (size 1.27 1.27))))
        )
        (pin bidirectional line (at 0 -83.82 0) (length 5.08)
          (name "IO_L16P_T2_16" (effects (font (size 1.27 1.27))))
          (number "G12" (effects (font (size 1.27 1.27))))
        )
        (pin passive line (at 0 0 0) (length 5.08) hide
          (name "VCCO_16" (effects (font (size 1.27 1.27))))
          (number "G13" (effects (font (size 1.27 1.27))))
        )
        (pin bidirectional line (at 0 -30.48 0) (length 5.08)
          (name "IO_L5N_T0_16" (effects (font (size 1.27 1.27))))
          (number "G14" (effects (font (size 1.27 1.27))))
        )
        (pin bidirectional line (at 0 -15.24 0) (length 5.08)
          (name "IO_L2N_T0_16" (effects (font (size 1.27 1.27))))
          (number "G9" (effects (font (size 1.27 1.27))))
        )
        (pin passive line (at 0 0 0) (length 5.08) hide
          (name "VCCO_16" (effects (font (size 1.27 1.27))))
          (number "H10" (effects (font (size 1.27 1.27))))
        )
        (pin bidirectional line (at 0 -35.56 0) (length 5.08)
          (name "IO_L6N_T0_VREF_16" (effects (font (size 1.27 1.27))))
          (number "H11" (effects (font (size 1.27 1.27))))
        )
        (pin bidirectional line (at 0 -33.02 0) (length 5.08)
          (name "IO_L6P_T0_16" (effects (font (size 1.27 1.27))))
          (number "H12" (effects (font (size 1.27 1.27))))
        )
        (pin bidirectional line (at 0 -20.32 0) (length 5.08)
          (name "IO_L3N_T0_DQS_16" (effects (font (size 1.27 1.27))))
          (number "H13" (effects (font (size 1.27 1.27))))
        )
        (pin bidirectional line (at 0 -27.94 0) (length 5.08)
          (name "IO_L5P_T0_16" (effects (font (size 1.27 1.27))))
          (number "H14" (effects (font (size 1.27 1.27))))
        )
        (pin bidirectional line (at 0 -10.16 0) (length 5.08)
          (name "IO_L1N_T0_16" (effects (font (size 1.27 1.27))))
          (number "H8" (effects (font (size 1.27 1.27))))
        )
        (pin bidirectional line (at 0 -7.62 0) (length 5.08)
          (name "IO_L1P_T0_16" (effects (font (size 1.27 1.27))))
          (number "H9" (effects (font (size 1.27 1.27))))
        )
        (pin bidirectional line (at 0 -25.4 0) (length 5.08)
          (name "IO_L4N_T0_16" (effects (font (size 1.27 1.27))))
          (number "J10" (effects (font (size 1.27 1.27))))
        )
        (pin bidirectional line (at 0 -22.86 0) (length 5.08)
          (name "IO_L4P_T0_16" (effects (font (size 1.27 1.27))))
          (number "J11" (effects (font (size 1.27 1.27))))
        )
        (pin bidirectional line (at 0 -17.78 0) (length 5.08)
          (name "IO_L3P_T0_DQS_16" (effects (font (size 1.27 1.27))))
          (number "J13" (effects (font (size 1.27 1.27))))
        )
        (pin bidirectional line (at 0 -129.54 0) (length 5.08)
          (name "IO_25_16" (effects (font (size 1.27 1.27))))
          (number "J14" (effects (font (size 1.27 1.27))))
        )
        (pin bidirectional line (at 0 -5.08 0) (length 5.08)
          (name "IO_0_16" (effects (font (size 1.27 1.27))))
          (number "J8" (effects (font (size 1.27 1.27))))
        )
      )
      (symbol "XC7K160T-FFG676_6_1"
        (polyline
          (pts
            (xy 22.86 -3.81)
            (xy 30.48 -3.81)
            (xy 30.48 -130.81)
            (xy 22.86 -130.81)
          )
          (stroke (width 0.254) (type default))
          (fill (type background))
        )
        (rectangle (start 5.08 -132.08) (end 33.02 2.54)
          (stroke (width 0.254) (type default))
          (fill (type background))
        )
        (text "BANK 32" (at 24.13 -1.27 0)
          (effects (font (size 1.27 1.27) (thickness 0.15)) (justify left bottom))
        )
        (pin bidirectional line (at 0 -38.1 0) (length 5.08)
          (name "IO_L7P_T1_32" (effects (font (size 1.27 1.27))))
          (number "AA14" (effects (font (size 1.27 1.27))))
        )
        (pin bidirectional line (at 0 -40.64 0) (length 5.08)
          (name "IO_L7N_T1_32" (effects (font (size 1.27 1.27))))
          (number "AA15" (effects (font (size 1.27 1.27))))
        )
        (pin bidirectional line (at 0 -58.42 0) (length 5.08)
          (name "IO_L11P_T1_SRCC_32" (effects (font (size 1.27 1.27))))
          (number "AA17" (effects (font (size 1.27 1.27))))
        )
        (pin bidirectional line (at 0 -60.96 0) (length 5.08)
          (name "IO_L11N_T1_SRCC_32" (effects (font (size 1.27 1.27))))
          (number "AA18" (effects (font (size 1.27 1.27))))
        )
        (pin bidirectional line (at 0 -83.82 0) (length 5.08)
          (name "IO_L16P_T2_32" (effects (font (size 1.27 1.27))))
          (number "AA19" (effects (font (size 1.27 1.27))))
        )
        (pin bidirectional line (at 0 -86.36 0) (length 5.08)
          (name "IO_L16N_T2_32" (effects (font (size 1.27 1.27))))
          (number "AA20" (effects (font (size 1.27 1.27))))
        )
        (pin bidirectional line (at 0 -53.34 0) (length 5.08)
          (name "IO_L10P_T1_32" (effects (font (size 1.27 1.27))))
          (number "AB14" (effects (font (size 1.27 1.27))))
        )
        (pin bidirectional line (at 0 -55.88 0) (length 5.08)
          (name "IO_L10N_T1_32" (effects (font (size 1.27 1.27))))
          (number "AB15" (effects (font (size 1.27 1.27))))
        )
        (pin bidirectional line (at 0 -63.5 0) (length 5.08)
          (name "IO_L12P_T1_MRCC_32" (effects (font (size 1.27 1.27))))
          (number "AB16" (effects (font (size 1.27 1.27))))
        )
        (pin bidirectional line (at 0 -73.66 0) (length 5.08)
          (name "IO_L14P_T2_SRCC_32" (effects (font (size 1.27 1.27))))
          (number "AB17" (effects (font (size 1.27 1.27))))
        )
        (pin power_in line (at 0 0 0) (length 5.08)
          (name "VCCO_32" (effects (font (size 1.27 1.27))))
          (number "AB18" (effects (font (size 1.27 1.27))))
        )
        (pin bidirectional line (at 0 -93.98 0) (length 5.08)
          (name "IO_L18P_T2_32" (effects (font (size 1.27 1.27))))
          (number "AB19" (effects (font (size 1.27 1.27))))
        )
        (pin bidirectional line (at 0 -96.52 0) (length 5.08)
          (name "IO_L18N_T2_32" (effects (font (size 1.27 1.27))))
          (number "AB20" (effects (font (size 1.27 1.27))))
        )
        (pin bidirectional line (at 0 -43.18 0) (length 5.08)
          (name "IO_L8P_T1_32" (effects (font (size 1.27 1.27))))
          (number "AC14" (effects (font (size 1.27 1.27))))
        )
        (pin passive line (at 0 0 0) (length 5.08) hide
          (name "VCCO_32" (effects (font (size 1.27 1.27))))
          (number "AC15" (effects (font (size 1.27 1.27))))
        )
        (pin bidirectional line (at 0 -66.04 0) (length 5.08)
          (name "IO_L12N_T1_MRCC_32" (effects (font (size 1.27 1.27))))
          (number "AC16" (effects (font (size 1.27 1.27))))
        )
        (pin bidirectional line (at 0 -76.2 0) (length 5.08)
          (name "IO_L14N_T2_SRCC_32" (effects (font (size 1.27 1.27))))
          (number "AC17" (effects (font (size 1.27 1.27))))
        )
        (pin bidirectional line (at 0 -68.58 0) (length 5.08)
          (name "IO_L13P_T2_MRCC_32" (effects (font (size 1.27 1.27))))
          (number "AC18" (effects (font (size 1.27 1.27))))
        )
        (pin bidirectional line (at 0 -88.9 0) (length 5.08)
          (name "IO_L17P_T2_32" (effects (font (size 1.27 1.27))))
          (number "AC19" (effects (font (size 1.27 1.27))))
        )
        (pin bidirectional line (at 0 -45.72 0) (length 5.08)
          (name "IO_L8N_T1_32" (effects (font (size 1.27 1.27))))
          (number "AD14" (effects (font (size 1.27 1.27))))
        )
        (pin bidirectional line (at 0 -22.86 0) (length 5.08)
          (name "IO_L4P_T0_32" (effects (font (size 1.27 1.27))))
          (number "AD15" (effects (font (size 1.27 1.27))))
        )
        (pin bidirectional line (at 0 -33.02 0) (length 5.08)
          (name "IO_L6P_T0_32" (effects (font (size 1.27 1.27))))
          (number "AD16" (effects (font (size 1.27 1.27))))
        )
        (pin bidirectional line (at 0 -71.12 0) (length 5.08)
          (name "IO_L13N_T2_MRCC_32" (effects (font (size 1.27 1.27))))
          (number "AD18" (effects (font (size 1.27 1.27))))
        )
        (pin bidirectional line (at 0 -91.44 0) (length 5.08)
          (name "IO_L17N_T2_32" (effects (font (size 1.27 1.27))))
          (number "AD19" (effects (font (size 1.27 1.27))))
        )
        (pin bidirectional line (at 0 -78.74 0) (length 5.08)
          (name "IO_L15P_T2_DQS_32" (effects (font (size 1.27 1.27))))
          (number "AD20" (effects (font (size 1.27 1.27))))
        )
        (pin bidirectional line (at 0 -25.4 0) (length 5.08)
          (name "IO_L4N_T0_32" (effects (font (size 1.27 1.27))))
          (number "AE15" (effects (font (size 1.27 1.27))))
        )
        (pin bidirectional line (at 0 -35.56 0) (length 5.08)
          (name "IO_L6N_T0_VREF_32" (effects (font (size 1.27 1.27))))
          (number "AE16" (effects (font (size 1.27 1.27))))
        )
        (pin bidirectional line (at 0 -7.62 0) (length 5.08)
          (name "IO_L1P_T0_32" (effects (font (size 1.27 1.27))))
          (number "AE17" (effects (font (size 1.27 1.27))))
        )
        (pin bidirectional line (at 0 -17.78 0) (length 5.08)
          (name "IO_L3P_T0_DQS_32" (effects (font (size 1.27 1.27))))
          (number "AE18" (effects (font (size 1.27 1.27))))
        )
        (pin passive line (at 0 0 0) (length 5.08) hide
          (name "VCCO_32" (effects (font (size 1.27 1.27))))
          (number "AE19" (effects (font (size 1.27 1.27))))
        )
        (pin bidirectional line (at 0 -81.28 0) (length 5.08)
          (name "IO_L15N_T2_DQS_32" (effects (font (size 1.27 1.27))))
          (number "AE20" (effects (font (size 1.27 1.27))))
        )
        (pin bidirectional line (at 0 -12.7 0) (length 5.08)
          (name "IO_L2P_T0_32" (effects (font (size 1.27 1.27))))
          (number "AF14" (effects (font (size 1.27 1.27))))
        )
        (pin bidirectional line (at 0 -15.24 0) (length 5.08)
          (name "IO_L2N_T0_32" (effects (font (size 1.27 1.27))))
          (number "AF15" (effects (font (size 1.27 1.27))))
        )
        (pin passive line (at 0 0 0) (length 5.08) hide
          (name "VCCO_32" (effects (font (size 1.27 1.27))))
          (number "AF16" (effects (font (size 1.27 1.27))))
        )
        (pin bidirectional line (at 0 -10.16 0) (length 5.08)
          (name "IO_L1N_T0_32" (effects (font (size 1.27 1.27))))
          (number "AF17" (effects (font (size 1.27 1.27))))
        )
        (pin bidirectional line (at 0 -20.32 0) (length 5.08)
          (name "IO_L3N_T0_DQS_32" (effects (font (size 1.27 1.27))))
          (number "AF18" (effects (font (size 1.27 1.27))))
        )
        (pin bidirectional line (at 0 -27.94 0) (length 5.08)
          (name "IO_L5P_T0_32" (effects (font (size 1.27 1.27))))
          (number "AF19" (effects (font (size 1.27 1.27))))
        )
        (pin bidirectional line (at 0 -30.48 0) (length 5.08)
          (name "IO_L5N_T0_32" (effects (font (size 1.27 1.27))))
          (number "AF20" (effects (font (size 1.27 1.27))))
        )
        (pin bidirectional line (at 0 -5.08 0) (length 5.08)
          (name "IO_0_VRN_32" (effects (font (size 1.27 1.27))))
          (number "V13" (effects (font (size 1.27 1.27))))
        )
        (pin bidirectional line (at 0 -124.46 0) (length 5.08)
          (name "IO_L24P_T3_32" (effects (font (size 1.27 1.27))))
          (number "V14" (effects (font (size 1.27 1.27))))
        )
        (pin bidirectional line (at 0 -104.14 0) (length 5.08)
          (name "IO_L20P_T3_32" (effects (font (size 1.27 1.27))))
          (number "V16" (effects (font (size 1.27 1.27))))
        )
        (pin bidirectional line (at 0 -106.68 0) (length 5.08)
          (name "IO_L20N_T3_32" (effects (font (size 1.27 1.27))))
          (number "V17" (effects (font (size 1.27 1.27))))
        )
        (pin bidirectional line (at 0 -119.38 0) (length 5.08)
          (name "IO_L23P_T3_32" (effects (font (size 1.27 1.27))))
          (number "V18" (effects (font (size 1.27 1.27))))
        )
        (pin bidirectional line (at 0 -121.92 0) (length 5.08)
          (name "IO_L23N_T3_32" (effects (font (size 1.27 1.27))))
          (number "V19" (effects (font (size 1.27 1.27))))
        )
        (pin bidirectional line (at 0 -129.54 0) (length 5.08)
          (name "IO_25_VRP_32" (effects (font (size 1.27 1.27))))
          (number "W13" (effects (font (size 1.27 1.27))))
        )
        (pin bidirectional line (at 0 -127 0) (length 5.08)
          (name "IO_L24N_T3_32" (effects (font (size 1.27 1.27))))
          (number "W14" (effects (font (size 1.27 1.27))))
        )
        (pin bidirectional line (at 0 -114.3 0) (length 5.08)
          (name "IO_L22P_T3_32" (effects (font (size 1.27 1.27))))
          (number "W15" (effects (font (size 1.27 1.27))))
        )
        (pin bidirectional line (at 0 -116.84 0) (length 5.08)
          (name "IO_L22N_T3_32" (effects (font (size 1.27 1.27))))
          (number "W16" (effects (font (size 1.27 1.27))))
        )
        (pin passive line (at 0 0 0) (length 5.08) hide
          (name "VCCO_32" (effects (font (size 1.27 1.27))))
          (number "W17" (effects (font (size 1.27 1.27))))
        )
        (pin bidirectional line (at 0 -109.22 0) (length 5.08)
          (name "IO_L21P_T3_DQS_32" (effects (font (size 1.27 1.27))))
          (number "W18" (effects (font (size 1.27 1.27))))
        )
        (pin bidirectional line (at 0 -111.76 0) (length 5.08)
          (name "IO_L21N_T3_DQS_32" (effects (font (size 1.27 1.27))))
          (number "W19" (effects (font (size 1.27 1.27))))
        )
        (pin passive line (at 0 0 0) (length 5.08) hide
          (name "VCCO_32" (effects (font (size 1.27 1.27))))
          (number "Y14" (effects (font (size 1.27 1.27))))
        )
        (pin bidirectional line (at 0 -48.26 0) (length 5.08)
          (name "IO_L9P_T1_DQS_32" (effects (font (size 1.27 1.27))))
          (number "Y15" (effects (font (size 1.27 1.27))))
        )
        (pin bidirectional line (at 0 -50.8 0) (length 5.08)
          (name "IO_L9N_T1_DQS_32" (effects (font (size 1.27 1.27))))
          (number "Y16" (effects (font (size 1.27 1.27))))
        )
        (pin bidirectional line (at 0 -99.06 0) (length 5.08)
          (name "IO_L19P_T3_32" (effects (font (size 1.27 1.27))))
          (number "Y17" (effects (font (size 1.27 1.27))))
        )
        (pin bidirectional line (at 0 -101.6 0) (length 5.08)
          (name "IO_L19N_T3_VREF_32" (effects (font (size 1.27 1.27))))
          (number "Y18" (effects (font (size 1.27 1.27))))
        )
      )
      (symbol "XC7K160T-FFG676_7_1"
        (polyline
          (pts
            (xy 22.86 -3.81)
            (xy 30.48 -3.81)
            (xy 30.48 -130.81)
            (xy 22.86 -130.81)
          )
          (stroke (width 0.254) (type default))
          (fill (type background))
        )
        (rectangle (start 5.08 -132.08) (end 33.02 2.54)
          (stroke (width 0.254) (type default))
          (fill (type background))
        )
        (text "BANK 33" (at 24.13 -1.27 0)
          (effects (font (size 1.27 1.27) (thickness 0.15)) (justify left bottom))
        )
        (pin bidirectional line (at 0 -73.66 0) (length 5.08)
          (name "IO_L14P_T2_SRCC_33" (effects (font (size 1.27 1.27))))
          (number "AA10" (effects (font (size 1.27 1.27))))
        )
        (pin power_in line (at 0 0 0) (length 5.08)
          (name "VCCO_33" (effects (font (size 1.27 1.27))))
          (number "AA11" (effects (font (size 1.27 1.27))))
        )
        (pin bidirectional line (at 0 -86.36 0) (length 5.08)
          (name "IO_L16N_T2_33" (effects (font (size 1.27 1.27))))
          (number "AA12" (effects (font (size 1.27 1.27))))
        )
        (pin bidirectional line (at 0 -83.82 0) (length 5.08)
          (name "IO_L16P_T2_33" (effects (font (size 1.27 1.27))))
          (number "AA13" (effects (font (size 1.27 1.27))))
        )
        (pin bidirectional line (at 0 -45.72 0) (length 5.08)
          (name "IO_L8N_T1_33" (effects (font (size 1.27 1.27))))
          (number "AA7" (effects (font (size 1.27 1.27))))
        )
        (pin bidirectional line (at 0 -43.18 0) (length 5.08)
          (name "IO_L8P_T1_33" (effects (font (size 1.27 1.27))))
          (number "AA8" (effects (font (size 1.27 1.27))))
        )
        (pin bidirectional line (at 0 -58.42 0) (length 5.08)
          (name "IO_L11P_T1_SRCC_33" (effects (font (size 1.27 1.27))))
          (number "AA9" (effects (font (size 1.27 1.27))))
        )
        (pin bidirectional line (at 0 -76.2 0) (length 5.08)
          (name "IO_L14N_T2_SRCC_33" (effects (font (size 1.27 1.27))))
          (number "AB10" (effects (font (size 1.27 1.27))))
        )
        (pin bidirectional line (at 0 -68.58 0) (length 5.08)
          (name "IO_L13P_T2_MRCC_33" (effects (font (size 1.27 1.27))))
          (number "AB11" (effects (font (size 1.27 1.27))))
        )
        (pin bidirectional line (at 0 -78.74 0) (length 5.08)
          (name "IO_L15P_T2_DQS_33" (effects (font (size 1.27 1.27))))
          (number "AB12" (effects (font (size 1.27 1.27))))
        )
        (pin bidirectional line (at 0 -53.34 0) (length 5.08)
          (name "IO_L10P_T1_33" (effects (font (size 1.27 1.27))))
          (number "AB7" (effects (font (size 1.27 1.27))))
        )
        (pin passive line (at 0 0 0) (length 5.08) hide
          (name "VCCO_33" (effects (font (size 1.27 1.27))))
          (number "AB8" (effects (font (size 1.27 1.27))))
        )
        (pin bidirectional line (at 0 -60.96 0) (length 5.08)
          (name "IO_L11N_T1_SRCC_33" (effects (font (size 1.27 1.27))))
          (number "AB9" (effects (font (size 1.27 1.27))))
        )
        (pin bidirectional line (at 0 -71.12 0) (length 5.08)
          (name "IO_L13N_T2_MRCC_33" (effects (font (size 1.27 1.27))))
          (number "AC11" (effects (font (size 1.27 1.27))))
        )
        (pin bidirectional line (at 0 -81.28 0) (length 5.08)
          (name "IO_L15N_T2_DQS_33" (effects (font (size 1.27 1.27))))
          (number "AC12" (effects (font (size 1.27 1.27))))
        )
        (pin bidirectional line (at 0 -88.9 0) (length 5.08)
          (name "IO_L17P_T2_33" (effects (font (size 1.27 1.27))))
          (number "AC13" (effects (font (size 1.27 1.27))))
        )
        (pin bidirectional line (at 0 -55.88 0) (length 5.08)
          (name "IO_L10N_T1_33" (effects (font (size 1.27 1.27))))
          (number "AC7" (effects (font (size 1.27 1.27))))
        )
        (pin bidirectional line (at 0 -48.26 0) (length 5.08)
          (name "IO_L9P_T1_DQS_33" (effects (font (size 1.27 1.27))))
          (number "AC8" (effects (font (size 1.27 1.27))))
        )
        (pin bidirectional line (at 0 -63.5 0) (length 5.08)
          (name "IO_L12P_T1_MRCC_33" (effects (font (size 1.27 1.27))))
          (number "AC9" (effects (font (size 1.27 1.27))))
        )
        (pin bidirectional line (at 0 -104.14 0) (length 5.08)
          (name "IO_L20P_T3_33" (effects (font (size 1.27 1.27))))
          (number "AD10" (effects (font (size 1.27 1.27))))
        )
        (pin bidirectional line (at 0 -99.06 0) (length 5.08)
          (name "IO_L19P_T3_33" (effects (font (size 1.27 1.27))))
          (number "AD11" (effects (font (size 1.27 1.27))))
        )
        (pin passive line (at 0 0 0) (length 5.08) hide
          (name "VCCO_33" (effects (font (size 1.27 1.27))))
          (number "AD12" (effects (font (size 1.27 1.27))))
        )
        (pin bidirectional line (at 0 -91.44 0) (length 5.08)
          (name "IO_L17N_T2_33" (effects (font (size 1.27 1.27))))
          (number "AD13" (effects (font (size 1.27 1.27))))
        )
        (pin bidirectional line (at 0 -50.8 0) (length 5.08)
          (name "IO_L9N_T1_DQS_33" (effects (font (size 1.27 1.27))))
          (number "AD8" (effects (font (size 1.27 1.27))))
        )
        (pin bidirectional line (at 0 -66.04 0) (length 5.08)
          (name "IO_L12N_T1_MRCC_33" (effects (font (size 1.27 1.27))))
          (number "AD9" (effects (font (size 1.27 1.27))))
        )
        (pin bidirectional line (at 0 -106.68 0) (length 5.08)
          (name "IO_L20N_T3_33" (effects (font (size 1.27 1.27))))
          (number "AE10" (effects (font (size 1.27 1.27))))
        )
        (pin bidirectional line (at 0 -101.6 0) (length 5.08)
          (name "IO_L19N_T3_VREF_33" (effects (font (size 1.27 1.27))))
          (number "AE11" (effects (font (size 1.27 1.27))))
        )
        (pin bidirectional line (at 0 -109.22 0) (length 5.08)
          (name "IO_L21P_T3_DQS_33" (effects (font (size 1.27 1.27))))
          (number "AE12" (effects (font (size 1.27 1.27))))
        )
        (pin bidirectional line (at 0 -119.38 0) (length 5.08)
          (name "IO_L23P_T3_33" (effects (font (size 1.27 1.27))))
          (number "AE13" (effects (font (size 1.27 1.27))))
        )
        (pin bidirectional line (at 0 -38.1 0) (length 5.08)
          (name "IO_L7P_T1_33" (effects (font (size 1.27 1.27))))
          (number "AE7" (effects (font (size 1.27 1.27))))
        )
        (pin bidirectional line (at 0 -114.3 0) (length 5.08)
          (name "IO_L22P_T3_33" (effects (font (size 1.27 1.27))))
          (number "AE8" (effects (font (size 1.27 1.27))))
        )
        (pin passive line (at 0 0 0) (length 5.08) hide
          (name "VCCO_33" (effects (font (size 1.27 1.27))))
          (number "AE9" (effects (font (size 1.27 1.27))))
        )
        (pin bidirectional line (at 0 -124.46 0) (length 5.08)
          (name "IO_L24P_T3_33" (effects (font (size 1.27 1.27))))
          (number "AF10" (effects (font (size 1.27 1.27))))
        )
        (pin bidirectional line (at 0 -111.76 0) (length 5.08)
          (name "IO_L21N_T3_DQS_33" (effects (font (size 1.27 1.27))))
          (number "AF12" (effects (font (size 1.27 1.27))))
        )
        (pin bidirectional line (at 0 -121.92 0) (length 5.08)
          (name "IO_L23N_T3_33" (effects (font (size 1.27 1.27))))
          (number "AF13" (effects (font (size 1.27 1.27))))
        )
        (pin bidirectional line (at 0 -40.64 0) (length 5.08)
          (name "IO_L7N_T1_33" (effects (font (size 1.27 1.27))))
          (number "AF7" (effects (font (size 1.27 1.27))))
        )
        (pin bidirectional line (at 0 -116.84 0) (length 5.08)
          (name "IO_L22N_T3_33" (effects (font (size 1.27 1.27))))
          (number "AF8" (effects (font (size 1.27 1.27))))
        )
        (pin bidirectional line (at 0 -127 0) (length 5.08)
          (name "IO_L24N_T3_33" (effects (font (size 1.27 1.27))))
          (number "AF9" (effects (font (size 1.27 1.27))))
        )
        (pin bidirectional line (at 0 -5.08 0) (length 5.08)
          (name "IO_0_VRN_33" (effects (font (size 1.27 1.27))))
          (number "U9" (effects (font (size 1.27 1.27))))
        )
        (pin passive line (at 0 0 0) (length 5.08) hide
          (name "VCCO_33" (effects (font (size 1.27 1.27))))
          (number "V10" (effects (font (size 1.27 1.27))))
        )
        (pin bidirectional line (at 0 -7.62 0) (length 5.08)
          (name "IO_L1P_T0_33" (effects (font (size 1.27 1.27))))
          (number "V11" (effects (font (size 1.27 1.27))))
        )
        (pin bidirectional line (at 0 -129.54 0) (length 5.08)
          (name "IO_25_VRP_33" (effects (font (size 1.27 1.27))))
          (number "V12" (effects (font (size 1.27 1.27))))
        )
        (pin bidirectional line (at 0 -15.24 0) (length 5.08)
          (name "IO_L2N_T0_33" (effects (font (size 1.27 1.27))))
          (number "V7" (effects (font (size 1.27 1.27))))
        )
        (pin bidirectional line (at 0 -12.7 0) (length 5.08)
          (name "IO_L2P_T0_33" (effects (font (size 1.27 1.27))))
          (number "V8" (effects (font (size 1.27 1.27))))
        )
        (pin bidirectional line (at 0 -33.02 0) (length 5.08)
          (name "IO_L6P_T0_33" (effects (font (size 1.27 1.27))))
          (number "V9" (effects (font (size 1.27 1.27))))
        )
        (pin bidirectional line (at 0 -17.78 0) (length 5.08)
          (name "IO_L3P_T0_DQS_33" (effects (font (size 1.27 1.27))))
          (number "W10" (effects (font (size 1.27 1.27))))
        )
        (pin bidirectional line (at 0 -10.16 0) (length 5.08)
          (name "IO_L1N_T0_33" (effects (font (size 1.27 1.27))))
          (number "W11" (effects (font (size 1.27 1.27))))
        )
        (pin passive line (at 0 0 0) (length 5.08) hide
          (name "VCCO_33" (effects (font (size 1.27 1.27))))
          (number "W7" (effects (font (size 1.27 1.27))))
        )
        (pin bidirectional line (at 0 -35.56 0) (length 5.08)
          (name "IO_L6N_T0_VREF_33" (effects (font (size 1.27 1.27))))
          (number "W8" (effects (font (size 1.27 1.27))))
        )
        (pin bidirectional line (at 0 -20.32 0) (length 5.08)
          (name "IO_L3N_T0_DQS_33" (effects (font (size 1.27 1.27))))
          (number "W9" (effects (font (size 1.27 1.27))))
        )
        (pin bidirectional line (at 0 -30.48 0) (length 5.08)
          (name "IO_L5N_T0_33" (effects (font (size 1.27 1.27))))
          (number "Y10" (effects (font (size 1.27 1.27))))
        )
        (pin bidirectional line (at 0 -27.94 0) (length 5.08)
          (name "IO_L5P_T0_33" (effects (font (size 1.27 1.27))))
          (number "Y11" (effects (font (size 1.27 1.27))))
        )
        (pin bidirectional line (at 0 -96.52 0) (length 5.08)
          (name "IO_L18N_T2_33" (effects (font (size 1.27 1.27))))
          (number "Y12" (effects (font (size 1.27 1.27))))
        )
        (pin bidirectional line (at 0 -93.98 0) (length 5.08)
          (name "IO_L18P_T2_33" (effects (font (size 1.27 1.27))))
          (number "Y13" (effects (font (size 1.27 1.27))))
        )
        (pin bidirectional line (at 0 -25.4 0) (length 5.08)
          (name "IO_L4N_T0_33" (effects (font (size 1.27 1.27))))
          (number "Y7" (effects (font (size 1.27 1.27))))
        )
        (pin bidirectional line (at 0 -22.86 0) (length 5.08)
          (name "IO_L4P_T0_33" (effects (font (size 1.27 1.27))))
          (number "Y8" (effects (font (size 1.27 1.27))))
        )
      )
      (symbol "XC7K160T-FFG676_8_1"
        (polyline
          (pts
            (xy 22.86 -3.81)
            (xy 30.48 -3.81)
            (xy 30.48 -130.81)
            (xy 22.86 -130.81)
          )
          (stroke (width 0.254) (type default))
          (fill (type background))
        )
        (rectangle (start 5.08 -132.08) (end 33.02 2.54)
          (stroke (width 0.254) (type default))
          (fill (type background))
        )
        (text "BANK 34" (at 24.13 -1.27 0)
          (effects (font (size 1.27 1.27) (thickness 0.15)) (justify left bottom))
        )
        (pin power_in line (at 0 0 0) (length 5.08)
          (name "VCCO_34" (effects (font (size 1.27 1.27))))
          (number "AA1" (effects (font (size 1.27 1.27))))
        )
        (pin bidirectional line (at 0 -66.04 0) (length 5.08)
          (name "IO_L12N_T1_MRCC_34" (effects (font (size 1.27 1.27))))
          (number "AA2" (effects (font (size 1.27 1.27))))
        )
        (pin bidirectional line (at 0 -63.5 0) (length 5.08)
          (name "IO_L12P_T1_MRCC_34" (effects (font (size 1.27 1.27))))
          (number "AA3" (effects (font (size 1.27 1.27))))
        )
        (pin bidirectional line (at 0 -68.58 0) (length 5.08)
          (name "IO_L13P_T2_MRCC_34" (effects (font (size 1.27 1.27))))
          (number "AA4" (effects (font (size 1.27 1.27))))
        )
        (pin bidirectional line (at 0 -78.74 0) (length 5.08)
          (name "IO_L15P_T2_DQS_34" (effects (font (size 1.27 1.27))))
          (number "AA5" (effects (font (size 1.27 1.27))))
        )
        (pin bidirectional line (at 0 -48.26 0) (length 5.08)
          (name "IO_L9P_T1_DQS_34" (effects (font (size 1.27 1.27))))
          (number "AB1" (effects (font (size 1.27 1.27))))
        )
        (pin bidirectional line (at 0 -58.42 0) (length 5.08)
          (name "IO_L11P_T1_SRCC_34" (effects (font (size 1.27 1.27))))
          (number "AB2" (effects (font (size 1.27 1.27))))
        )
        (pin bidirectional line (at 0 -71.12 0) (length 5.08)
          (name "IO_L13N_T2_MRCC_34" (effects (font (size 1.27 1.27))))
          (number "AB4" (effects (font (size 1.27 1.27))))
        )
        (pin bidirectional line (at 0 -81.28 0) (length 5.08)
          (name "IO_L15N_T2_DQS_34" (effects (font (size 1.27 1.27))))
          (number "AB5" (effects (font (size 1.27 1.27))))
        )
        (pin bidirectional line (at 0 -83.82 0) (length 5.08)
          (name "IO_L16P_T2_34" (effects (font (size 1.27 1.27))))
          (number "AB6" (effects (font (size 1.27 1.27))))
        )
        (pin bidirectional line (at 0 -50.8 0) (length 5.08)
          (name "IO_L9N_T1_DQS_34" (effects (font (size 1.27 1.27))))
          (number "AC1" (effects (font (size 1.27 1.27))))
        )
        (pin bidirectional line (at 0 -60.96 0) (length 5.08)
          (name "IO_L11N_T1_SRCC_34" (effects (font (size 1.27 1.27))))
          (number "AC2" (effects (font (size 1.27 1.27))))
        )
        (pin bidirectional line (at 0 -76.2 0) (length 5.08)
          (name "IO_L14N_T2_SRCC_34" (effects (font (size 1.27 1.27))))
          (number "AC3" (effects (font (size 1.27 1.27))))
        )
        (pin bidirectional line (at 0 -73.66 0) (length 5.08)
          (name "IO_L14P_T2_SRCC_34" (effects (font (size 1.27 1.27))))
          (number "AC4" (effects (font (size 1.27 1.27))))
        )
        (pin passive line (at 0 0 0) (length 5.08) hide
          (name "VCCO_34" (effects (font (size 1.27 1.27))))
          (number "AC5" (effects (font (size 1.27 1.27))))
        )
        (pin bidirectional line (at 0 -86.36 0) (length 5.08)
          (name "IO_L16N_T2_34" (effects (font (size 1.27 1.27))))
          (number "AC6" (effects (font (size 1.27 1.27))))
        )
        (pin bidirectional line (at 0 -104.14 0) (length 5.08)
          (name "IO_L20P_T3_34" (effects (font (size 1.27 1.27))))
          (number "AD1" (effects (font (size 1.27 1.27))))
        )
        (pin passive line (at 0 0 0) (length 5.08) hide
          (name "VCCO_34" (effects (font (size 1.27 1.27))))
          (number "AD2" (effects (font (size 1.27 1.27))))
        )
        (pin bidirectional line (at 0 -101.6 0) (length 5.08)
          (name "IO_L19N_T3_VREF_34" (effects (font (size 1.27 1.27))))
          (number "AD3" (effects (font (size 1.27 1.27))))
        )
        (pin bidirectional line (at 0 -99.06 0) (length 5.08)
          (name "IO_L19P_T3_34" (effects (font (size 1.27 1.27))))
          (number "AD4" (effects (font (size 1.27 1.27))))
        )
        (pin bidirectional line (at 0 -96.52 0) (length 5.08)
          (name "IO_L18N_T2_34" (effects (font (size 1.27 1.27))))
          (number "AD5" (effects (font (size 1.27 1.27))))
        )
        (pin bidirectional line (at 0 -93.98 0) (length 5.08)
          (name "IO_L18P_T2_34" (effects (font (size 1.27 1.27))))
          (number "AD6" (effects (font (size 1.27 1.27))))
        )
        (pin bidirectional line (at 0 -106.68 0) (length 5.08)
          (name "IO_L20N_T3_34" (effects (font (size 1.27 1.27))))
          (number "AE1" (effects (font (size 1.27 1.27))))
        )
        (pin bidirectional line (at 0 -116.84 0) (length 5.08)
          (name "IO_L22N_T3_34" (effects (font (size 1.27 1.27))))
          (number "AE2" (effects (font (size 1.27 1.27))))
        )
        (pin bidirectional line (at 0 -114.3 0) (length 5.08)
          (name "IO_L22P_T3_34" (effects (font (size 1.27 1.27))))
          (number "AE3" (effects (font (size 1.27 1.27))))
        )
        (pin bidirectional line (at 0 -121.92 0) (length 5.08)
          (name "IO_L23N_T3_34" (effects (font (size 1.27 1.27))))
          (number "AE5" (effects (font (size 1.27 1.27))))
        )
        (pin bidirectional line (at 0 -119.38 0) (length 5.08)
          (name "IO_L23P_T3_34" (effects (font (size 1.27 1.27))))
          (number "AE6" (effects (font (size 1.27 1.27))))
        )
        (pin bidirectional line (at 0 -127 0) (length 5.08)
          (name "IO_L24N_T3_34" (effects (font (size 1.27 1.27))))
          (number "AF2" (effects (font (size 1.27 1.27))))
        )
        (pin bidirectional line (at 0 -124.46 0) (length 5.08)
          (name "IO_L24P_T3_34" (effects (font (size 1.27 1.27))))
          (number "AF3" (effects (font (size 1.27 1.27))))
        )
        (pin bidirectional line (at 0 -111.76 0) (length 5.08)
          (name "IO_L21N_T3_DQS_34" (effects (font (size 1.27 1.27))))
          (number "AF4" (effects (font (size 1.27 1.27))))
        )
        (pin bidirectional line (at 0 -109.22 0) (length 5.08)
          (name "IO_L21P_T3_DQS_34" (effects (font (size 1.27 1.27))))
          (number "AF5" (effects (font (size 1.27 1.27))))
        )
        (pin passive line (at 0 0 0) (length 5.08) hide
          (name "VCCO_34" (effects (font (size 1.27 1.27))))
          (number "AF6" (effects (font (size 1.27 1.27))))
        )
        (pin bidirectional line (at 0 -129.54 0) (length 5.08)
          (name "IO_25_VRP_34" (effects (font (size 1.27 1.27))))
          (number "T7" (effects (font (size 1.27 1.27))))
        )
        (pin bidirectional line (at 0 -15.24 0) (length 5.08)
          (name "IO_L2N_T0_34" (effects (font (size 1.27 1.27))))
          (number "U1" (effects (font (size 1.27 1.27))))
        )
        (pin bidirectional line (at 0 -12.7 0) (length 5.08)
          (name "IO_L2P_T0_34" (effects (font (size 1.27 1.27))))
          (number "U2" (effects (font (size 1.27 1.27))))
        )
        (pin passive line (at 0 0 0) (length 5.08) hide
          (name "VCCO_34" (effects (font (size 1.27 1.27))))
          (number "U3" (effects (font (size 1.27 1.27))))
        )
        (pin bidirectional line (at 0 -5.08 0) (length 5.08)
          (name "IO_0_VRN_34" (effects (font (size 1.27 1.27))))
          (number "U4" (effects (font (size 1.27 1.27))))
        )
        (pin bidirectional line (at 0 -10.16 0) (length 5.08)
          (name "IO_L1N_T0_34" (effects (font (size 1.27 1.27))))
          (number "U5" (effects (font (size 1.27 1.27))))
        )
        (pin bidirectional line (at 0 -7.62 0) (length 5.08)
          (name "IO_L1P_T0_34" (effects (font (size 1.27 1.27))))
          (number "U6" (effects (font (size 1.27 1.27))))
        )
        (pin bidirectional line (at 0 -27.94 0) (length 5.08)
          (name "IO_L5P_T0_34" (effects (font (size 1.27 1.27))))
          (number "U7" (effects (font (size 1.27 1.27))))
        )
        (pin bidirectional line (at 0 -45.72 0) (length 5.08)
          (name "IO_L8N_T1_34" (effects (font (size 1.27 1.27))))
          (number "V1" (effects (font (size 1.27 1.27))))
        )
        (pin bidirectional line (at 0 -43.18 0) (length 5.08)
          (name "IO_L8P_T1_34" (effects (font (size 1.27 1.27))))
          (number "V2" (effects (font (size 1.27 1.27))))
        )
        (pin bidirectional line (at 0 -22.86 0) (length 5.08)
          (name "IO_L4P_T0_34" (effects (font (size 1.27 1.27))))
          (number "V3" (effects (font (size 1.27 1.27))))
        )
        (pin bidirectional line (at 0 -33.02 0) (length 5.08)
          (name "IO_L6P_T0_34" (effects (font (size 1.27 1.27))))
          (number "V4" (effects (font (size 1.27 1.27))))
        )
        (pin bidirectional line (at 0 -30.48 0) (length 5.08)
          (name "IO_L5N_T0_34" (effects (font (size 1.27 1.27))))
          (number "V6" (effects (font (size 1.27 1.27))))
        )
        (pin bidirectional line (at 0 -53.34 0) (length 5.08)
          (name "IO_L10P_T1_34" (effects (font (size 1.27 1.27))))
          (number "W1" (effects (font (size 1.27 1.27))))
        )
        (pin bidirectional line (at 0 -25.4 0) (length 5.08)
          (name "IO_L4N_T0_34" (effects (font (size 1.27 1.27))))
          (number "W3" (effects (font (size 1.27 1.27))))
        )
        (pin bidirectional line (at 0 -35.56 0) (length 5.08)
          (name "IO_L6N_T0_VREF_34" (effects (font (size 1.27 1.27))))
          (number "W4" (effects (font (size 1.27 1.27))))
        )
        (pin bidirectional line (at 0 -20.32 0) (length 5.08)
          (name "IO_L3N_T0_DQS_34" (effects (font (size 1.27 1.27))))
          (number "W5" (effects (font (size 1.27 1.27))))
        )
        (pin bidirectional line (at 0 -17.78 0) (length 5.08)
          (name "IO_L3P_T0_DQS_34" (effects (font (size 1.27 1.27))))
          (number "W6" (effects (font (size 1.27 1.27))))
        )
        (pin bidirectional line (at 0 -55.88 0) (length 5.08)
          (name "IO_L10N_T1_34" (effects (font (size 1.27 1.27))))
          (number "Y1" (effects (font (size 1.27 1.27))))
        )
        (pin bidirectional line (at 0 -40.64 0) (length 5.08)
          (name "IO_L7N_T1_34" (effects (font (size 1.27 1.27))))
          (number "Y2" (effects (font (size 1.27 1.27))))
        )
        (pin bidirectional line (at 0 -38.1 0) (length 5.08)
          (name "IO_L7P_T1_34" (effects (font (size 1.27 1.27))))
          (number "Y3" (effects (font (size 1.27 1.27))))
        )
        (pin passive line (at 0 0 0) (length 5.08) hide
          (name "VCCO_34" (effects (font (size 1.27 1.27))))
          (number "Y4" (effects (font (size 1.27 1.27))))
        )
        (pin bidirectional line (at 0 -91.44 0) (length 5.08)
          (name "IO_L17N_T2_34" (effects (font (size 1.27 1.27))))
          (number "Y5" (effects (font (size 1.27 1.27))))
        )
        (pin bidirectional line (at 0 -88.9 0) (length 5.08)
          (name "IO_L17P_T2_34" (effects (font (size 1.27 1.27))))
          (number "Y6" (effects (font (size 1.27 1.27))))
        )
      )
      (symbol "XC7K160T-FFG676_9_1"
        (polyline
          (pts
            (xy 16.51 2.54)
            (xy 24.13 2.54)
            (xy 24.13 -55.88)
            (xy 16.51 -55.88)
          )
          (stroke (width 0.254) (type default))
          (fill (type background))
        )
        (polyline
          (pts
            (xy 38.1 2.54)
            (xy 30.48 2.54)
            (xy 30.48 -55.88)
            (xy 38.1 -55.88)
          )
          (stroke (width 0.254) (type default))
          (fill (type background))
        )
        (rectangle (start 5.08 6.35) (end 49.53 -58.42)
          (stroke (width 0.254) (type default))
          (fill (type background))
        )
        (text "GTX 115" (at 15.24 3.81 0)
          (effects (font (size 1.27 1.27) (thickness 0.15)) (justify left bottom))
        )
        (text "GTX 116" (at 30.48 3.81 0)
          (effects (font (size 1.27 1.27) (thickness 0.15)) (justify left bottom))
        )
        (pin bidirectional line (at 54.61 -17.78 180) (length 5.08)
          (name "MGTXTXN3_116" (effects (font (size 1.27 1.27))))
          (number "A3" (effects (font (size 1.27 1.27))))
        )
        (pin bidirectional line (at 54.61 -15.24 180) (length 5.08)
          (name "MGTXTXP3_116" (effects (font (size 1.27 1.27))))
          (number "A4" (effects (font (size 1.27 1.27))))
        )
        (pin bidirectional line (at 54.61 -12.7 180) (length 5.08)
          (name "MGTXTXN2_116" (effects (font (size 1.27 1.27))))
          (number "B1" (effects (font (size 1.27 1.27))))
        )
        (pin bidirectional line (at 54.61 -10.16 180) (length 5.08)
          (name "MGTXTXP2_116" (effects (font (size 1.27 1.27))))
          (number "B2" (effects (font (size 1.27 1.27))))
        )
        (pin bidirectional line (at 54.61 -40.64 180) (length 5.08)
          (name "MGTXRXN3_116" (effects (font (size 1.27 1.27))))
          (number "B5" (effects (font (size 1.27 1.27))))
        )
        (pin bidirectional line (at 54.61 -38.1 180) (length 5.08)
          (name "MGTXRXP3_116" (effects (font (size 1.27 1.27))))
          (number "B6" (effects (font (size 1.27 1.27))))
        )
        (pin bidirectional line (at 54.61 -35.56 180) (length 5.08)
          (name "MGTXRXN2_116" (effects (font (size 1.27 1.27))))
          (number "C3" (effects (font (size 1.27 1.27))))
        )
        (pin bidirectional line (at 54.61 -33.02 180) (length 5.08)
          (name "MGTXRXP2_116" (effects (font (size 1.27 1.27))))
          (number "C4" (effects (font (size 1.27 1.27))))
        )
        (pin bidirectional line (at 54.61 -7.62 180) (length 5.08)
          (name "MGTXTXN1_116" (effects (font (size 1.27 1.27))))
          (number "D1" (effects (font (size 1.27 1.27))))
        )
        (pin bidirectional line (at 54.61 -5.08 180) (length 5.08)
          (name "MGTXTXP1_116" (effects (font (size 1.27 1.27))))
          (number "D2" (effects (font (size 1.27 1.27))))
        )
        (pin bidirectional line (at 54.61 -48.26 180) (length 5.08)
          (name "MGTREFCLK0N_116" (effects (font (size 1.27 1.27))))
          (number "D5" (effects (font (size 1.27 1.27))))
        )
        (pin bidirectional line (at 54.61 -45.72 180) (length 5.08)
          (name "MGTREFCLK0P_116" (effects (font (size 1.27 1.27))))
          (number "D6" (effects (font (size 1.27 1.27))))
        )
        (pin bidirectional line (at 54.61 -30.48 180) (length 5.08)
          (name "MGTXRXN1_116" (effects (font (size 1.27 1.27))))
          (number "E3" (effects (font (size 1.27 1.27))))
        )
        (pin bidirectional line (at 54.61 -27.94 180) (length 5.08)
          (name "MGTXRXP1_116" (effects (font (size 1.27 1.27))))
          (number "E4" (effects (font (size 1.27 1.27))))
        )
        (pin bidirectional line (at 54.61 -2.54 180) (length 5.08)
          (name "MGTXTXN0_116" (effects (font (size 1.27 1.27))))
          (number "F1" (effects (font (size 1.27 1.27))))
        )
        (pin bidirectional line (at 54.61 0 180) (length 5.08)
          (name "MGTXTXP0_116" (effects (font (size 1.27 1.27))))
          (number "F2" (effects (font (size 1.27 1.27))))
        )
        (pin bidirectional line (at 54.61 -53.34 180) (length 5.08)
          (name "MGTREFCLK1N_116" (effects (font (size 1.27 1.27))))
          (number "F5" (effects (font (size 1.27 1.27))))
        )
        (pin bidirectional line (at 54.61 -50.8 180) (length 5.08)
          (name "MGTREFCLK1P_116" (effects (font (size 1.27 1.27))))
          (number "F6" (effects (font (size 1.27 1.27))))
        )
        (pin bidirectional line (at 54.61 -25.4 180) (length 5.08)
          (name "MGTXRXN0_116" (effects (font (size 1.27 1.27))))
          (number "G3" (effects (font (size 1.27 1.27))))
        )
        (pin bidirectional line (at 54.61 -22.86 180) (length 5.08)
          (name "MGTXRXP0_116" (effects (font (size 1.27 1.27))))
          (number "G4" (effects (font (size 1.27 1.27))))
        )
        (pin bidirectional line (at 0 -17.78 0) (length 5.08)
          (name "MGTXTXN3_115" (effects (font (size 1.27 1.27))))
          (number "H1" (effects (font (size 1.27 1.27))))
        )
        (pin bidirectional line (at 0 -15.24 0) (length 5.08)
          (name "MGTXTXP3_115" (effects (font (size 1.27 1.27))))
          (number "H2" (effects (font (size 1.27 1.27))))
        )
        (pin bidirectional line (at 0 -48.26 0) (length 5.08)
          (name "MGTREFCLK0N_115" (effects (font (size 1.27 1.27))))
          (number "H5" (effects (font (size 1.27 1.27))))
        )
        (pin bidirectional line (at 0 -45.72 0) (length 5.08)
          (name "MGTREFCLK0P_115" (effects (font (size 1.27 1.27))))
          (number "H6" (effects (font (size 1.27 1.27))))
        )
        (pin bidirectional line (at 0 -40.64 0) (length 5.08)
          (name "MGTXRXN3_115" (effects (font (size 1.27 1.27))))
          (number "J3" (effects (font (size 1.27 1.27))))
        )
        (pin bidirectional line (at 0 -38.1 0) (length 5.08)
          (name "MGTXRXP3_115" (effects (font (size 1.27 1.27))))
          (number "J4" (effects (font (size 1.27 1.27))))
        )
        (pin bidirectional line (at 0 -12.7 0) (length 5.08)
          (name "MGTXTXN2_115" (effects (font (size 1.27 1.27))))
          (number "K1" (effects (font (size 1.27 1.27))))
        )
        (pin bidirectional line (at 0 -10.16 0) (length 5.08)
          (name "MGTXTXP2_115" (effects (font (size 1.27 1.27))))
          (number "K2" (effects (font (size 1.27 1.27))))
        )
        (pin bidirectional line (at 0 -53.34 0) (length 5.08)
          (name "MGTREFCLK1N_115" (effects (font (size 1.27 1.27))))
          (number "K5" (effects (font (size 1.27 1.27))))
        )
        (pin bidirectional line (at 0 -50.8 0) (length 5.08)
          (name "MGTREFCLK1P_115" (effects (font (size 1.27 1.27))))
          (number "K6" (effects (font (size 1.27 1.27))))
        )
        (pin bidirectional line (at 0 -35.56 0) (length 5.08)
          (name "MGTXRXN2_115" (effects (font (size 1.27 1.27))))
          (number "L3" (effects (font (size 1.27 1.27))))
        )
        (pin bidirectional line (at 0 -33.02 0) (length 5.08)
          (name "MGTXRXP2_115" (effects (font (size 1.27 1.27))))
          (number "L4" (effects (font (size 1.27 1.27))))
        )
        (pin bidirectional line (at 0 -7.62 0) (length 5.08)
          (name "MGTXTXN1_115" (effects (font (size 1.27 1.27))))
          (number "M1" (effects (font (size 1.27 1.27))))
        )
        (pin bidirectional line (at 0 -5.08 0) (length 5.08)
          (name "MGTXTXP1_115" (effects (font (size 1.27 1.27))))
          (number "M2" (effects (font (size 1.27 1.27))))
        )
        (pin bidirectional line (at 0 -30.48 0) (length 5.08)
          (name "MGTXRXN1_115" (effects (font (size 1.27 1.27))))
          (number "N3" (effects (font (size 1.27 1.27))))
        )
        (pin bidirectional line (at 0 -27.94 0) (length 5.08)
          (name "MGTXRXP1_115" (effects (font (size 1.27 1.27))))
          (number "N4" (effects (font (size 1.27 1.27))))
        )
        (pin bidirectional line (at 0 -2.54 0) (length 5.08)
          (name "MGTXTXN0_115" (effects (font (size 1.27 1.27))))
          (number "P1" (effects (font (size 1.27 1.27))))
        )
        (pin bidirectional line (at 0 0 0) (length 5.08)
          (name "MGTXTXP0_115" (effects (font (size 1.27 1.27))))
          (number "P2" (effects (font (size 1.27 1.27))))
        )
        (pin bidirectional line (at 0 -25.4 0) (length 5.08)
          (name "MGTXRXN0_115" (effects (font (size 1.27 1.27))))
          (number "R3" (effects (font (size 1.27 1.27))))
        )
        (pin bidirectional line (at 0 -22.86 0) (length 5.08)
          (name "MGTXRXP0_115" (effects (font (size 1.27 1.27))))
          (number "R4" (effects (font (size 1.27 1.27))))
        )
      )
      (symbol "XC7K160T-FFG676_10_1"
        (rectangle (start 5.08 2.54) (end 39.37 -33.02)
          (stroke (width 0.254) (type default))
          (fill (type background))
        )
        (pin power_in line (at 0 -30.48 0) (length 5.08)
          (name "GND" (effects (font (size 1.27 1.27))))
          (number "A1" (effects (font (size 1.27 1.27))))
        )
        (pin passive line (at 0 -30.48 0) (length 5.08) hide
          (name "GND" (effects (font (size 1.27 1.27))))
          (number "A16" (effects (font (size 1.27 1.27))))
        )
        (pin passive line (at 0 -30.48 0) (length 5.08) hide
          (name "GND" (effects (font (size 1.27 1.27))))
          (number "A2" (effects (font (size 1.27 1.27))))
        )
        (pin passive line (at 0 -30.48 0) (length 5.08) hide
          (name "GND" (effects (font (size 1.27 1.27))))
          (number "A26" (effects (font (size 1.27 1.27))))
        )
        (pin passive line (at 0 -30.48 0) (length 5.08) hide
          (name "GND" (effects (font (size 1.27 1.27))))
          (number "A5" (effects (font (size 1.27 1.27))))
        )
        (pin passive line (at 0 -30.48 0) (length 5.08) hide
          (name "GND" (effects (font (size 1.27 1.27))))
          (number "A6" (effects (font (size 1.27 1.27))))
        )
        (pin passive line (at 0 -30.48 0) (length 5.08) hide
          (name "GND" (effects (font (size 1.27 1.27))))
          (number "A7" (effects (font (size 1.27 1.27))))
        )
        (pin passive line (at 0 -30.48 0) (length 5.08) hide
          (name "GND" (effects (font (size 1.27 1.27))))
          (number "AA16" (effects (font (size 1.27 1.27))))
        )
        (pin passive line (at 0 -30.48 0) (length 5.08) hide
          (name "GND" (effects (font (size 1.27 1.27))))
          (number "AA26" (effects (font (size 1.27 1.27))))
        )
        (pin passive line (at 0 -30.48 0) (length 5.08) hide
          (name "GND" (effects (font (size 1.27 1.27))))
          (number "AA6" (effects (font (size 1.27 1.27))))
        )
        (pin passive line (at 0 -30.48 0) (length 5.08) hide
          (name "GND" (effects (font (size 1.27 1.27))))
          (number "AB13" (effects (font (size 1.27 1.27))))
        )
        (pin passive line (at 0 -30.48 0) (length 5.08) hide
          (name "GND" (effects (font (size 1.27 1.27))))
          (number "AB23" (effects (font (size 1.27 1.27))))
        )
        (pin passive line (at 0 -30.48 0) (length 5.08) hide
          (name "GND" (effects (font (size 1.27 1.27))))
          (number "AB3" (effects (font (size 1.27 1.27))))
        )
        (pin passive line (at 0 -30.48 0) (length 5.08) hide
          (name "GND" (effects (font (size 1.27 1.27))))
          (number "AC10" (effects (font (size 1.27 1.27))))
        )
        (pin passive line (at 0 -30.48 0) (length 5.08) hide
          (name "GND" (effects (font (size 1.27 1.27))))
          (number "AC20" (effects (font (size 1.27 1.27))))
        )
        (pin passive line (at 0 -30.48 0) (length 5.08) hide
          (name "GND" (effects (font (size 1.27 1.27))))
          (number "AD17" (effects (font (size 1.27 1.27))))
        )
        (pin passive line (at 0 -30.48 0) (length 5.08) hide
          (name "GND" (effects (font (size 1.27 1.27))))
          (number "AD7" (effects (font (size 1.27 1.27))))
        )
        (pin passive line (at 0 -30.48 0) (length 5.08) hide
          (name "GND" (effects (font (size 1.27 1.27))))
          (number "AE14" (effects (font (size 1.27 1.27))))
        )
        (pin passive line (at 0 -30.48 0) (length 5.08) hide
          (name "GND" (effects (font (size 1.27 1.27))))
          (number "AE24" (effects (font (size 1.27 1.27))))
        )
        (pin passive line (at 0 -30.48 0) (length 5.08) hide
          (name "GND" (effects (font (size 1.27 1.27))))
          (number "AE4" (effects (font (size 1.27 1.27))))
        )
        (pin passive line (at 0 -30.48 0) (length 5.08) hide
          (name "GND" (effects (font (size 1.27 1.27))))
          (number "AF1" (effects (font (size 1.27 1.27))))
        )
        (pin passive line (at 0 -30.48 0) (length 5.08) hide
          (name "GND" (effects (font (size 1.27 1.27))))
          (number "AF11" (effects (font (size 1.27 1.27))))
        )
        (pin passive line (at 0 -30.48 0) (length 5.08) hide
          (name "GND" (effects (font (size 1.27 1.27))))
          (number "AF21" (effects (font (size 1.27 1.27))))
        )
        (pin passive line (at 0 -30.48 0) (length 5.08) hide
          (name "GND" (effects (font (size 1.27 1.27))))
          (number "B13" (effects (font (size 1.27 1.27))))
        )
        (pin passive line (at 0 -30.48 0) (length 5.08) hide
          (name "GND" (effects (font (size 1.27 1.27))))
          (number "B23" (effects (font (size 1.27 1.27))))
        )
        (pin power_in line (at 44.45 -10.16 180) (length 5.08)
          (name "MGTAVTT" (effects (font (size 1.27 1.27))))
          (number "B3" (effects (font (size 1.27 1.27))))
        )
        (pin passive line (at 0 -30.48 0) (length 5.08) hide
          (name "GND" (effects (font (size 1.27 1.27))))
          (number "B4" (effects (font (size 1.27 1.27))))
        )
        (pin passive line (at 0 -30.48 0) (length 5.08) hide
          (name "GND" (effects (font (size 1.27 1.27))))
          (number "B7" (effects (font (size 1.27 1.27))))
        )
        (pin passive line (at 0 -30.48 0) (length 5.08) hide
          (name "GND" (effects (font (size 1.27 1.27))))
          (number "C1" (effects (font (size 1.27 1.27))))
        )
        (pin passive line (at 0 -30.48 0) (length 5.08) hide
          (name "GND" (effects (font (size 1.27 1.27))))
          (number "C10" (effects (font (size 1.27 1.27))))
        )
        (pin passive line (at 44.45 -10.16 180) (length 5.08) hide
          (name "MGTAVTT" (effects (font (size 1.27 1.27))))
          (number "C2" (effects (font (size 1.27 1.27))))
        )
        (pin passive line (at 0 -30.48 0) (length 5.08) hide
          (name "GND" (effects (font (size 1.27 1.27))))
          (number "C20" (effects (font (size 1.27 1.27))))
        )
        (pin passive line (at 0 -30.48 0) (length 5.08) hide
          (name "GND" (effects (font (size 1.27 1.27))))
          (number "C5" (effects (font (size 1.27 1.27))))
        )
        (pin power_in line (at 44.45 0 180) (length 5.08)
          (name "MGTAVCC" (effects (font (size 1.27 1.27))))
          (number "C6" (effects (font (size 1.27 1.27))))
        )
        (pin passive line (at 0 -30.48 0) (length 5.08) hide
          (name "GND" (effects (font (size 1.27 1.27))))
          (number "C7" (effects (font (size 1.27 1.27))))
        )
        (pin passive line (at 0 -30.48 0) (length 5.08) hide
          (name "GND" (effects (font (size 1.27 1.27))))
          (number "D17" (effects (font (size 1.27 1.27))))
        )
        (pin passive line (at 44.45 -10.16 180) (length 5.08) hide
          (name "MGTAVTT" (effects (font (size 1.27 1.27))))
          (number "D3" (effects (font (size 1.27 1.27))))
        )
        (pin passive line (at 0 -30.48 0) (length 5.08) hide
          (name "GND" (effects (font (size 1.27 1.27))))
          (number "D4" (effects (font (size 1.27 1.27))))
        )
        (pin passive line (at 0 -30.48 0) (length 5.08) hide
          (name "GND" (effects (font (size 1.27 1.27))))
          (number "D7" (effects (font (size 1.27 1.27))))
        )
        (pin passive line (at 0 -30.48 0) (length 5.08) hide
          (name "GND" (effects (font (size 1.27 1.27))))
          (number "E1" (effects (font (size 1.27 1.27))))
        )
        (pin passive line (at 0 -30.48 0) (length 5.08) hide
          (name "GND" (effects (font (size 1.27 1.27))))
          (number "E14" (effects (font (size 1.27 1.27))))
        )
        (pin passive line (at 0 -30.48 0) (length 5.08) hide
          (name "GND" (effects (font (size 1.27 1.27))))
          (number "E2" (effects (font (size 1.27 1.27))))
        )
        (pin passive line (at 0 -30.48 0) (length 5.08) hide
          (name "GND" (effects (font (size 1.27 1.27))))
          (number "E24" (effects (font (size 1.27 1.27))))
        )
        (pin passive line (at 0 -30.48 0) (length 5.08) hide
          (name "GND" (effects (font (size 1.27 1.27))))
          (number "E5" (effects (font (size 1.27 1.27))))
        )
        (pin passive line (at 44.45 0 180) (length 5.08) hide
          (name "MGTAVCC" (effects (font (size 1.27 1.27))))
          (number "E6" (effects (font (size 1.27 1.27))))
        )
        (pin passive line (at 0 -30.48 0) (length 5.08) hide
          (name "GND" (effects (font (size 1.27 1.27))))
          (number "E7" (effects (font (size 1.27 1.27))))
        )
        (pin power_in line (at 0 -20.32 0) (length 5.08)
          (name "VCCBATT_0" (effects (font (size 1.27 1.27))))
          (number "E8" (effects (font (size 1.27 1.27))))
        )
        (pin passive line (at 0 -30.48 0) (length 5.08) hide
          (name "GND" (effects (font (size 1.27 1.27))))
          (number "F11" (effects (font (size 1.27 1.27))))
        )
        (pin passive line (at 0 -30.48 0) (length 5.08) hide
          (name "GND" (effects (font (size 1.27 1.27))))
          (number "F21" (effects (font (size 1.27 1.27))))
        )
        (pin passive line (at 0 -30.48 0) (length 5.08) hide
          (name "GND" (effects (font (size 1.27 1.27))))
          (number "F3" (effects (font (size 1.27 1.27))))
        )
        (pin passive line (at 0 -30.48 0) (length 5.08) hide
          (name "GND" (effects (font (size 1.27 1.27))))
          (number "F4" (effects (font (size 1.27 1.27))))
        )
        (pin passive line (at 0 -30.48 0) (length 5.08) hide
          (name "GND" (effects (font (size 1.27 1.27))))
          (number "F7" (effects (font (size 1.27 1.27))))
        )
        (pin passive line (at 0 -30.48 0) (length 5.08) hide
          (name "GND" (effects (font (size 1.27 1.27))))
          (number "G1" (effects (font (size 1.27 1.27))))
        )
        (pin passive line (at 0 -30.48 0) (length 5.08) hide
          (name "GND" (effects (font (size 1.27 1.27))))
          (number "G18" (effects (font (size 1.27 1.27))))
        )
        (pin passive line (at 44.45 -10.16 180) (length 5.08) hide
          (name "MGTAVTT" (effects (font (size 1.27 1.27))))
          (number "G2" (effects (font (size 1.27 1.27))))
        )
        (pin passive line (at 0 -30.48 0) (length 5.08) hide
          (name "GND" (effects (font (size 1.27 1.27))))
          (number "G5" (effects (font (size 1.27 1.27))))
        )
        (pin passive line (at 44.45 0 180) (length 5.08) hide
          (name "MGTAVCC" (effects (font (size 1.27 1.27))))
          (number "G6" (effects (font (size 1.27 1.27))))
        )
        (pin passive line (at 0 -30.48 0) (length 5.08) hide
          (name "GND" (effects (font (size 1.27 1.27))))
          (number "G8" (effects (font (size 1.27 1.27))))
        )
        (pin passive line (at 0 -30.48 0) (length 5.08) hide
          (name "GND" (effects (font (size 1.27 1.27))))
          (number "H15" (effects (font (size 1.27 1.27))))
        )
        (pin passive line (at 0 -30.48 0) (length 5.08) hide
          (name "GND" (effects (font (size 1.27 1.27))))
          (number "H25" (effects (font (size 1.27 1.27))))
        )
        (pin passive line (at 44.45 -10.16 180) (length 5.08) hide
          (name "MGTAVTT" (effects (font (size 1.27 1.27))))
          (number "H3" (effects (font (size 1.27 1.27))))
        )
        (pin passive line (at 0 -30.48 0) (length 5.08) hide
          (name "GND" (effects (font (size 1.27 1.27))))
          (number "H4" (effects (font (size 1.27 1.27))))
        )
        (pin passive line (at 0 -30.48 0) (length 5.08) hide
          (name "GND" (effects (font (size 1.27 1.27))))
          (number "H7" (effects (font (size 1.27 1.27))))
        )
        (pin passive line (at 0 -30.48 0) (length 5.08) hide
          (name "GND" (effects (font (size 1.27 1.27))))
          (number "J1" (effects (font (size 1.27 1.27))))
        )
        (pin passive line (at 0 -30.48 0) (length 5.08) hide
          (name "GND" (effects (font (size 1.27 1.27))))
          (number "J12" (effects (font (size 1.27 1.27))))
        )
        (pin passive line (at 0 -30.48 0) (length 5.08) hide
          (name "GND" (effects (font (size 1.27 1.27))))
          (number "J2" (effects (font (size 1.27 1.27))))
        )
        (pin passive line (at 0 -30.48 0) (length 5.08) hide
          (name "GND" (effects (font (size 1.27 1.27))))
          (number "J22" (effects (font (size 1.27 1.27))))
        )
        (pin passive line (at 0 -30.48 0) (length 5.08) hide
          (name "GND" (effects (font (size 1.27 1.27))))
          (number "J5" (effects (font (size 1.27 1.27))))
        )
        (pin passive line (at 44.45 0 180) (length 5.08) hide
          (name "MGTAVCC" (effects (font (size 1.27 1.27))))
          (number "J6" (effects (font (size 1.27 1.27))))
        )
        (pin power_in line (at 0 0 0) (length 5.08)
          (name "VCCINT" (effects (font (size 1.27 1.27))))
          (number "J9" (effects (font (size 1.27 1.27))))
        )
        (pin passive line (at 0 0 0) (length 5.08) hide
          (name "VCCINT" (effects (font (size 1.27 1.27))))
          (number "K10" (effects (font (size 1.27 1.27))))
        )
        (pin passive line (at 0 -30.48 0) (length 5.08) hide
          (name "GND" (effects (font (size 1.27 1.27))))
          (number "K11" (effects (font (size 1.27 1.27))))
        )
        (pin passive line (at 0 0 0) (length 5.08) hide
          (name "VCCINT" (effects (font (size 1.27 1.27))))
          (number "K12" (effects (font (size 1.27 1.27))))
        )
        (pin passive line (at 0 -30.48 0) (length 5.08) hide
          (name "GND" (effects (font (size 1.27 1.27))))
          (number "K13" (effects (font (size 1.27 1.27))))
        )
        (pin passive line (at 0 0 0) (length 5.08) hide
          (name "VCCINT" (effects (font (size 1.27 1.27))))
          (number "K14" (effects (font (size 1.27 1.27))))
        )
        (pin passive line (at 0 -30.48 0) (length 5.08) hide
          (name "GND" (effects (font (size 1.27 1.27))))
          (number "K19" (effects (font (size 1.27 1.27))))
        )
        (pin passive line (at 0 -30.48 0) (length 5.08) hide
          (name "GND" (effects (font (size 1.27 1.27))))
          (number "K3" (effects (font (size 1.27 1.27))))
        )
        (pin passive line (at 0 -30.48 0) (length 5.08) hide
          (name "GND" (effects (font (size 1.27 1.27))))
          (number "K4" (effects (font (size 1.27 1.27))))
        )
        (pin passive line (at 0 -30.48 0) (length 5.08) hide
          (name "GND" (effects (font (size 1.27 1.27))))
          (number "K7" (effects (font (size 1.27 1.27))))
        )
        (pin passive line (at 0 0 0) (length 5.08) hide
          (name "VCCINT" (effects (font (size 1.27 1.27))))
          (number "K8" (effects (font (size 1.27 1.27))))
        )
        (pin passive line (at 0 -30.48 0) (length 5.08) hide
          (name "GND" (effects (font (size 1.27 1.27))))
          (number "K9" (effects (font (size 1.27 1.27))))
        )
        (pin passive line (at 0 -30.48 0) (length 5.08) hide
          (name "GND" (effects (font (size 1.27 1.27))))
          (number "L1" (effects (font (size 1.27 1.27))))
        )
        (pin passive line (at 0 -30.48 0) (length 5.08) hide
          (name "GND" (effects (font (size 1.27 1.27))))
          (number "L10" (effects (font (size 1.27 1.27))))
        )
        (pin power_in line (at 0 -5.08 0) (length 5.08)
          (name "VCCAUX" (effects (font (size 1.27 1.27))))
          (number "L11" (effects (font (size 1.27 1.27))))
        )
        (pin passive line (at 0 -30.48 0) (length 5.08) hide
          (name "GND" (effects (font (size 1.27 1.27))))
          (number "L12" (effects (font (size 1.27 1.27))))
        )
        (pin passive line (at 0 0 0) (length 5.08) hide
          (name "VCCINT" (effects (font (size 1.27 1.27))))
          (number "L13" (effects (font (size 1.27 1.27))))
        )
        (pin passive line (at 0 -30.48 0) (length 5.08) hide
          (name "GND" (effects (font (size 1.27 1.27))))
          (number "L14" (effects (font (size 1.27 1.27))))
        )
        (pin passive line (at 0 0 0) (length 5.08) hide
          (name "VCCINT" (effects (font (size 1.27 1.27))))
          (number "L15" (effects (font (size 1.27 1.27))))
        )
        (pin passive line (at 0 -30.48 0) (length 5.08) hide
          (name "GND" (effects (font (size 1.27 1.27))))
          (number "L16" (effects (font (size 1.27 1.27))))
        )
        (pin passive line (at 44.45 -10.16 180) (length 5.08) hide
          (name "MGTAVTT" (effects (font (size 1.27 1.27))))
          (number "L2" (effects (font (size 1.27 1.27))))
        )
        (pin passive line (at 0 -30.48 0) (length 5.08) hide
          (name "GND" (effects (font (size 1.27 1.27))))
          (number "L26" (effects (font (size 1.27 1.27))))
        )
        (pin passive line (at 0 -30.48 0) (length 5.08) hide
          (name "GND" (effects (font (size 1.27 1.27))))
          (number "L5" (effects (font (size 1.27 1.27))))
        )
        (pin passive line (at 44.45 0 180) (length 5.08) hide
          (name "MGTAVCC" (effects (font (size 1.27 1.27))))
          (number "L6" (effects (font (size 1.27 1.27))))
        )
        (pin passive line (at 0 0 0) (length 5.08) hide
          (name "VCCINT" (effects (font (size 1.27 1.27))))
          (number "L9" (effects (font (size 1.27 1.27))))
        )
        (pin passive line (at 0 -5.08 0) (length 5.08) hide
          (name "VCCAUX" (effects (font (size 1.27 1.27))))
          (number "M10" (effects (font (size 1.27 1.27))))
        )
        (pin power_in line (at 0 -15.24 0) (length 5.08)
          (name "GNDADC_0" (effects (font (size 1.27 1.27))))
          (number "M11" (effects (font (size 1.27 1.27))))
        )
        (pin power_in line (at 0 -12.7 0) (length 5.08)
          (name "VCCADC_0" (effects (font (size 1.27 1.27))))
          (number "M12" (effects (font (size 1.27 1.27))))
        )
        (pin passive line (at 0 -30.48 0) (length 5.08) hide
          (name "GND" (effects (font (size 1.27 1.27))))
          (number "M13" (effects (font (size 1.27 1.27))))
        )
        (pin passive line (at 0 0 0) (length 5.08) hide
          (name "VCCINT" (effects (font (size 1.27 1.27))))
          (number "M14" (effects (font (size 1.27 1.27))))
        )
        (pin passive line (at 0 -30.48 0) (length 5.08) hide
          (name "GND" (effects (font (size 1.27 1.27))))
          (number "M15" (effects (font (size 1.27 1.27))))
        )
        (pin passive line (at 0 -30.48 0) (length 5.08) hide
          (name "GND" (effects (font (size 1.27 1.27))))
          (number "M23" (effects (font (size 1.27 1.27))))
        )
        (pin passive line (at 44.45 -10.16 180) (length 5.08) hide
          (name "MGTAVTT" (effects (font (size 1.27 1.27))))
          (number "M3" (effects (font (size 1.27 1.27))))
        )
        (pin passive line (at 0 -30.48 0) (length 5.08) hide
          (name "GND" (effects (font (size 1.27 1.27))))
          (number "M4" (effects (font (size 1.27 1.27))))
        )
        (pin power_in line (at 44.45 -15.24 180) (length 5.08)
          (name "MGTAVTTRCAL_115" (effects (font (size 1.27 1.27))))
          (number "M5" (effects (font (size 1.27 1.27))))
        )
        (pin power_in line (at 44.45 -17.78 180) (length 5.08)
          (name "MGTRREF_115" (effects (font (size 1.27 1.27))))
          (number "M6" (effects (font (size 1.27 1.27))))
        )
        (pin passive line (at 0 -30.48 0) (length 5.08) hide
          (name "GND" (effects (font (size 1.27 1.27))))
          (number "M7" (effects (font (size 1.27 1.27))))
        )
        (pin passive line (at 0 0 0) (length 5.08) hide
          (name "VCCINT" (effects (font (size 1.27 1.27))))
          (number "M8" (effects (font (size 1.27 1.27))))
        )
        (pin passive line (at 0 -30.48 0) (length 5.08) hide
          (name "GND" (effects (font (size 1.27 1.27))))
          (number "M9" (effects (font (size 1.27 1.27))))
        )
        (pin passive line (at 0 -30.48 0) (length 5.08) hide
          (name "GND" (effects (font (size 1.27 1.27))))
          (number "N1" (effects (font (size 1.27 1.27))))
        )
        (pin passive line (at 0 -30.48 0) (length 5.08) hide
          (name "GND" (effects (font (size 1.27 1.27))))
          (number "N10" (effects (font (size 1.27 1.27))))
        )
        (pin power_in line (at 0 -25.4 0) (length 5.08)
          (name "VCCBRAM" (effects (font (size 1.27 1.27))))
          (number "N13" (effects (font (size 1.27 1.27))))
        )
        (pin passive line (at 0 -30.48 0) (length 5.08) hide
          (name "GND" (effects (font (size 1.27 1.27))))
          (number "N14" (effects (font (size 1.27 1.27))))
        )
        (pin passive line (at 0 0 0) (length 5.08) hide
          (name "VCCINT" (effects (font (size 1.27 1.27))))
          (number "N15" (effects (font (size 1.27 1.27))))
        )
        (pin passive line (at 0 -30.48 0) (length 5.08) hide
          (name "GND" (effects (font (size 1.27 1.27))))
          (number "N2" (effects (font (size 1.27 1.27))))
        )
        (pin passive line (at 0 -30.48 0) (length 5.08) hide
          (name "GND" (effects (font (size 1.27 1.27))))
          (number "N20" (effects (font (size 1.27 1.27))))
        )
        (pin passive line (at 0 -30.48 0) (length 5.08) hide
          (name "GND" (effects (font (size 1.27 1.27))))
          (number "N5" (effects (font (size 1.27 1.27))))
        )
        (pin power_in line (at 44.45 -5.08 180) (length 5.08)
          (name "MGTVCCAUX" (effects (font (size 1.27 1.27))))
          (number "N6" (effects (font (size 1.27 1.27))))
        )
        (pin passive line (at 0 -30.48 0) (length 5.08) hide
          (name "GND" (effects (font (size 1.27 1.27))))
          (number "N7" (effects (font (size 1.27 1.27))))
        )
        (pin passive line (at 0 0 0) (length 5.08) hide
          (name "VCCINT" (effects (font (size 1.27 1.27))))
          (number "N9" (effects (font (size 1.27 1.27))))
        )
        (pin passive line (at 0 -5.08 0) (length 5.08) hide
          (name "VCCAUX" (effects (font (size 1.27 1.27))))
          (number "P10" (effects (font (size 1.27 1.27))))
        )
        (pin passive line (at 0 -30.48 0) (length 5.08) hide
          (name "GND" (effects (font (size 1.27 1.27))))
          (number "P13" (effects (font (size 1.27 1.27))))
        )
        (pin passive line (at 0 0 0) (length 5.08) hide
          (name "VCCINT" (effects (font (size 1.27 1.27))))
          (number "P14" (effects (font (size 1.27 1.27))))
        )
        (pin passive line (at 0 -30.48 0) (length 5.08) hide
          (name "GND" (effects (font (size 1.27 1.27))))
          (number "P15" (effects (font (size 1.27 1.27))))
        )
        (pin passive line (at 0 -30.48 0) (length 5.08) hide
          (name "GND" (effects (font (size 1.27 1.27))))
          (number "P17" (effects (font (size 1.27 1.27))))
        )
        (pin passive line (at 0 -30.48 0) (length 5.08) hide
          (name "GND" (effects (font (size 1.27 1.27))))
          (number "P3" (effects (font (size 1.27 1.27))))
        )
        (pin passive line (at 0 -30.48 0) (length 5.08) hide
          (name "GND" (effects (font (size 1.27 1.27))))
          (number "P4" (effects (font (size 1.27 1.27))))
        )
        (pin power_in line (at 0 -7.62 0) (length 5.08)
          (name "VCCAUX_IO_G0" (effects (font (size 1.27 1.27))))
          (number "P8" (effects (font (size 1.27 1.27))))
        )
        (pin passive line (at 0 -30.48 0) (length 5.08) hide
          (name "GND" (effects (font (size 1.27 1.27))))
          (number "P9" (effects (font (size 1.27 1.27))))
        )
        (pin passive line (at 0 -30.48 0) (length 5.08) hide
          (name "GND" (effects (font (size 1.27 1.27))))
          (number "R1" (effects (font (size 1.27 1.27))))
        )
        (pin passive line (at 0 -30.48 0) (length 5.08) hide
          (name "GND" (effects (font (size 1.27 1.27))))
          (number "R10" (effects (font (size 1.27 1.27))))
        )
        (pin passive line (at 0 -25.4 0) (length 5.08) hide
          (name "VCCBRAM" (effects (font (size 1.27 1.27))))
          (number "R13" (effects (font (size 1.27 1.27))))
        )
        (pin passive line (at 0 -30.48 0) (length 5.08) hide
          (name "GND" (effects (font (size 1.27 1.27))))
          (number "R14" (effects (font (size 1.27 1.27))))
        )
        (pin passive line (at 0 0 0) (length 5.08) hide
          (name "VCCINT" (effects (font (size 1.27 1.27))))
          (number "R15" (effects (font (size 1.27 1.27))))
        )
        (pin passive line (at 0 -30.48 0) (length 5.08) hide
          (name "GND" (effects (font (size 1.27 1.27))))
          (number "R2" (effects (font (size 1.27 1.27))))
        )
        (pin passive line (at 0 -30.48 0) (length 5.08) hide
          (name "GND" (effects (font (size 1.27 1.27))))
          (number "R24" (effects (font (size 1.27 1.27))))
        )
        (pin passive line (at 0 -30.48 0) (length 5.08) hide
          (name "GND" (effects (font (size 1.27 1.27))))
          (number "R5" (effects (font (size 1.27 1.27))))
        )
        (pin passive line (at 0 -30.48 0) (length 5.08) hide
          (name "GND" (effects (font (size 1.27 1.27))))
          (number "R8" (effects (font (size 1.27 1.27))))
        )
        (pin passive line (at 0 -7.62 0) (length 5.08) hide
          (name "VCCAUX_IO_G0" (effects (font (size 1.27 1.27))))
          (number "R9" (effects (font (size 1.27 1.27))))
        )
        (pin passive line (at 0 -30.48 0) (length 5.08) hide
          (name "GND" (effects (font (size 1.27 1.27))))
          (number "T1" (effects (font (size 1.27 1.27))))
        )
        (pin passive line (at 0 -5.08 0) (length 5.08) hide
          (name "VCCAUX" (effects (font (size 1.27 1.27))))
          (number "T10" (effects (font (size 1.27 1.27))))
        )
        (pin passive line (at 0 -30.48 0) (length 5.08) hide
          (name "GND" (effects (font (size 1.27 1.27))))
          (number "T11" (effects (font (size 1.27 1.27))))
        )
        (pin passive line (at 0 -25.4 0) (length 5.08) hide
          (name "VCCBRAM" (effects (font (size 1.27 1.27))))
          (number "T12" (effects (font (size 1.27 1.27))))
        )
        (pin passive line (at 0 -30.48 0) (length 5.08) hide
          (name "GND" (effects (font (size 1.27 1.27))))
          (number "T13" (effects (font (size 1.27 1.27))))
        )
        (pin passive line (at 0 0 0) (length 5.08) hide
          (name "VCCINT" (effects (font (size 1.27 1.27))))
          (number "T14" (effects (font (size 1.27 1.27))))
        )
        (pin passive line (at 0 -30.48 0) (length 5.08) hide
          (name "GND" (effects (font (size 1.27 1.27))))
          (number "T15" (effects (font (size 1.27 1.27))))
        )
        (pin passive line (at 0 -30.48 0) (length 5.08) hide
          (name "GND" (effects (font (size 1.27 1.27))))
          (number "T21" (effects (font (size 1.27 1.27))))
        )
        (pin passive line (at 0 -30.48 0) (length 5.08) hide
          (name "GND" (effects (font (size 1.27 1.27))))
          (number "T3" (effects (font (size 1.27 1.27))))
        )
        (pin passive line (at 0 -30.48 0) (length 5.08) hide
          (name "GND" (effects (font (size 1.27 1.27))))
          (number "T4" (effects (font (size 1.27 1.27))))
        )
        (pin passive line (at 0 -7.62 0) (length 5.08) hide
          (name "VCCAUX_IO_G0" (effects (font (size 1.27 1.27))))
          (number "T8" (effects (font (size 1.27 1.27))))
        )
        (pin passive line (at 0 -30.48 0) (length 5.08) hide
          (name "GND" (effects (font (size 1.27 1.27))))
          (number "T9" (effects (font (size 1.27 1.27))))
        )
        (pin passive line (at 0 -30.48 0) (length 5.08) hide
          (name "GND" (effects (font (size 1.27 1.27))))
          (number "U10" (effects (font (size 1.27 1.27))))
        )
        (pin passive line (at 0 -5.08 0) (length 5.08) hide
          (name "VCCAUX" (effects (font (size 1.27 1.27))))
          (number "U11" (effects (font (size 1.27 1.27))))
        )
        (pin passive line (at 0 -30.48 0) (length 5.08) hide
          (name "GND" (effects (font (size 1.27 1.27))))
          (number "U12" (effects (font (size 1.27 1.27))))
        )
        (pin passive line (at 0 -25.4 0) (length 5.08) hide
          (name "VCCBRAM" (effects (font (size 1.27 1.27))))
          (number "U13" (effects (font (size 1.27 1.27))))
        )
        (pin passive line (at 0 -30.48 0) (length 5.08) hide
          (name "GND" (effects (font (size 1.27 1.27))))
          (number "U14" (effects (font (size 1.27 1.27))))
        )
        (pin passive line (at 0 0 0) (length 5.08) hide
          (name "VCCINT" (effects (font (size 1.27 1.27))))
          (number "U15" (effects (font (size 1.27 1.27))))
        )
        (pin passive line (at 0 -30.48 0) (length 5.08) hide
          (name "GND" (effects (font (size 1.27 1.27))))
          (number "U18" (effects (font (size 1.27 1.27))))
        )
        (pin passive line (at 0 -30.48 0) (length 5.08) hide
          (name "GND" (effects (font (size 1.27 1.27))))
          (number "U8" (effects (font (size 1.27 1.27))))
        )
        (pin passive line (at 0 -30.48 0) (length 5.08) hide
          (name "GND" (effects (font (size 1.27 1.27))))
          (number "V15" (effects (font (size 1.27 1.27))))
        )
        (pin passive line (at 0 -30.48 0) (length 5.08) hide
          (name "GND" (effects (font (size 1.27 1.27))))
          (number "V25" (effects (font (size 1.27 1.27))))
        )
        (pin passive line (at 0 -30.48 0) (length 5.08) hide
          (name "GND" (effects (font (size 1.27 1.27))))
          (number "V5" (effects (font (size 1.27 1.27))))
        )
        (pin passive line (at 0 -30.48 0) (length 5.08) hide
          (name "GND" (effects (font (size 1.27 1.27))))
          (number "W12" (effects (font (size 1.27 1.27))))
        )
        (pin passive line (at 0 -30.48 0) (length 5.08) hide
          (name "GND" (effects (font (size 1.27 1.27))))
          (number "W2" (effects (font (size 1.27 1.27))))
        )
        (pin passive line (at 0 -30.48 0) (length 5.08) hide
          (name "GND" (effects (font (size 1.27 1.27))))
          (number "W22" (effects (font (size 1.27 1.27))))
        )
        (pin passive line (at 0 -30.48 0) (length 5.08) hide
          (name "GND" (effects (font (size 1.27 1.27))))
          (number "Y19" (effects (font (size 1.27 1.27))))
        )
        (pin passive line (at 0 -30.48 0) (length 5.08) hide
          (name "GND" (effects (font (size 1.27 1.27))))
          (number "Y9" (effects (font (size 1.27 1.27))))
        )
      )
      (symbol "XC7K160T-FFG676_11_1"
        (rectangle (start 5.08 2.54) (end 30.48 -38.1)
          (stroke (width 0.254) (type default))
          (fill (type background))
        )
        (pin bidirectional line (at 0 -17.78 0) (length 5.08)
          (name "CCLK_0" (effects (font (size 1.27 1.27))))
          (number "C8" (effects (font (size 1.27 1.27))))
        )
        (pin bidirectional line (at 0 -33.02 0) (length 5.08)
          (name "INIT_B_0" (effects (font (size 1.27 1.27))))
          (number "G7" (effects (font (size 1.27 1.27))))
        )
        (pin bidirectional line (at 0 -30.48 0) (length 5.08)
          (name "DONE_0" (effects (font (size 1.27 1.27))))
          (number "J7" (effects (font (size 1.27 1.27))))
        )
        (pin power_in line (at 0 0 0) (length 5.08)
          (name "VCCO_0" (effects (font (size 1.27 1.27))))
          (number "L7" (effects (font (size 1.27 1.27))))
        )
        (pin bidirectional line (at 0 -12.7 0) (length 5.08)
          (name "TCK_0" (effects (font (size 1.27 1.27))))
          (number "L8" (effects (font (size 1.27 1.27))))
        )
        (pin bidirectional line (at 35.56 -20.32 180) (length 5.08)
          (name "VREFN_0" (effects (font (size 1.27 1.27))))
          (number "N11" (effects (font (size 1.27 1.27))))
        )
        (pin bidirectional line (at 35.56 -10.16 180) (length 5.08)
          (name "VP_0" (effects (font (size 1.27 1.27))))
          (number "N12" (effects (font (size 1.27 1.27))))
        )
        (pin bidirectional line (at 0 -10.16 0) (length 5.08)
          (name "TMS_0" (effects (font (size 1.27 1.27))))
          (number "N8" (effects (font (size 1.27 1.27))))
        )
        (pin bidirectional line (at 35.56 -12.7 180) (length 5.08)
          (name "VN_0" (effects (font (size 1.27 1.27))))
          (number "P11" (effects (font (size 1.27 1.27))))
        )
        (pin bidirectional line (at 35.56 -17.78 180) (length 5.08)
          (name "VREFP_0" (effects (font (size 1.27 1.27))))
          (number "P12" (effects (font (size 1.27 1.27))))
        )
        (pin bidirectional line (at 0 -25.4 0) (length 5.08)
          (name "M2_0" (effects (font (size 1.27 1.27))))
          (number "P5" (effects (font (size 1.27 1.27))))
        )
        (pin bidirectional line (at 0 -35.56 0) (length 5.08)
          (name "PROGRAM_B_0" (effects (font (size 1.27 1.27))))
          (number "P6" (effects (font (size 1.27 1.27))))
        )
        (pin bidirectional line (at 35.56 -5.08 180) (length 5.08)
          (name "CFGBVS_0" (effects (font (size 1.27 1.27))))
          (number "P7" (effects (font (size 1.27 1.27))))
        )
        (pin bidirectional line (at 35.56 -26.67 180) (length 5.08)
          (name "DXN_0" (effects (font (size 1.27 1.27))))
          (number "R11" (effects (font (size 1.27 1.27))))
        )
        (pin bidirectional line (at 35.56 -24.13 180) (length 5.08)
          (name "DXP_0" (effects (font (size 1.27 1.27))))
          (number "R12" (effects (font (size 1.27 1.27))))
        )
        (pin bidirectional line (at 0 -5.08 0) (length 5.08)
          (name "TDI_0" (effects (font (size 1.27 1.27))))
          (number "R6" (effects (font (size 1.27 1.27))))
        )
        (pin bidirectional line (at 0 -7.62 0) (length 5.08)
          (name "TDO_0" (effects (font (size 1.27 1.27))))
          (number "R7" (effects (font (size 1.27 1.27))))
        )
        (pin bidirectional line (at 0 -22.86 0) (length 5.08)
          (name "M1_0" (effects (font (size 1.27 1.27))))
          (number "T2" (effects (font (size 1.27 1.27))))
        )
        (pin bidirectional line (at 0 -20.32 0) (length 5.08)
          (name "M0_0" (effects (font (size 1.27 1.27))))
          (number "T5" (effects (font (size 1.27 1.27))))
        )
        (pin passive line (at 0 0 0) (length 5.08) hide
          (name "VCCO_0" (effects (font (size 1.27 1.27))))
          (number "T6" (effects (font (size 1.27 1.27))))
        )
      )
    )
	(symbol "antmicroModularConnectorsJacksWithMagnetics:Bus_RJ45_5-2337992-8" (in_bom yes) (on_board yes)
      (property "Reference" "J" (at 35.56 -2.54 0)
        (effects (font (size 1.27 1.27) (thickness 0.15)) (justify left bottom))
      )
      (property "Value" "Bus_RJ45_5-2337992-8" (at 35.56 -5.08 0)
        (effects (font (size 1.27 1.27) (thickness 0.15)) (justify left bottom))
      )
      (property "Footprint" "antmicro-footprints:RJ45_5-2337992-8_Horizontal" (at 35.56 -7.62 0)
        (effects (font (size 1.27 1.27) (thickness 0.15)) (justify left bottom) hide)
      )
      (property "Datasheet" "https://www.te.com/commerce/DocumentDelivery/DDEController?Action=showdoc&DocId=Customer+Drawing%7F5-2337992-8%7FA%7Fpdf%7FEnglish%7FENG_CD_5-2337992-8_A.pdf%7F5-2337992-8" (at 35.56 -10.16 0)
        (effects (font (size 1.27 1.27) (thickness 0.15)) (justify left bottom) hide)
      )
      (property "MPN" "5-2337992-8" (at 35.56 -12.7 0)
        (effects (font (size 1.27 1.27) (thickness 0.15)) (justify left bottom) hide)
      )
      (property "Manufacturer" "TE Connectivity" (at 35.56 -15.24 0)
        (effects (font (size 1.27 1.27) (thickness 0.15)) (justify left bottom) hide)
      )
      (property "Author" "Antmicro" (at 35.56 -17.78 0)
        (effects (font (size 1.27 1.27) (thickness 0.15)) (justify left bottom) hide)
      )
      (property "License" "Apache-2.0" (at 35.56 -20.32 0)
        (effects (font (size 1.27 1.27) (thickness 0.15)) (justify left bottom) hide)
      )
      (property "ki_keywords" "RJ45 PoE Ethernet te connectivity magnetics gigabit power" (at 0 0 0)
        (effects (font (size 1.27 1.27)) hide)
      )
      (property "ki_description" "RJ45 Gigabit Ethernet Jack w/ Magnetics and PoE, Single Port, 802.3at Power over Ethernet" (at 0 0 0)
        (effects (font (size 1.27 1.27)) hide)
      )
      (property "ki_fp_filters" "CONN18_5-2337992-8_TEC" (at 0 0 0)
        (effects (font (size 1.27 1.27)) hide)
      )
      (symbol "Bus_RJ45_5-2337992-8_1_1"
        (polyline
          (pts
            (xy 8.89 -13.97)
            (xy 13.97 -13.97)
          )
          (stroke (width 0.254) (type default))
          (fill (type background))
        )
        (polyline
          (pts
            (xy 8.89 -1.27)
            (xy 8.89 -13.97)
          )
          (stroke (width 0.254) (type default))
          (fill (type background))
        )
        (polyline
          (pts
            (xy 8.89 -1.27)
            (xy 13.97 -1.27)
          )
          (stroke (width 0.254) (type default))
          (fill (type background))
        )
        (polyline
          (pts
            (xy 13.97 -13.97)
            (xy 13.97 -12.7)
          )
          (stroke (width 0.254) (type default))
          (fill (type background))
        )
        (polyline
          (pts
            (xy 13.97 -12.7)
            (xy 15.24 -12.7)
          )
          (stroke (width 0.254) (type default))
          (fill (type background))
        )
        (polyline
          (pts
            (xy 13.97 -2.54)
            (xy 15.24 -2.54)
          )
          (stroke (width 0.254) (type default))
          (fill (type background))
        )
        (polyline
          (pts
            (xy 13.97 -1.27)
            (xy 13.97 -2.54)
          )
          (stroke (width 0.254) (type default))
          (fill (type background))
        )
        (polyline
          (pts
            (xy 15.24 -12.7)
            (xy 15.24 -11.43)
          )
          (stroke (width 0.254) (type default))
          (fill (type background))
        )
        (polyline
          (pts
            (xy 15.24 -11.43)
            (xy 16.51 -11.43)
          )
          (stroke (width 0.254) (type default))
          (fill (type background))
        )
        (polyline
          (pts
            (xy 15.24 -3.81)
            (xy 16.51 -3.81)
          )
          (stroke (width 0.254) (type default))
          (fill (type background))
        )
        (polyline
          (pts
            (xy 15.24 -2.54)
            (xy 15.24 -3.81)
          )
          (stroke (width 0.254) (type default))
          (fill (type background))
        )
        (polyline
          (pts
            (xy 16.51 -3.81)
            (xy 16.51 -11.43)
          )
          (stroke (width 0.254) (type default))
          (fill (type background))
        )
        (rectangle (start 2.54 2.54) (end 19.05 -38.1)
          (stroke (width 0.254) (type default))
          (fill (type background))
        )
        (pin bidirectional line (at 0 0 0) (length 2.54)
          (name "P1" (effects (font (size 1.27 1.27))))
          (number "1" (effects (font (size 1.27 1.27))))
        )
        (pin bidirectional line (at 0 -17.78 0) (length 2.54)
          (name "P10" (effects (font (size 1.27 1.27))))
          (number "10" (effects (font (size 1.27 1.27))))
        )
        (pin bidirectional line (at 0 -27.94 0) (length 2.54)
          (name "VC1" (effects (font (size 1.27 1.27))))
          (number "11" (effects (font (size 1.27 1.27))))
        )
        (pin bidirectional line (at 0 -30.48 0) (length 2.54)
          (name "VC2" (effects (font (size 1.27 1.27))))
          (number "12" (effects (font (size 1.27 1.27))))
        )
        (pin bidirectional line (at 0 -33.02 0) (length 2.54)
          (name "VC3" (effects (font (size 1.27 1.27))))
          (number "13" (effects (font (size 1.27 1.27))))
        )
        (pin bidirectional line (at 0 -35.56 0) (length 2.54)
          (name "VC4" (effects (font (size 1.27 1.27))))
          (number "14" (effects (font (size 1.27 1.27))))
        )
        (pin passive line (at 21.59 -27.94 180) (length 2.54)
          (name "LED_GRN+" (effects (font (size 1.27 1.27))))
          (number "15" (effects (font (size 1.27 1.27))))
        )
        (pin passive line (at 21.59 -30.48 180) (length 2.54)
          (name "LED_GRN-" (effects (font (size 1.27 1.27))))
          (number "16" (effects (font (size 1.27 1.27))))
        )
        (pin passive line (at 21.59 -22.86 180) (length 2.54)
          (name "LED_YEL+" (effects (font (size 1.27 1.27))))
          (number "17" (effects (font (size 1.27 1.27))))
        )
        (pin passive line (at 21.59 -25.4 180) (length 2.54)
          (name "LED_YEL-" (effects (font (size 1.27 1.27))))
          (number "18" (effects (font (size 1.27 1.27))))
        )
        (pin passive line (at 21.59 -35.56 180) (length 2.54)
          (name "SHIELD" (effects (font (size 1.27 1.27))))
          (number "19" (effects (font (size 1.27 1.27))))
        )
        (pin bidirectional line (at 0 -2.54 0) (length 2.54)
          (name "P2" (effects (font (size 1.27 1.27))))
          (number "2" (effects (font (size 1.27 1.27))))
        )
        (pin passive line (at 21.59 -35.56 180) (length 2.54) hide
          (name "SHIELD" (effects (font (size 1.27 1.27))))
          (number "20" (effects (font (size 1.27 1.27))))
        )
        (pin bidirectional line (at 0 -5.08 0) (length 2.54)
          (name "P3" (effects (font (size 1.27 1.27))))
          (number "3" (effects (font (size 1.27 1.27))))
        )
        (pin bidirectional line (at 0 -22.86 0) (length 2.54)
          (name "P4" (effects (font (size 1.27 1.27))))
          (number "4" (effects (font (size 1.27 1.27))))
        )
        (pin bidirectional line (at 0 -25.4 0) (length 2.54)
          (name "P5" (effects (font (size 1.27 1.27))))
          (number "5" (effects (font (size 1.27 1.27))))
        )
        (pin bidirectional line (at 0 -7.62 0) (length 2.54)
          (name "P6" (effects (font (size 1.27 1.27))))
          (number "6" (effects (font (size 1.27 1.27))))
        )
        (pin bidirectional line (at 0 -10.16 0) (length 2.54)
          (name "P7" (effects (font (size 1.27 1.27))))
          (number "7" (effects (font (size 1.27 1.27))))
        )
        (pin bidirectional line (at 0 -12.7 0) (length 2.54)
          (name "P8" (effects (font (size 1.27 1.27))))
          (number "8" (effects (font (size 1.27 1.27))))
        )
        (pin bidirectional line (at 0 -15.24 0) (length 2.54)
          (name "P9" (effects (font (size 1.27 1.27))))
          (number "9" (effects (font (size 1.27 1.27))))
        )
      )
    )
	(symbol "antmicroOptoisolatorsLogicOutput:ACPL-217-500E" (in_bom yes) (on_board yes)
      (property "Reference" "U" (at 27.94 -5.08 0)
        (effects (font (size 1.27 1.27) (thickness 0.15)) (justify left bottom))
      )
      (property "Value" "ACPL-217-500E" (at 27.94 -7.62 0)
        (effects (font (size 1.27 1.27) (thickness 0.15)) (justify left bottom))
      )
      (property "Footprint" "antmicro-footprints:SOIC-4_4.55x2.6mm_P1.27mm" (at 27.94 -10.16 0)
        (effects (font (size 1.27 1.27) (thickness 0.15)) (justify left bottom) hide)
      )
      (property "Datasheet" "https://docs.broadcom.com/doc/AV02-0470EN" (at 27.94 -12.7 0)
        (effects (font (size 1.27 1.27) (thickness 0.15)) (justify left bottom) hide)
      )
      (property "Description" "Broadcom ACPL-217-500E DC Input Transistor Output Optocoupler, Surface Mount, 4-Pin SO" (at 27.94 -15.24 0)
        (effects (font (size 1.27 1.27) (thickness 0.15)) (justify left bottom) hide)
      )
      (property "Manufacturer" "Broadcom" (at 27.94 -17.78 0)
        (effects (font (size 1.27 1.27) (thickness 0.15)) (justify left bottom) hide)
      )
      (property "MPN" "ACPL-217-500E" (at 27.94 -20.32 0)
        (effects (font (size 1.27 1.27) (thickness 0.15)) (justify left bottom) hide)
      )
      (property "Author" "Antmicro" (at 27.94 -22.86 0)
        (effects (font (size 1.27 1.27) (thickness 0.15)) (justify left bottom) hide)
      )
      (property "License" "Apache-2.0" (at 27.94 -25.4 0)
        (effects (font (size 1.27 1.27) (thickness 0.15)) (justify left bottom) hide)
      )
      (property "ki_description" "Broadcom ACPL-217-500E DC Input Transistor Output Optocoupler, Surface Mount, 4-Pin SO" (at 0 0 0)
        (effects (font (size 1.27 1.27)) hide)
      )
      (symbol "ACPL-217-500E_1_1"
        (polyline
          (pts
            (xy 3.175 -2.413)
            (xy 4.445 -2.413)
          )
          (stroke (width 0.254) (type default))
          (fill (type background))
        )
        (polyline
          (pts
            (xy 5.207 -2.413)
            (xy 7.239 -2.413)
          )
          (stroke (width 0.254) (type default))
          (fill (type background))
        )
        (polyline
          (pts
            (xy 5.207 -1.397)
            (xy 7.239 -1.397)
          )
          (stroke (width 0.254) (type default))
          (fill (type background))
        )
        (polyline
          (pts
            (xy 7.747 -0.889)
            (xy 7.747 -2.921)
          )
          (stroke (width 0.254) (type default))
          (fill (type background))
        )
        (polyline
          (pts
            (xy 9.017 -3.683)
            (xy 7.747 -2.413)
          )
          (stroke (width 0.254) (type default))
          (fill (type background))
        )
        (polyline
          (pts
            (xy 9.017 -0.127)
            (xy 7.747 -1.397)
          )
          (stroke (width 0.254) (type default))
          (fill (type background))
        )
        (polyline
          (pts
            (xy 9.144 -3.81)
            (xy 8.89 -3.556)
          )
          (stroke (width 0.254) (type default))
          (fill (type background))
        )
        (polyline
          (pts
            (xy 9.144 -3.81)
            (xy 8.89 -3.556)
          )
          (stroke (width 0.254) (type default))
          (fill (type background))
        )
        (polyline
          (pts
            (xy 9.144 0)
            (xy 7.874 -1.27)
          )
          (stroke (width 0.254) (type default))
          (fill (type background))
        )
        (polyline
          (pts
            (xy 10.414 -3.81)
            (xy 9.144 -3.81)
          )
          (stroke (width 0.254) (type default))
          (fill (type background))
        )
        (polyline
          (pts
            (xy 10.414 0)
            (xy 9.144 0)
          )
          (stroke (width 0.254) (type default))
          (fill (type background))
        )
        (polyline
          (pts
            (xy 2.54 -3.81)
            (xy 3.81 -3.81)
            (xy 3.81 -2.54)
          )
          (stroke (width 0.254) (type default))
          (fill (type background))
        )
        (polyline
          (pts
            (xy 2.54 0)
            (xy 3.81 0)
            (xy 3.81 -1.27)
          )
          (stroke (width 0.254) (type default))
          (fill (type background))
        )
        (polyline
          (pts
            (xy 3.175 -1.27)
            (xy 4.445 -1.27)
            (xy 3.81 -2.413)
            (xy 3.175 -1.27)
          )
          (stroke (width 0.254) (type default))
          (fill (type background))
        )
        (polyline
          (pts
            (xy 6.477 -2.159)
            (xy 6.477 -2.159)
            (xy 6.477 -2.667)
            (xy 7.239 -2.413)
            (xy 6.477 -2.159)
            (xy 6.477 -2.159)
          )
          (stroke (width 0.254) (type default))
          (fill (type background))
        )
        (polyline
          (pts
            (xy 6.477 -1.143)
            (xy 6.477 -1.143)
            (xy 6.477 -1.651)
            (xy 7.239 -1.397)
            (xy 6.477 -1.143)
            (xy 6.477 -1.143)
          )
          (stroke (width 0.254) (type default))
          (fill (type background))
        )
        (polyline
          (pts
            (xy 9.017 -3.683)
            (xy 9.017 -3.683)
            (xy 8.89 -3.048)
            (xy 8.382 -3.556)
            (xy 9.017 -3.683)
            (xy 9.017 -3.683)
          )
          (stroke (width 0.254) (type default))
          (fill (type background))
        )
        (rectangle (start 2.54 0.635) (end 2.54 0.635)
          (stroke (width 0.254) (type default))
          (fill (type background))
        )
        (rectangle (start 2.54 1.27) (end 10.414 -5.08)
          (stroke (width 0.254) (type default))
          (fill (type background))
        )
        (pin passive line (at 0 0 0) (length 2.54)
          (name "~" (effects (font (size 1.27 1.27))))
          (number "1" (effects (font (size 1.27 1.27))))
        )
        (pin passive line (at 0 -3.81 0) (length 2.54)
          (name "~" (effects (font (size 1.27 1.27))))
          (number "2" (effects (font (size 1.27 1.27))))
        )
        (pin passive line (at 12.7 -3.81 180) (length 2.54)
          (name "~" (effects (font (size 1.27 1.27))))
          (number "3" (effects (font (size 1.27 1.27))))
        )
        (pin passive line (at 12.7 0 180) (length 2.54)
          (name "~" (effects (font (size 1.27 1.27))))
          (number "4" (effects (font (size 1.27 1.27))))
        )
      )
    )
	(symbol "antmicroPMICPowerDistributionSwitchesLoadDrivers:TPS2372-3RGWR" (in_bom yes) (on_board yes)
      (property "Reference" "U" (at 35.56 0 0)
        (effects (font (size 1.27 1.27) (thickness 0.15)) (justify left bottom))
      )
      (property "Value" "TPS2372-3RGWR" (at 35.56 -2.54 0)
        (effects (font (size 1.27 1.27) (thickness 0.15)) (justify left bottom))
      )
      (property "Footprint" "antmicro-footprints:VQFN-20_5x5x1mm_P0.65mm" (at 35.56 -5.08 0)
        (effects (font (size 1.27 1.27) (thickness 0.15)) (justify left bottom) hide)
      )
      (property "Datasheet" "https://www.ti.com/lit/ds/symlink/tps2372.pdf?ts=1679042478513&ref_url=https%253A%252F%252Fwww.google.com%252F" (at 35.56 -7.62 0)
        (effects (font (size 1.27 1.27) (thickness 0.15)) (justify left bottom) hide)
      )
      (property "MPN" "TPS2372-3RGWR" (at 35.56 -10.16 0)
        (effects (font (size 1.27 1.27) (thickness 0.15)) (justify left bottom) hide)
      )
      (property "Manufacturer" "Texas Instruments" (at 35.56 -12.7 0)
        (effects (font (size 1.27 1.27) (thickness 0.15)) (justify left bottom) hide)
      )
      (property "Author" "Antmicro" (at 35.56 -15.24 0)
        (effects (font (size 1.27 1.27) (thickness 0.15)) (justify left bottom) hide)
      )
      (property "License" "Apache-2.0" (at 35.56 -17.78 0)
        (effects (font (size 1.27 1.27) (thickness 0.15)) (justify left bottom) hide)
      )
      (property "ki_keywords" "IEEE 802.3bt PoE high-power PD interface with automatic MPS & autoclass" (at 0 0 0)
        (effects (font (size 1.27 1.27)) hide)
      )
      (property "ki_description" "IEEE 802.3bt PoE high-power PD interface with automatic MPS & autoclass" (at 0 0 0)
        (effects (font (size 1.27 1.27)) hide)
      )
      (symbol "TPS2372-3RGWR_1_1"
        (rectangle (start 2.54 2.54) (end 19.05 -35.56)
          (stroke (width 0.254) (type default))
          (fill (type background))
        )
        (pin power_in line (at 0 0 0) (length 2.54)
          (name "VDD" (effects (font (size 1.27 1.27))))
          (number "1" (effects (font (size 1.27 1.27))))
        )
        (pin input line (at 0 -33.02 0) (length 2.54)
          (name "~{AUTCLS}" (effects (font (size 1.27 1.27))))
          (number "10" (effects (font (size 1.27 1.27))))
        )
        (pin output line (at 21.59 -30.48 180) (length 2.54)
          (name "RTNA" (effects (font (size 1.27 1.27))))
          (number "11" (effects (font (size 1.27 1.27))))
        )
        (pin output line (at 21.59 -33.02 180) (length 2.54)
          (name "RTNB" (effects (font (size 1.27 1.27))))
          (number "12" (effects (font (size 1.27 1.27))))
        )
        (pin output line (at 21.59 -20.32 180) (length 2.54)
          (name "PG" (effects (font (size 1.27 1.27))))
          (number "13" (effects (font (size 1.27 1.27))))
        )
        (pin no_connect line (at 19.05 -15.24 180) (length 2.54) hide
          (name "NC" (effects (font (size 1.27 1.27))))
          (number "14" (effects (font (size 1.27 1.27))))
        )
        (pin no_connect line (at 19.05 -12.7 180) (length 2.54) hide
          (name "NC" (effects (font (size 1.27 1.27))))
          (number "15" (effects (font (size 1.27 1.27))))
        )
        (pin output line (at 21.59 -25.4 180) (length 2.54)
          (name "IRSHDL_EN" (effects (font (size 1.27 1.27))))
          (number "16" (effects (font (size 1.27 1.27))))
        )
        (pin output line (at 21.59 -2.54 180) (length 2.54)
          (name "TPL" (effects (font (size 1.27 1.27))))
          (number "17" (effects (font (size 1.27 1.27))))
        )
        (pin output line (at 21.59 0 180) (length 2.54)
          (name "TPH" (effects (font (size 1.27 1.27))))
          (number "18" (effects (font (size 1.27 1.27))))
        )
        (pin output line (at 21.59 -5.08 180) (length 2.54)
          (name "~{BT}" (effects (font (size 1.27 1.27))))
          (number "19" (effects (font (size 1.27 1.27))))
        )
        (pin input line (at 0 -2.54 0) (length 2.54)
          (name "DEN" (effects (font (size 1.27 1.27))))
          (number "2" (effects (font (size 1.27 1.27))))
        )
        (pin no_connect line (at 19.05 -10.16 180) (length 2.54) hide
          (name "NC" (effects (font (size 1.27 1.27))))
          (number "20" (effects (font (size 1.27 1.27))))
        )
        (pin power_in line (at 0 -20.32 0) (length 2.54)
          (name "PAD_VSSC" (effects (font (size 1.27 1.27))))
          (number "21" (effects (font (size 1.27 1.27))))
        )
        (pin input line (at 0 -7.62 0) (length 2.54)
          (name "CLSA" (effects (font (size 1.27 1.27))))
          (number "3" (effects (font (size 1.27 1.27))))
        )
        (pin power_in line (at 0 -15.24 0) (length 2.54)
          (name "VSSA" (effects (font (size 1.27 1.27))))
          (number "4" (effects (font (size 1.27 1.27))))
        )
        (pin power_in line (at 0 -17.78 0) (length 2.54)
          (name "VSSB" (effects (font (size 1.27 1.27))))
          (number "5" (effects (font (size 1.27 1.27))))
        )
        (pin input line (at 0 -10.16 0) (length 2.54)
          (name "CLSB" (effects (font (size 1.27 1.27))))
          (number "6" (effects (font (size 1.27 1.27))))
        )
        (pin input line (at 0 -25.4 0) (length 2.54)
          (name "REF" (effects (font (size 1.27 1.27))))
          (number "7" (effects (font (size 1.27 1.27))))
        )
        (pin input line (at 0 -22.86 0) (length 2.54)
          (name "AMPS_CTL" (effects (font (size 1.27 1.27))))
          (number "8" (effects (font (size 1.27 1.27))))
        )
        (pin input line (at 0 -27.94 0) (length 2.54)
          (name "MPS_DUTY" (effects (font (size 1.27 1.27))))
          (number "9" (effects (font (size 1.27 1.27))))
        )
      )
    )
	(symbol "antmicroPMICPowerSequencers:MAX16150A_SOT" (in_bom yes) (on_board yes)
      (property "Reference" "U" (at 31.75 -3.81 0)
        (effects (font (size 1.27 1.27) (thickness 0.15)) (justify left bottom))
      )
      (property "Value" "MAX16150A_SOT" (at 31.75 -6.35 0)
        (effects (font (size 1.27 1.27) (thickness 0.15)) (justify left bottom))
      )
      (property "Footprint" "antmicro-footprints:SOT-23-6" (at 31.75 -8.89 0)
        (effects (font (size 1.27 1.27) (thickness 0.15)) (justify left bottom) hide)
      )
      (property "Datasheet" "https://datasheets.maximintegrated.com/en/ds/MAX16150.pdf" (at 31.75 -11.43 0)
        (effects (font (size 1.27 1.27) (thickness 0.15)) (justify left bottom) hide)
      )
      (property "Manufacturer" "Maxim Integrated" (at 31.75 -13.97 0)
        (effects (font (size 1.27 1.27) (thickness 0.15)) (justify left bottom) hide)
      )
      (property "MPN" "MAX16150AUT+T" (at 31.75 -16.51 0)
        (effects (font (size 1.27 1.27) (thickness 0.15)) (justify left bottom) hide)
      )
      (property "License" "Apache-2.0" (at 31.75 -19.05 0)
        (effects (font (size 1.27 1.27) (thickness 0.15)) (justify left bottom) hide)
      )
      (property "Author" "Antmicro" (at 31.75 -21.59 0)
        (effects (font (size 1.27 1.27) (thickness 0.15)) (justify left bottom) hide)
      )
      (property "ki_description" "nanoPower Pushbutton On/Off Controller and Battery Freshness Seal" (at 0 0 0)
        (effects (font (size 1.27 1.27)) hide)
      )
      (symbol "MAX16150A_SOT_0_0"
        (text "CTRL" (at 8.89 -0.254 0)
          (effects (font (size 0.635 0.635)))
        )
      )
      (symbol "MAX16150A_SOT_1_1"
        (polyline
          (pts
            (xy 6.35 -3.429)
            (xy 7.112 -3.429)
          )
          (stroke (width 0.254) (type default))
          (fill (type background))
        )
        (polyline
          (pts
            (xy 7.112 -2.54)
            (xy 10.668 -2.54)
          )
          (stroke (width 0.254) (type default))
          (fill (type background))
        )
        (polyline
          (pts
            (xy 7.874 -1.016)
            (xy 9.906 -1.016)
          )
          (stroke (width 0.254) (type default))
          (fill (type background))
        )
        (polyline
          (pts
            (xy 8.89 -2.54)
            (xy 8.89 -1.016)
          )
          (stroke (width 0.254) (type default))
          (fill (type background))
        )
        (polyline
          (pts
            (xy 11.43 -3.429)
            (xy 10.668 -3.429)
          )
          (stroke (width 0.254) (type default))
          (fill (type background))
        )
        (rectangle (start 2.54 2.54) (end 15.24 -7.62)
          (stroke (width 0.254) (type default))
          (fill (type background))
        )
        (circle (center 7.366 -3.429) (radius 0.254)
          (stroke (width 0.254) (type default))
          (fill (type outline))
        )
        (circle (center 10.414 -3.429) (radius 0.254)
          (stroke (width 0.254) (type default))
          (fill (type outline))
        )
        (pin input line (at 0 -5.08 0) (length 2.54)
          (name "~{PB_IN}" (effects (font (size 1.27 1.27))))
          (number "1" (effects (font (size 1.27 1.27))))
        )
        (pin power_in line (at 17.78 -5.08 180) (length 2.54)
          (name "GND" (effects (font (size 1.27 1.27))))
          (number "2" (effects (font (size 1.27 1.27))))
        )
        (pin power_in line (at 0 0 0) (length 2.54)
          (name "VCC" (effects (font (size 1.27 1.27))))
          (number "3" (effects (font (size 1.27 1.27))))
        )
        (pin output line (at 17.78 0 180) (length 2.54)
          (name "OUT" (effects (font (size 1.27 1.27))))
          (number "4" (effects (font (size 1.27 1.27))))
        )
        (pin output line (at 17.78 -2.54 180) (length 2.54)
          (name "~{INT}" (effects (font (size 1.27 1.27))))
          (number "5" (effects (font (size 1.27 1.27))))
        )
        (pin input line (at 0 -2.54 0) (length 2.54)
          (name "~{CLR}" (effects (font (size 1.27 1.27))))
          (number "6" (effects (font (size 1.27 1.27))))
        )
      )
    )
	(symbol "antmicroPMICPowerSequencers:MAX812REUS+T" (in_bom yes) (on_board yes)
      (property "Reference" "U" (at 30.48 -2.54 0)
        (effects (font (size 1.27 1.27) (thickness 0.15)) (justify left bottom))
      )
      (property "Value" "MAX812REUS+T" (at 30.48 -5.08 0)
        (effects (font (size 1.27 1.27) (thickness 0.15)) (justify left bottom))
      )
      (property "Footprint" "antmicro-footprints:SOT-143-4" (at 30.48 -7.62 0)
        (effects (font (size 1.27 1.27) (thickness 0.15)) (justify left bottom) hide)
      )
      (property "Datasheet" "https://datasheets.maximintegrated.com/en/ds/MAX811-MAX812T.pdf" (at 30.48 -10.16 0)
        (effects (font (size 1.27 1.27) (thickness 0.15)) (justify left bottom) hide)
      )
      (property "Manufacturer" "Maxim Integrated" (at 30.48 -12.7 0)
        (effects (font (size 1.27 1.27) (thickness 0.15)) (justify left bottom) hide)
      )
      (property "MPN" "MAX812REUS+T" (at 30.48 -15.24 0)
        (effects (font (size 1.27 1.27) (thickness 0.15)) (justify left bottom) hide)
      )
      (property "License" "Apache-2.0" (at 30.48 -17.78 0)
        (effects (font (size 1.27 1.27) (thickness 0.15)) (justify left bottom) hide)
      )
      (property "Author" "Antmicro" (at 30.48 -20.32 0)
        (effects (font (size 1.27 1.27) (thickness 0.15)) (justify left bottom) hide)
      )
      (property "ki_description" "Supervisory Circuits 4-Pin uP Voltage Monitors with Manual Reset Input" (at 0 0 0)
        (effects (font (size 1.27 1.27)) hide)
      )
      (symbol "MAX812REUS+T_1_1"
        (rectangle (start 2.54 2.54) (end 12.7 -7.62)
          (stroke (width 0.254) (type default))
          (fill (type background))
        )
        (pin power_in line (at 0 -5.08 0) (length 2.54)
          (name "GND" (effects (font (size 1.27 1.27))))
          (number "1" (effects (font (size 1.27 1.27))))
        )
        (pin output line (at 15.24 -2.54 180) (length 2.54)
          (name "~{RST}" (effects (font (size 1.27 1.27))))
          (number "2" (effects (font (size 1.27 1.27))))
        )
        (pin input line (at 0 -2.54 0) (length 2.54)
          (name "~{MR}" (effects (font (size 1.27 1.27))))
          (number "3" (effects (font (size 1.27 1.27))))
        )
        (pin power_in line (at 0 0 0) (length 2.54)
          (name "VCC" (effects (font (size 1.27 1.27))))
          (number "4" (effects (font (size 1.27 1.27))))
        )
      )
    )
	(symbol "antmicroPMICVoltageRegulatorsDCDCSwitchingControllers:TPS65295RJE" (in_bom yes) (on_board yes)
      (property "Reference" "U" (at 41.91 -3.81 0)
        (effects (font (size 1.27 1.27) (thickness 0.15)) (justify left bottom))
      )
      (property "Value" "TPS65295RJE" (at 41.91 -6.35 0)
        (effects (font (size 1.27 1.27) (thickness 0.15)) (justify left bottom))
      )
      (property "Footprint" "antmicro-footprints:TPS65295RJET" (at 41.91 -8.89 0)
        (effects (font (size 1.27 1.27) (thickness 0.15)) (justify left bottom) hide)
      )
      (property "Datasheet" "https://www.ti.com/lit/ds/symlink/tps65295.pdf?ts=1678974348145&ref_url=https%253A%252F%252Fwww.ti.com%252Fproduct%252FTPS65295%252Fpart-details%252FTPS65295RJET%253Futm_source%253Dgoogle%2526utm_medium%253Dcpc%2526utm_campaign%253Docb-tistore-promo-app_opn_en-cpc-storeic-google-wwe%2526utm_content%253DDevice%2526ds_k%253DTPS65295RJET%2526DCM%253Dyes%2526gclid%253DCjwKCAjw_MqgBhAGEiwAnYOAenqZlHFYNIv8bo8LzLCLfbwSVYe5HxpiyTTTkdL5wSHfzakFHjgpQRoCDzsQAvD_BwE%2526gclsrc%253Daw.ds" (at 41.91 -11.43 0)
        (effects (font (size 1.27 1.27) (thickness 0.15)) (justify left bottom) hide)
      )
      (property "MPN" "TPS65295RJET" (at 41.91 -13.97 0)
        (effects (font (size 1.27 1.27) (thickness 0.15)) (justify left bottom) hide)
      )
      (property "Manufacturer" "Texas Instruments" (at 41.91 -16.51 0)
        (effects (font (size 1.27 1.27) (thickness 0.15)) (justify left bottom) hide)
      )
      (property "Author" "Antmicro" (at 41.91 -19.05 0)
        (effects (font (size 1.27 1.27) (thickness 0.15)) (justify left bottom) hide)
      )
      (property "License" "Apache-2.0" (at 41.91 -21.59 0)
        (effects (font (size 1.27 1.27) (thickness 0.15)) (justify left bottom) hide)
      )
      (property "ki_fp_filters" "VQFN-HR18_RJE_TEX" (at 0 0 0)
        (effects (font (size 1.27 1.27)) hide)
      )
      (symbol "TPS65295RJE_1_1"
        (rectangle (start 2.54 2.54) (end 21.59 -45.72)
          (stroke (width 0.254) (type default))
          (fill (type background))
        )
        (pin power_in line (at 0 -20.32 0) (length 2.54)
          (name "VLDOIN" (effects (font (size 1.27 1.27))))
          (number "1" (effects (font (size 1.27 1.27))))
        )
        (pin input line (at 0 -36.83 0) (length 2.54)
          (name "VTT_CNTL" (effects (font (size 1.27 1.27))))
          (number "10" (effects (font (size 1.27 1.27))))
        )
        (pin input line (at 0 -34.29 0) (length 2.54)
          (name "SLP_S4" (effects (font (size 1.27 1.27))))
          (number "11" (effects (font (size 1.27 1.27))))
        )
        (pin input line (at 24.13 -2.54 180) (length 2.54)
          (name "VPPSNS" (effects (font (size 1.27 1.27))))
          (number "12" (effects (font (size 1.27 1.27))))
        )
        (pin power_in line (at 0 -8.89 0) (length 2.54)
          (name "VCC_5V" (effects (font (size 1.27 1.27))))
          (number "13" (effects (font (size 1.27 1.27))))
        )
        (pin power_in line (at 0 -11.43 0) (length 2.54)
          (name "PVIN_VPP" (effects (font (size 1.27 1.27))))
          (number "14" (effects (font (size 1.27 1.27))))
        )
        (pin input line (at 24.13 0 180) (length 2.54)
          (name "SW_VPP" (effects (font (size 1.27 1.27))))
          (number "15" (effects (font (size 1.27 1.27))))
        )
        (pin passive line (at 24.13 -43.18 180) (length 2.54) hide
          (name "PGND" (effects (font (size 1.27 1.27))))
          (number "16" (effects (font (size 1.27 1.27))))
        )
        (pin input line (at 24.13 -15.24 180) (length 2.54)
          (name "SW" (effects (font (size 1.27 1.27))))
          (number "17" (effects (font (size 1.27 1.27))))
        )
        (pin input line (at 24.13 -10.16 180) (length 2.54)
          (name "BST" (effects (font (size 1.27 1.27))))
          (number "18" (effects (font (size 1.27 1.27))))
        )
        (pin input line (at 24.13 -25.4 180) (length 2.54)
          (name "VTT" (effects (font (size 1.27 1.27))))
          (number "2" (effects (font (size 1.27 1.27))))
        )
        (pin power_in line (at 0 -43.18 0) (length 2.54)
          (name "AGND" (effects (font (size 1.27 1.27))))
          (number "3" (effects (font (size 1.27 1.27))))
        )
        (pin input line (at 24.13 -27.94 180) (length 2.54)
          (name "VTTSNS" (effects (font (size 1.27 1.27))))
          (number "4" (effects (font (size 1.27 1.27))))
        )
        (pin input line (at 24.13 -17.78 180) (length 2.54)
          (name "VDDQSNS" (effects (font (size 1.27 1.27))))
          (number "5" (effects (font (size 1.27 1.27))))
        )
        (pin input line (at 24.13 -35.56 180) (length 2.54)
          (name "VTTREF" (effects (font (size 1.27 1.27))))
          (number "6" (effects (font (size 1.27 1.27))))
        )
        (pin power_in line (at 0 0 0) (length 2.54)
          (name "PVIN" (effects (font (size 1.27 1.27))))
          (number "7" (effects (font (size 1.27 1.27))))
        )
        (pin output line (at 0 -31.75 0) (length 2.54)
          (name "PGOOD" (effects (font (size 1.27 1.27))))
          (number "8" (effects (font (size 1.27 1.27))))
        )
        (pin power_in line (at 24.13 -43.18 180) (length 2.54)
          (name "PGND" (effects (font (size 1.27 1.27))))
          (number "9" (effects (font (size 1.27 1.27))))
        )
      )
    )
	(symbol "antmicroPMICVoltageRegulatorsLinear:NCP718ASN500_SOT" (in_bom yes) (on_board yes)
      (property "Reference" "U" (at 30.48 -2.54 0)
        (effects (font (size 1.27 1.27) (thickness 0.15)) (justify left bottom))
      )
      (property "Value" "NCP718ASN500_SOT" (at 30.48 -5.08 0)
        (effects (font (size 1.27 1.27) (thickness 0.15)) (justify left bottom))
      )
      (property "Footprint" "antmicro-footprints:SOT-23-5" (at 30.48 -7.62 0)
        (effects (font (size 1.27 1.27) (thickness 0.15)) (justify left bottom) hide)
      )
      (property "Datasheet" "https://www.mouser.pl/datasheet/2/308/NCP718_D-1224359.pdf" (at 30.48 -10.16 0)
        (effects (font (size 1.27 1.27) (thickness 0.15)) (justify left bottom) hide)
      )
      (property "MPN" "NCP718ASN500T1G" (at 30.48 -12.7 0)
        (effects (font (size 1.27 1.27) (thickness 0.15)) (justify left bottom) hide)
      )
      (property "Manufacturer" "ON Semiconductor" (at 30.48 -15.24 0)
        (effects (font (size 1.27 1.27) (thickness 0.15)) (justify left bottom) hide)
      )
      (property "Author" "Antmicro" (at 30.48 -17.78 0)
        (effects (font (size 1.27 1.27) (thickness 0.15)) (justify left bottom) hide)
      )
      (property "License" "Apache-2.0" (at 30.48 -20.32 0)
        (effects (font (size 1.27 1.27) (thickness 0.15)) (justify left bottom) hide)
      )
      (property "ki_description" "LDO Voltage Regulators 300 MA LOW IQ WIDE INPUT 5.0V" (at 0 0 0)
        (effects (font (size 1.27 1.27)) hide)
      )
      (symbol "NCP718ASN500_SOT_1_1"
        (rectangle (start 2.54 2.54) (end 12.7 -7.62)
          (stroke (width 0.254) (type default))
          (fill (type background))
        )
        (pin power_in line (at 0 0 0) (length 2.54)
          (name "V_{IN}" (effects (font (size 1.27 1.27))))
          (number "1" (effects (font (size 1.27 1.27))))
        )
        (pin power_in line (at 15.24 -5.08 180) (length 2.54)
          (name "GND" (effects (font (size 1.27 1.27))))
          (number "2" (effects (font (size 1.27 1.27))))
        )
        (pin input line (at 0 -2.54 0) (length 2.54)
          (name "EN" (effects (font (size 1.27 1.27))))
          (number "3" (effects (font (size 1.27 1.27))))
        )
        (pin no_connect line (at 12.7 -2.54 180) (length 2.54) hide
          (name "NC" (effects (font (size 1.27 1.27))))
          (number "4" (effects (font (size 1.27 1.27))))
        )
        (pin power_out line (at 15.24 0 180) (length 2.54)
          (name "V_{OUT}" (effects (font (size 1.27 1.27))))
          (number "5" (effects (font (size 1.27 1.27))))
        )
      )
    )
	(symbol "antmicroPMICVoltageRegulatorsLinear:TPS54561QDPRRQ1" (in_bom yes) (on_board yes)
      (property "Reference" "U" (at 38.1 -2.54 0)
        (effects (font (size 1.27 1.27) (thickness 0.15)) (justify left bottom))
      )
      (property "Value" "TPS54561QDPRRQ1" (at 38.1 -5.08 0)
        (effects (font (size 1.27 1.27) (thickness 0.15)) (justify left bottom))
      )
      (property "Footprint" "antmicro-footprints:WSON-10-1EP_4x4mm_P0.8mm_EP2.6x3mm" (at 38.1 -7.62 0)
        (effects (font (size 1.27 1.27) (thickness 0.15)) (justify left bottom) hide)
      )
      (property "Datasheet" "https://www.ti.com/lit/ds/symlink/tps54561-q1.pdf?ts=1678720110394&ref_url=https%253A%252F%252Fwww.google.com%252F" (at 38.1 -10.16 0)
        (effects (font (size 1.27 1.27) (thickness 0.15)) (justify left bottom) hide)
      )
      (property "Manufacturer" "Texas Instruments" (at 38.1 -12.7 0)
        (effects (font (size 1.27 1.27) (thickness 0.15)) (justify left bottom) hide)
      )
      (property "MPN" "TPS54561QDPRRQ1" (at 38.1 -15.24 0)
        (effects (font (size 1.27 1.27) (thickness 0.15)) (justify left bottom) hide)
      )
      (property "Author" "Antmicro" (at 38.1 -17.78 0)
        (effects (font (size 1.27 1.27) (thickness 0.15)) (justify left bottom) hide)
      )
      (property "License" "Apache-2.0" (at 38.1 -20.32 0)
        (effects (font (size 1.27 1.27) (thickness 0.15)) (justify left bottom) hide)
      )
      (property "ki_description" " 4.5-V to 60-V Input, 5-A, Step-Down DC-DC Converter" (at 0 0 0)
        (effects (font (size 1.27 1.27)) hide)
      )
      (symbol "TPS54561QDPRRQ1_1_1"
        (rectangle (start 2.54 2.54) (end 22.86 -21.59)
          (stroke (width 0.254) (type default))
          (fill (type background))
        )
        (pin passive line (at 25.4 -2.54 180) (length 2.54)
          (name "BOOT" (effects (font (size 1.27 1.27))))
          (number "1" (effects (font (size 1.27 1.27))))
        )
        (pin passive line (at 25.4 0 180) (length 2.54)
          (name "PWRGD" (effects (font (size 1.27 1.27))))
          (number "10" (effects (font (size 1.27 1.27))))
        )
        (pin passive line (at 0 -19.05 0) (length 2.54) hide
          (name "GND" (effects (font (size 1.27 1.27))))
          (number "11" (effects (font (size 1.27 1.27))))
        )
        (pin passive line (at 0 0 0) (length 2.54)
          (name "VDD" (effects (font (size 1.27 1.27))))
          (number "2" (effects (font (size 1.27 1.27))))
        )
        (pin passive line (at 0 -2.54 0) (length 2.54)
          (name "EN" (effects (font (size 1.27 1.27))))
          (number "3" (effects (font (size 1.27 1.27))))
        )
        (pin passive line (at 0 -10.16 0) (length 2.54)
          (name "SS/TR" (effects (font (size 1.27 1.27))))
          (number "4" (effects (font (size 1.27 1.27))))
        )
        (pin passive line (at 0 -7.62 0) (length 2.54)
          (name "RT/CLK" (effects (font (size 1.27 1.27))))
          (number "5" (effects (font (size 1.27 1.27))))
        )
        (pin passive line (at 25.4 -13.97 180) (length 2.54)
          (name "FB" (effects (font (size 1.27 1.27))))
          (number "6" (effects (font (size 1.27 1.27))))
        )
        (pin passive line (at 25.4 -19.05 180) (length 2.54)
          (name "COMP" (effects (font (size 1.27 1.27))))
          (number "7" (effects (font (size 1.27 1.27))))
        )
        (pin power_in line (at 0 -19.05 0) (length 2.54)
          (name "GND" (effects (font (size 1.27 1.27))))
          (number "8" (effects (font (size 1.27 1.27))))
        )
        (pin passive line (at 25.4 -7.62 180) (length 2.54)
          (name "SW" (effects (font (size 1.27 1.27))))
          (number "9" (effects (font (size 1.27 1.27))))
        )
      )
    )
	(symbol "antmicroPushbuttonSwitches:SW_1-1825027-1_THT" (pin_names hide) (in_bom yes) (on_board yes)
      (property "Reference" "SW" (at 25.4 -5.08 0)
        (effects (font (size 1.27 1.27) (thickness 0.15)) (justify left bottom))
      )
      (property "Value" "SW_1-1825027-1_THT" (at 25.4 -7.62 0)
        (effects (font (size 1.27 1.27) (thickness 0.15)) (justify left bottom) hide)
      )
      (property "Footprint" "antmicro-footprints:SW_1-1825027-1_THT" (at 25.4 -10.16 0)
        (effects (font (size 1.27 1.27) (thickness 0.15)) (justify left bottom) hide)
      )
      (property "Datasheet" "https://www.te.com/commerce/DocumentDelivery/DDEController?Action=showdoc&DocId=Customer+Drawing%7F1825027%7FH1%7Fpdf%7FEnglish%7FENG_CD_1825027_H1.pdf%7F1-1825027-1" (at 25.4 -12.7 0)
        (effects (font (size 1.27 1.27) (thickness 0.15)) (justify left bottom) hide)
      )
      (property "MPN" "1-1825027-1" (at 25.4 -15.24 0)
        (effects (font (size 1.27 1.27) (thickness 0.15)) (justify left bottom))
      )
      (property "Manufacturer" "TE Connectivity" (at 25.4 -17.78 0)
        (effects (font (size 1.27 1.27) (thickness 0.15)) (justify left bottom) hide)
      )
      (property "Author" "Antmicro" (at 25.4 -20.32 0)
        (effects (font (size 1.27 1.27) (thickness 0.15)) (justify left bottom) hide)
      )
      (property "License" "Apache-2.0" (at 25.4 -22.86 0)
        (effects (font (size 1.27 1.27) (thickness 0.15)) (justify left bottom) hide)
      )
      (property "ki_keywords" "HORIZONTAL, SWITCH, THT, MECHANICAL, TACTILE" (at 0 0 0)
        (effects (font (size 1.27 1.27)) hide)
      )
      (property "ki_description" "Tactile Switch, Side Actuated, Through Hole, Round Button, 160 gf, 50mA at 24VDC" (at 0 0 0)
        (effects (font (size 1.27 1.27)) hide)
      )
      (symbol "SW_1-1825027-1_THT_1_1"
        (polyline
          (pts
            (xy 2.54 0)
            (xy 3.302 0)
          )
          (stroke (width 0.254) (type default))
          (fill (type none))
        )
        (polyline
          (pts
            (xy 3.302 -1.016)
            (xy 6.858 -1.016)
          )
          (stroke (width 0.254) (type default))
          (fill (type none))
        )
        (polyline
          (pts
            (xy 3.302 1.27)
            (xy 6.858 1.27)
          )
          (stroke (width 0.254) (type default))
          (fill (type none))
        )
        (polyline
          (pts
            (xy 4.064 2.794)
            (xy 6.096 2.794)
          )
          (stroke (width 0.254) (type default))
          (fill (type none))
        )
        (polyline
          (pts
            (xy 5.08 1.27)
            (xy 5.08 2.794)
          )
          (stroke (width 0.254) (type default))
          (fill (type none))
        )
        (polyline
          (pts
            (xy 7.62 0)
            (xy 6.858 0)
          )
          (stroke (width 0.254) (type default))
          (fill (type none))
        )
        (polyline
          (pts
            (xy 7.62 -2.54)
            (xy 5.08 -2.54)
            (xy 5.08 -1.016)
          )
          (stroke (width 0.254) (type default))
          (fill (type none))
        )
        (circle (center 3.556 0) (radius 0.254)
          (stroke (width 0.254) (type default))
          (fill (type none))
        )
        (circle (center 6.604 0) (radius 0.254)
          (stroke (width 0.254) (type default))
          (fill (type none))
        )
        (pin passive line (at 0 0 0) (length 2.54)
          (name "1" (effects (font (size 1.27 1.27))))
          (number "1" (effects (font (size 1.27 1.27))))
        )
        (pin passive line (at 10.16 0 180) (length 2.54)
          (name "2" (effects (font (size 1.27 1.27))))
          (number "2" (effects (font (size 1.27 1.27))))
        )
        (pin passive line (at 10.16 -2.54 180) (length 2.54)
          (name "SH" (effects (font (size 1.27 1.27))))
          (number "SH" (effects (font (size 1.27 1.27))))
        )
      )
    )
	(symbol "antmicroPushbuttonSwitches:SW_B3U-1000P_SMD" (pin_names hide) (in_bom yes) (on_board yes)
      (property "Reference" "SW" (at 25.4 -2.54 0)
        (effects (font (size 1.27 1.27) (thickness 0.15)) (justify left bottom))
      )
      (property "Value" "SW_B3U-1000P_SMD" (at 25.4 -5.08 0)
        (effects (font (size 1.27 1.27) (thickness 0.15)) (justify left bottom) hide)
      )
      (property "Footprint" "antmicro-footprints:SW_B3U-1000P_SMD" (at 25.4 -7.62 0)
        (effects (font (size 1.27 1.27) (thickness 0.15)) (justify left bottom) hide)
      )
      (property "Datasheet" "https://omronfs.omron.com/en_US/ecb/products/pdf/en-b3u.pdf" (at 25.4 -10.16 0)
        (effects (font (size 1.27 1.27) (thickness 0.15)) (justify left bottom) hide)
      )
      (property "MPN" "B3U-1000P" (at 25.4 -12.7 0)
        (effects (font (size 1.27 1.27) (thickness 0.15)) (justify left bottom))
      )
      (property "Manufacturer" "Omron" (at 25.4 -15.24 0)
        (effects (font (size 1.27 1.27) (thickness 0.15)) (justify left bottom) hide)
      )
      (property "Author" "Antmicro" (at 25.4 -17.78 0)
        (effects (font (size 1.27 1.27) (thickness 0.15)) (justify left bottom) hide)
      )
      (property "License" "Apache-2.0" (at 25.4 -20.32 0)
        (effects (font (size 1.27 1.27) (thickness 0.15)) (justify left bottom) hide)
      )
      (property "ki_keywords" "VERTICAL, SMT, SWITCH, MECHANICAL, TACTILE" (at 0 0 0)
        (effects (font (size 1.27 1.27)) hide)
      )
      (property "ki_description" "Tactile Switch, B3U, Top Actuated, Surface Mount, Round Button, 153 gf, 50mA at 12VDC" (at 0 0 0)
        (effects (font (size 1.27 1.27)) hide)
      )
      (symbol "SW_B3U-1000P_SMD_1_1"
        (polyline
          (pts
            (xy 2.54 0)
            (xy 3.302 0)
          )
          (stroke (width 0.254) (type default))
          (fill (type none))
        )
        (polyline
          (pts
            (xy 3.302 1.27)
            (xy 6.858 1.27)
          )
          (stroke (width 0.254) (type default))
          (fill (type none))
        )
        (polyline
          (pts
            (xy 4.064 2.794)
            (xy 6.096 2.794)
          )
          (stroke (width 0.254) (type default))
          (fill (type none))
        )
        (polyline
          (pts
            (xy 5.08 1.27)
            (xy 5.08 2.794)
          )
          (stroke (width 0.254) (type default))
          (fill (type none))
        )
        (polyline
          (pts
            (xy 7.62 0)
            (xy 6.858 0)
          )
          (stroke (width 0.254) (type default))
          (fill (type none))
        )
        (circle (center 3.556 0) (radius 0.254)
          (stroke (width 0.254) (type default))
          (fill (type none))
        )
        (circle (center 6.604 0) (radius 0.254)
          (stroke (width 0.254) (type default))
          (fill (type none))
        )
        (pin passive line (at 0 0 0) (length 2.54)
          (name "1" (effects (font (size 1.27 1.27))))
          (number "1" (effects (font (size 1.27 1.27))))
        )
        (pin passive line (at 10.16 0 180) (length 2.54)
          (name "2" (effects (font (size 1.27 1.27))))
          (number "2" (effects (font (size 1.27 1.27))))
        )
      )
    )
	(symbol "antmicroResistors0402:R_0R_0402" (pin_numbers hide) (pin_names hide) (in_bom yes) (on_board yes)
      (property "Reference" "R" (at 20.32 -5.08 0)
        (effects (font (size 1.27 1.27) (thickness 0.15)) (justify left bottom))
      )
      (property "Value" "R_0R_0402" (at 20.32 -12.7 0)
        (effects (font (size 1.27 1.27) (thickness 0.15)) (justify left bottom) hide)
      )
      (property "Footprint" "antmicro-footprints:R_0402_1005Metric" (at 20.32 -15.24 0)
        (effects (font (size 1.27 1.27) (thickness 0.15)) (justify left bottom) hide)
      )
      (property "Datasheet" "https://industrial.panasonic.com/cdbs/www-data/pdf/RDA0000/AOA0000C301.pdf" (at 20.32 -17.78 0)
        (effects (font (size 1.27 1.27) (thickness 0.15)) (justify left bottom) hide)
      )
      (property "MPN" "ERJ2GE0R00X" (at 20.32 -20.32 0)
        (effects (font (size 1.27 1.27) (thickness 0.15)) (justify left bottom) hide)
      )
      (property "Manufacturer" "Panasonic" (at 20.32 -22.86 0)
        (effects (font (size 1.27 1.27) (thickness 0.15)) (justify left bottom) hide)
      )
      (property "License" "Apache-2.0" (at 20.32 -25.4 0)
        (effects (font (size 1.27 1.27) (thickness 0.15)) (justify left bottom) hide)
      )
      (property "Author" "Antmicro" (at 20.32 -27.94 0)
        (effects (font (size 1.27 1.27) (thickness 0.15)) (justify left bottom) hide)
      )
      (property "Val" "0R" (at 20.32 -7.62 0)
        (effects (font (size 1.27 1.27) (thickness 0.15)) (justify left bottom))
      )
      (property "Tolerance" "~" (at 20.32 -10.16 0)
        (effects (font (size 1.27 1.27)) (justify left bottom) hide)
      )
      (property "Current" "1A" (at 20.32 -30.48 0)
        (effects (font (size 1.27 1.27) (thickness 0.15)) (justify left bottom) hide)
      )
      (property "ki_description" "0R resistor in 0402 package with unspecified tolerance" (at 0 0 0)
        (effects (font (size 1.27 1.27)) hide)
      )
      (symbol "R_0R_0402_0_1"
        (rectangle (start 0.635 0.889) (end 4.445 -0.889)
          (stroke (width 0.254) (type default))
          (fill (type none))
        )
      )
      (symbol "R_0R_0402_1_1"
        (pin passive line (at 0 0 0) (length 0.635)
          (name "~" (effects (font (size 1.27 1.27))))
          (number "1" (effects (font (size 1.27 1.27))))
        )
        (pin passive line (at 5.08 0 180) (length 0.635)
          (name "~" (effects (font (size 1.27 1.27))))
          (number "2" (effects (font (size 1.27 1.27))))
        )
      )
    )
	(symbol "antmicroResistors0402:R_100R_0402" (pin_numbers hide) (pin_names hide) (in_bom yes) (on_board yes)
      (property "Reference" "R" (at 20.32 -5.08 0)
        (effects (font (size 1.27 1.27) (thickness 0.15)) (justify left bottom))
      )
      (property "Value" "R_100R_0402" (at 20.32 -12.7 0)
        (effects (font (size 1.27 1.27) (thickness 0.15)) (justify left bottom) hide)
      )
      (property "Footprint" "antmicro-footprints:R_0402_1005Metric" (at 20.32 -15.24 0)
        (effects (font (size 1.27 1.27) (thickness 0.15)) (justify left bottom) hide)
      )
      (property "Datasheet" "https://www.bourns.com/docs/product-datasheets/cr.pdf" (at 20.32 -17.78 0)
        (effects (font (size 1.27 1.27) (thickness 0.15)) (justify left bottom) hide)
      )
      (property "MPN" "CR0402-FX-1000GLF" (at 20.32 -20.32 0)
        (effects (font (size 1.27 1.27) (thickness 0.15)) (justify left bottom) hide)
      )
      (property "Manufacturer" "Bourns" (at 20.32 -22.86 0)
        (effects (font (size 1.27 1.27) (thickness 0.15)) (justify left bottom) hide)
      )
      (property "License" "Apache-2.0" (at 20.32 -25.4 0)
        (effects (font (size 1.27 1.27) (thickness 0.15)) (justify left bottom) hide)
      )
      (property "Author" "Antmicro" (at 20.32 -27.94 0)
        (effects (font (size 1.27 1.27) (thickness 0.15)) (justify left bottom) hide)
      )
      (property "Val" "100R" (at 20.32 -7.62 0)
        (effects (font (size 1.27 1.27) (thickness 0.15)) (justify left bottom))
      )
      (property "Tolerance" "1%" (at 20.32 -10.16 0)
        (effects (font (size 1.27 1.27)) (justify left bottom) hide)
      )
      (property "ki_description" "100R resistor in 0402 package with 1% tolerance" (at 0 0 0)
        (effects (font (size 1.27 1.27)) hide)
      )
      (symbol "R_100R_0402_0_1"
        (rectangle (start 0.635 0.889) (end 4.445 -0.889)
          (stroke (width 0.254) (type default))
          (fill (type none))
        )
      )
      (symbol "R_100R_0402_1_1"
        (pin passive line (at 0 0 0) (length 0.635)
          (name "~" (effects (font (size 1.27 1.27))))
          (number "1" (effects (font (size 1.27 1.27))))
        )
        (pin passive line (at 5.08 0 180) (length 0.635)
          (name "~" (effects (font (size 1.27 1.27))))
          (number "2" (effects (font (size 1.27 1.27))))
        )
      )
    )
	(symbol "antmicroResistors0402:R_100k_0402" (pin_numbers hide) (pin_names hide) (in_bom yes) (on_board yes)
      (property "Reference" "R" (at 20.32 -5.08 0)
        (effects (font (size 1.27 1.27) (thickness 0.15)) (justify left bottom))
      )
      (property "Value" "R_100k_0402" (at 20.32 -12.7 0)
        (effects (font (size 1.27 1.27) (thickness 0.15)) (justify left bottom) hide)
      )
      (property "Footprint" "antmicro-footprints:R_0402_1005Metric" (at 20.32 -15.24 0)
        (effects (font (size 1.27 1.27) (thickness 0.15)) (justify left bottom) hide)
      )
      (property "Datasheet" "https://www.bourns.com/docs/product-datasheets/cr.pdf" (at 20.32 -17.78 0)
        (effects (font (size 1.27 1.27) (thickness 0.15)) (justify left bottom) hide)
      )
      (property "MPN" "CR0402-FX-1003GLF" (at 20.32 -20.32 0)
        (effects (font (size 1.27 1.27) (thickness 0.15)) (justify left bottom) hide)
      )
      (property "Manufacturer" "Bourns" (at 20.32 -22.86 0)
        (effects (font (size 1.27 1.27) (thickness 0.15)) (justify left bottom) hide)
      )
      (property "License" "Apache-2.0" (at 20.32 -25.4 0)
        (effects (font (size 1.27 1.27) (thickness 0.15)) (justify left bottom) hide)
      )
      (property "Author" "Antmicro" (at 20.32 -27.94 0)
        (effects (font (size 1.27 1.27) (thickness 0.15)) (justify left bottom) hide)
      )
      (property "Val" "100k" (at 20.32 -7.62 0)
        (effects (font (size 1.27 1.27) (thickness 0.15)) (justify left bottom))
      )
      (property "Tolerance" "1%" (at 20.32 -10.16 0)
        (effects (font (size 1.27 1.27)) (justify left bottom) hide)
      )
      (property "ki_description" "100k resistor in 0402 package with 1% tolerance" (at 0 0 0)
        (effects (font (size 1.27 1.27)) hide)
      )
      (symbol "R_100k_0402_0_1"
        (rectangle (start 0.635 0.889) (end 4.445 -0.889)
          (stroke (width 0.254) (type default))
          (fill (type none))
        )
      )
      (symbol "R_100k_0402_1_1"
        (pin passive line (at 0 0 0) (length 0.635)
          (name "~" (effects (font (size 1.27 1.27))))
          (number "1" (effects (font (size 1.27 1.27))))
        )
        (pin passive line (at 5.08 0 180) (length 0.635)
          (name "~" (effects (font (size 1.27 1.27))))
          (number "2" (effects (font (size 1.27 1.27))))
        )
      )
    )
	(symbol "antmicroResistors0402:R_10k2_0402" (pin_numbers hide) (pin_names hide) (in_bom yes) (on_board yes)
      (property "Reference" "R" (at 20.32 -5.08 0)
        (effects (font (size 1.27 1.27) (thickness 0.15)) (justify left bottom))
      )
      (property "Value" "R_10k2_0402" (at 20.32 -12.7 0)
        (effects (font (size 1.27 1.27) (thickness 0.15)) (justify left bottom) hide)
      )
      (property "Footprint" "antmicro-footprints:R_0402_1005Metric" (at 20.32 -15.24 0)
        (effects (font (size 1.27 1.27) (thickness 0.15)) (justify left bottom) hide)
      )
      (property "Datasheet" "https://www.bourns.com/docs/product-datasheets/cr.pdf" (at 20.32 -17.78 0)
        (effects (font (size 1.27 1.27) (thickness 0.15)) (justify left bottom) hide)
      )
      (property "MPN" "CR0402-FX-1022GLF" (at 20.32 -20.32 0)
        (effects (font (size 1.27 1.27) (thickness 0.15)) (justify left bottom) hide)
      )
      (property "Manufacturer" "Bourns" (at 20.32 -22.86 0)
        (effects (font (size 1.27 1.27) (thickness 0.15)) (justify left bottom) hide)
      )
      (property "License" "Apache-2.0" (at 20.32 -25.4 0)
        (effects (font (size 1.27 1.27) (thickness 0.15)) (justify left bottom) hide)
      )
      (property "Author" "Antmicro" (at 20.32 -27.94 0)
        (effects (font (size 1.27 1.27) (thickness 0.15)) (justify left bottom) hide)
      )
      (property "Val" "10k2" (at 20.32 -7.62 0)
        (effects (font (size 1.27 1.27) (thickness 0.15)) (justify left bottom))
      )
      (property "Tolerance" "1%" (at 20.32 -10.16 0)
        (effects (font (size 1.27 1.27)) (justify left bottom) hide)
      )
      (property "ki_description" "10k2 resistor in 0402 package with 1% tolerance" (at 0 0 0)
        (effects (font (size 1.27 1.27)) hide)
      )
      (symbol "R_10k2_0402_0_1"
        (rectangle (start 0.635 0.889) (end 4.445 -0.889)
          (stroke (width 0.254) (type default))
          (fill (type none))
        )
      )
      (symbol "R_10k2_0402_1_1"
        (pin passive line (at 0 0 0) (length 0.635)
          (name "~" (effects (font (size 1.27 1.27))))
          (number "1" (effects (font (size 1.27 1.27))))
        )
        (pin passive line (at 5.08 0 180) (length 0.635)
          (name "~" (effects (font (size 1.27 1.27))))
          (number "2" (effects (font (size 1.27 1.27))))
        )
      )
    )
	(symbol "antmicroResistors0402:R_10k_0402" (pin_numbers hide) (pin_names hide) (in_bom yes) (on_board yes)
      (property "Reference" "R" (at 20.32 -5.08 0)
        (effects (font (size 1.27 1.27) (thickness 0.15)) (justify left bottom))
      )
      (property "Value" "R_10k_0402" (at 20.32 -12.7 0)
        (effects (font (size 1.27 1.27) (thickness 0.15)) (justify left bottom) hide)
      )
      (property "Footprint" "antmicro-footprints:R_0402_1005Metric" (at 20.32 -15.24 0)
        (effects (font (size 1.27 1.27) (thickness 0.15)) (justify left bottom) hide)
      )
      (property "Datasheet" "https://www.bourns.com/docs/product-datasheets/cr.pdf" (at 20.32 -17.78 0)
        (effects (font (size 1.27 1.27) (thickness 0.15)) (justify left bottom) hide)
      )
      (property "MPN" "CR0402-FX-1002GLF" (at 20.32 -20.32 0)
        (effects (font (size 1.27 1.27) (thickness 0.15)) (justify left bottom) hide)
      )
      (property "Manufacturer" "Bourns" (at 20.32 -22.86 0)
        (effects (font (size 1.27 1.27) (thickness 0.15)) (justify left bottom) hide)
      )
      (property "License" "Apache-2.0" (at 20.32 -25.4 0)
        (effects (font (size 1.27 1.27) (thickness 0.15)) (justify left bottom) hide)
      )
      (property "Author" "Antmicro" (at 20.32 -27.94 0)
        (effects (font (size 1.27 1.27) (thickness 0.15)) (justify left bottom) hide)
      )
      (property "Val" "10k" (at 20.32 -7.62 0)
        (effects (font (size 1.27 1.27) (thickness 0.15)) (justify left bottom))
      )
      (property "Tolerance" "1%" (at 20.32 -10.16 0)
        (effects (font (size 1.27 1.27)) (justify left bottom) hide)
      )
      (property "ki_description" "10k resistor in 0402 package with 1% tolerance" (at 0 0 0)
        (effects (font (size 1.27 1.27)) hide)
      )
      (symbol "R_10k_0402_0_1"
        (rectangle (start 0.635 0.889) (end 4.445 -0.889)
          (stroke (width 0.254) (type default))
          (fill (type none))
        )
      )
      (symbol "R_10k_0402_1_1"
        (pin passive line (at 0 0 0) (length 0.635)
          (name "~" (effects (font (size 1.27 1.27))))
          (number "1" (effects (font (size 1.27 1.27))))
        )
        (pin passive line (at 5.08 0 180) (length 0.635)
          (name "~" (effects (font (size 1.27 1.27))))
          (number "2" (effects (font (size 1.27 1.27))))
        )
      )
    )
	(symbol "antmicroResistors0402:R_12k1_0402" (pin_numbers hide) (pin_names hide) (in_bom yes) (on_board yes)
      (property "Reference" "R" (at 20.32 -5.08 0)
        (effects (font (size 1.27 1.27) (thickness 0.15)) (justify left bottom))
      )
      (property "Value" "R_12k1_0402" (at 20.32 -12.7 0)
        (effects (font (size 1.27 1.27) (thickness 0.15)) (justify left bottom) hide)
      )
      (property "Footprint" "antmicro-footprints:R_0402_1005Metric" (at 20.32 -15.24 0)
        (effects (font (size 1.27 1.27) (thickness 0.15)) (justify left bottom) hide)
      )
      (property "Datasheet" "https://www.bourns.com/docs/product-datasheets/cr.pdf" (at 20.32 -17.78 0)
        (effects (font (size 1.27 1.27) (thickness 0.15)) (justify left bottom) hide)
      )
      (property "MPN" "CR0402-FX-1212GLF" (at 20.32 -20.32 0)
        (effects (font (size 1.27 1.27) (thickness 0.15)) (justify left bottom) hide)
      )
      (property "Manufacturer" "Bourns" (at 20.32 -22.86 0)
        (effects (font (size 1.27 1.27) (thickness 0.15)) (justify left bottom) hide)
      )
      (property "License" "Apache-2.0" (at 20.32 -25.4 0)
        (effects (font (size 1.27 1.27) (thickness 0.15)) (justify left bottom) hide)
      )
      (property "Author" "Antmicro" (at 20.32 -27.94 0)
        (effects (font (size 1.27 1.27) (thickness 0.15)) (justify left bottom) hide)
      )
      (property "Val" "12k1" (at 20.32 -7.62 0)
        (effects (font (size 1.27 1.27) (thickness 0.15)) (justify left bottom))
      )
      (property "Tolerance" "1%" (at 20.32 -10.16 0)
        (effects (font (size 1.27 1.27)) (justify left bottom) hide)
      )
      (property "ki_description" "12k1 resistor in 0402 package with 1% tolerance" (at 0 0 0)
        (effects (font (size 1.27 1.27)) hide)
      )
      (symbol "R_12k1_0402_0_1"
        (rectangle (start 0.635 0.889) (end 4.445 -0.889)
          (stroke (width 0.254) (type default))
          (fill (type none))
        )
      )
      (symbol "R_12k1_0402_1_1"
        (pin passive line (at 0 0 0) (length 0.635)
          (name "~" (effects (font (size 1.27 1.27))))
          (number "1" (effects (font (size 1.27 1.27))))
        )
        (pin passive line (at 5.08 0 180) (length 0.635)
          (name "~" (effects (font (size 1.27 1.27))))
          (number "2" (effects (font (size 1.27 1.27))))
        )
      )
    )
	(symbol "antmicroResistors0402:R_12k4_0402" (pin_numbers hide) (pin_names hide) (in_bom yes) (on_board yes)
      (property "Reference" "R" (at 20.32 -5.08 0)
        (effects (font (size 1.27 1.27) (thickness 0.15)) (justify left bottom))
      )
      (property "Value" "R_12k4_0402" (at 20.32 -12.7 0)
        (effects (font (size 1.27 1.27) (thickness 0.15)) (justify left bottom) hide)
      )
      (property "Footprint" "antmicro-footprints:R_0402_1005Metric" (at 20.32 -15.24 0)
        (effects (font (size 1.27 1.27) (thickness 0.15)) (justify left bottom) hide)
      )
      (property "Datasheet" "https://www.bourns.com/docs/product-datasheets/cr.pdf" (at 20.32 -17.78 0)
        (effects (font (size 1.27 1.27) (thickness 0.15)) (justify left bottom) hide)
      )
      (property "MPN" "CR0402-FX-1242GLF" (at 20.32 -20.32 0)
        (effects (font (size 1.27 1.27) (thickness 0.15)) (justify left bottom) hide)
      )
      (property "Manufacturer" "Bourns" (at 20.32 -22.86 0)
        (effects (font (size 1.27 1.27) (thickness 0.15)) (justify left bottom) hide)
      )
      (property "License" "Apache-2.0" (at 20.32 -25.4 0)
        (effects (font (size 1.27 1.27) (thickness 0.15)) (justify left bottom) hide)
      )
      (property "Author" "Antmicro" (at 20.32 -27.94 0)
        (effects (font (size 1.27 1.27) (thickness 0.15)) (justify left bottom) hide)
      )
      (property "Val" "12k4" (at 20.32 -7.62 0)
        (effects (font (size 1.27 1.27) (thickness 0.15)) (justify left bottom))
      )
      (property "Tolerance" "1%" (at 20.32 -10.16 0)
        (effects (font (size 1.27 1.27)) (justify left bottom) hide)
      )
      (property "ki_description" "12k4 resistor in 0402 package with 1% tolerance" (at 0 0 0)
        (effects (font (size 1.27 1.27)) hide)
      )
      (symbol "R_12k4_0402_0_1"
        (rectangle (start 0.635 0.889) (end 4.445 -0.889)
          (stroke (width 0.254) (type default))
          (fill (type none))
        )
      )
      (symbol "R_12k4_0402_1_1"
        (pin passive line (at 0 0 0) (length 0.635)
          (name "~" (effects (font (size 1.27 1.27))))
          (number "1" (effects (font (size 1.27 1.27))))
        )
        (pin passive line (at 5.08 0 180) (length 0.635)
          (name "~" (effects (font (size 1.27 1.27))))
          (number "2" (effects (font (size 1.27 1.27))))
        )
      )
    )
	(symbol "antmicroResistors0402:R_12k_0402" (pin_numbers hide) (pin_names hide) (in_bom yes) (on_board yes)
      (property "Reference" "R" (at 20.32 -5.08 0)
        (effects (font (size 1.27 1.27) (thickness 0.15)) (justify left bottom))
      )
      (property "Value" "R_12k_0402" (at 20.32 -12.7 0)
        (effects (font (size 1.27 1.27) (thickness 0.15)) (justify left bottom) hide)
      )
      (property "Footprint" "antmicro-footprints:R_0402_1005Metric" (at 20.32 -15.24 0)
        (effects (font (size 1.27 1.27) (thickness 0.15)) (justify left bottom) hide)
      )
      (property "Datasheet" "https://www.bourns.com/docs/product-datasheets/cr.pdf" (at 20.32 -17.78 0)
        (effects (font (size 1.27 1.27) (thickness 0.15)) (justify left bottom) hide)
      )
      (property "MPN" "CR0402-FX-1202GLF" (at 20.32 -20.32 0)
        (effects (font (size 1.27 1.27) (thickness 0.15)) (justify left bottom) hide)
      )
      (property "Manufacturer" "Bourns" (at 20.32 -22.86 0)
        (effects (font (size 1.27 1.27) (thickness 0.15)) (justify left bottom) hide)
      )
      (property "License" "Apache-2.0" (at 20.32 -25.4 0)
        (effects (font (size 1.27 1.27) (thickness 0.15)) (justify left bottom) hide)
      )
      (property "Author" "Antmicro" (at 20.32 -27.94 0)
        (effects (font (size 1.27 1.27) (thickness 0.15)) (justify left bottom) hide)
      )
      (property "Val" "12k" (at 20.32 -7.62 0)
        (effects (font (size 1.27 1.27) (thickness 0.15)) (justify left bottom))
      )
      (property "Tolerance" "1%" (at 20.32 -10.16 0)
        (effects (font (size 1.27 1.27)) (justify left bottom) hide)
      )
      (property "ki_description" "12k resistor in 0402 package with 1% tolerance" (at 0 0 0)
        (effects (font (size 1.27 1.27)) hide)
      )
      (symbol "R_12k_0402_0_1"
        (rectangle (start 0.635 0.889) (end 4.445 -0.889)
          (stroke (width 0.254) (type default))
          (fill (type none))
        )
      )
      (symbol "R_12k_0402_1_1"
        (pin passive line (at 0 0 0) (length 0.635)
          (name "~" (effects (font (size 1.27 1.27))))
          (number "1" (effects (font (size 1.27 1.27))))
        )
        (pin passive line (at 5.08 0 180) (length 0.635)
          (name "~" (effects (font (size 1.27 1.27))))
          (number "2" (effects (font (size 1.27 1.27))))
        )
      )
    )
	(symbol "antmicroResistors0402:R_16k9_0402" (pin_numbers hide) (pin_names hide) (in_bom yes) (on_board yes)
      (property "Reference" "R" (at 20.32 -5.08 0)
        (effects (font (size 1.27 1.27) (thickness 0.15)) (justify left bottom))
      )
      (property "Value" "R_16k9_0402" (at 20.32 -12.7 0)
        (effects (font (size 1.27 1.27) (thickness 0.15)) (justify left bottom) hide)
      )
      (property "Footprint" "antmicro-footprints:R_0402_1005Metric" (at 20.32 -15.24 0)
        (effects (font (size 1.27 1.27) (thickness 0.15)) (justify left bottom) hide)
      )
      (property "Datasheet" "https://www.bourns.com/docs/product-datasheets/cr.pdf" (at 20.32 -17.78 0)
        (effects (font (size 1.27 1.27) (thickness 0.15)) (justify left bottom) hide)
      )
      (property "MPN" "CR0402-FX-1692GLF" (at 20.32 -20.32 0)
        (effects (font (size 1.27 1.27) (thickness 0.15)) (justify left bottom) hide)
      )
      (property "Manufacturer" "Bourns" (at 20.32 -22.86 0)
        (effects (font (size 1.27 1.27) (thickness 0.15)) (justify left bottom) hide)
      )
      (property "License" "Apache-2.0" (at 20.32 -25.4 0)
        (effects (font (size 1.27 1.27) (thickness 0.15)) (justify left bottom) hide)
      )
      (property "Author" "Antmicro" (at 20.32 -27.94 0)
        (effects (font (size 1.27 1.27) (thickness 0.15)) (justify left bottom) hide)
      )
      (property "Val" "16k9" (at 20.32 -7.62 0)
        (effects (font (size 1.27 1.27) (thickness 0.15)) (justify left bottom))
      )
      (property "Tolerance" "1%" (at 20.32 -10.16 0)
        (effects (font (size 1.27 1.27)) (justify left bottom) hide)
      )
      (property "ki_description" "16k9 resistor in 0402 package with 1% tolerance" (at 0 0 0)
        (effects (font (size 1.27 1.27)) hide)
      )
      (symbol "R_16k9_0402_0_1"
        (rectangle (start 0.635 0.889) (end 4.445 -0.889)
          (stroke (width 0.254) (type default))
          (fill (type none))
        )
      )
      (symbol "R_16k9_0402_1_1"
        (pin passive line (at 0 0 0) (length 0.635)
          (name "~" (effects (font (size 1.27 1.27))))
          (number "1" (effects (font (size 1.27 1.27))))
        )
        (pin passive line (at 5.08 0 180) (length 0.635)
          (name "~" (effects (font (size 1.27 1.27))))
          (number "2" (effects (font (size 1.27 1.27))))
        )
      )
    )
	(symbol "antmicroResistors0402:R_1M8_0402" (pin_numbers hide) (pin_names hide) (in_bom yes) (on_board yes)
      (property "Reference" "R" (at 20.32 -5.08 0)
        (effects (font (size 1.27 1.27) (thickness 0.15)) (justify left bottom))
      )
      (property "Value" "R_1M8_0402" (at 20.32 -12.7 0)
        (effects (font (size 1.27 1.27) (thickness 0.15)) (justify left bottom) hide)
      )
      (property "Footprint" "antmicro-footprints:R_0402_1005Metric" (at 20.32 -15.24 0)
        (effects (font (size 1.27 1.27) (thickness 0.15)) (justify left bottom) hide)
      )
      (property "Datasheet" "https://www.bourns.com/docs/product-datasheets/cr.pdf" (at 20.32 -17.78 0)
        (effects (font (size 1.27 1.27) (thickness 0.15)) (justify left bottom) hide)
      )
      (property "MPN" "CR0402-FX-1804GLF" (at 20.32 -20.32 0)
        (effects (font (size 1.27 1.27) (thickness 0.15)) (justify left bottom) hide)
      )
      (property "Manufacturer" "Bourns" (at 20.32 -22.86 0)
        (effects (font (size 1.27 1.27) (thickness 0.15)) (justify left bottom) hide)
      )
      (property "License" "Apache-2.0" (at 20.32 -25.4 0)
        (effects (font (size 1.27 1.27) (thickness 0.15)) (justify left bottom) hide)
      )
      (property "Author" "Antmicro" (at 20.32 -27.94 0)
        (effects (font (size 1.27 1.27) (thickness 0.15)) (justify left bottom) hide)
      )
      (property "Val" "1M8" (at 20.32 -7.62 0)
        (effects (font (size 1.27 1.27) (thickness 0.15)) (justify left bottom))
      )
      (property "Tolerance" "1%" (at 20.32 -10.16 0)
        (effects (font (size 1.27 1.27)) (justify left bottom) hide)
      )
      (property "ki_description" "1M8 resistor in 0402 package with 1% tolerance" (at 0 0 0)
        (effects (font (size 1.27 1.27)) hide)
      )
      (symbol "R_1M8_0402_0_1"
        (rectangle (start 0.635 0.889) (end 4.445 -0.889)
          (stroke (width 0.254) (type default))
          (fill (type none))
        )
      )
      (symbol "R_1M8_0402_1_1"
        (pin passive line (at 0 0 0) (length 0.635)
          (name "~" (effects (font (size 1.27 1.27))))
          (number "1" (effects (font (size 1.27 1.27))))
        )
        (pin passive line (at 5.08 0 180) (length 0.635)
          (name "~" (effects (font (size 1.27 1.27))))
          (number "2" (effects (font (size 1.27 1.27))))
        )
      )
    )
	(symbol "antmicroResistors0402:R_1k5_0402" (pin_numbers hide) (pin_names hide) (in_bom yes) (on_board yes)
      (property "Reference" "R" (at 20.32 -5.08 0)
        (effects (font (size 1.27 1.27) (thickness 0.15)) (justify left bottom))
      )
      (property "Value" "R_1k5_0402" (at 20.32 -12.7 0)
        (effects (font (size 1.27 1.27) (thickness 0.15)) (justify left bottom) hide)
      )
      (property "Footprint" "antmicro-footprints:R_0402_1005Metric" (at 20.32 -15.24 0)
        (effects (font (size 1.27 1.27) (thickness 0.15)) (justify left bottom) hide)
      )
      (property "Datasheet" "https://www.bourns.com/docs/product-datasheets/cr.pdf" (at 20.32 -17.78 0)
        (effects (font (size 1.27 1.27) (thickness 0.15)) (justify left bottom) hide)
      )
      (property "MPN" "CR0402-FX-1501GLF" (at 20.32 -20.32 0)
        (effects (font (size 1.27 1.27) (thickness 0.15)) (justify left bottom) hide)
      )
      (property "Manufacturer" "Bourns" (at 20.32 -22.86 0)
        (effects (font (size 1.27 1.27) (thickness 0.15)) (justify left bottom) hide)
      )
      (property "License" "Apache-2.0" (at 20.32 -25.4 0)
        (effects (font (size 1.27 1.27) (thickness 0.15)) (justify left bottom) hide)
      )
      (property "Author" "Antmicro" (at 20.32 -27.94 0)
        (effects (font (size 1.27 1.27) (thickness 0.15)) (justify left bottom) hide)
      )
      (property "Val" "1k5" (at 20.32 -7.62 0)
        (effects (font (size 1.27 1.27) (thickness 0.15)) (justify left bottom))
      )
      (property "Tolerance" "1%" (at 20.32 -10.16 0)
        (effects (font (size 1.27 1.27)) (justify left bottom) hide)
      )
      (property "ki_description" "1k5 resistor in 0402 package with 1% tolerance" (at 0 0 0)
        (effects (font (size 1.27 1.27)) hide)
      )
      (symbol "R_1k5_0402_0_1"
        (rectangle (start 0.635 0.889) (end 4.445 -0.889)
          (stroke (width 0.254) (type default))
          (fill (type none))
        )
      )
      (symbol "R_1k5_0402_1_1"
        (pin passive line (at 0 0 0) (length 0.635)
          (name "~" (effects (font (size 1.27 1.27))))
          (number "1" (effects (font (size 1.27 1.27))))
        )
        (pin passive line (at 5.08 0 180) (length 0.635)
          (name "~" (effects (font (size 1.27 1.27))))
          (number "2" (effects (font (size 1.27 1.27))))
        )
      )
    )
	(symbol "antmicroResistors0402:R_1k_0402" (pin_numbers hide) (pin_names hide) (in_bom yes) (on_board yes)
      (property "Reference" "R" (at 20.32 -5.08 0)
        (effects (font (size 1.27 1.27) (thickness 0.15)) (justify left bottom))
      )
      (property "Value" "R_1k_0402" (at 20.32 -12.7 0)
        (effects (font (size 1.27 1.27) (thickness 0.15)) (justify left bottom) hide)
      )
      (property "Footprint" "antmicro-footprints:R_0402_1005Metric" (at 20.32 -15.24 0)
        (effects (font (size 1.27 1.27) (thickness 0.15)) (justify left bottom) hide)
      )
      (property "Datasheet" "https://www.bourns.com/docs/product-datasheets/cr.pdf" (at 20.32 -17.78 0)
        (effects (font (size 1.27 1.27) (thickness 0.15)) (justify left bottom) hide)
      )
      (property "MPN" "CR0402-FX-1001GLF" (at 20.32 -20.32 0)
        (effects (font (size 1.27 1.27) (thickness 0.15)) (justify left bottom) hide)
      )
      (property "Manufacturer" "Bourns" (at 20.32 -22.86 0)
        (effects (font (size 1.27 1.27) (thickness 0.15)) (justify left bottom) hide)
      )
      (property "License" "Apache-2.0" (at 20.32 -25.4 0)
        (effects (font (size 1.27 1.27) (thickness 0.15)) (justify left bottom) hide)
      )
      (property "Author" "Antmicro" (at 20.32 -27.94 0)
        (effects (font (size 1.27 1.27) (thickness 0.15)) (justify left bottom) hide)
      )
      (property "Val" "1k" (at 20.32 -7.62 0)
        (effects (font (size 1.27 1.27) (thickness 0.15)) (justify left bottom))
      )
      (property "Tolerance" "1%" (at 20.32 -10.16 0)
        (effects (font (size 1.27 1.27)) (justify left bottom) hide)
      )
      (property "ki_description" "1k resistor in 0402 package with 1% tolerance" (at 0 0 0)
        (effects (font (size 1.27 1.27)) hide)
      )
      (symbol "R_1k_0402_0_1"
        (rectangle (start 0.635 0.889) (end 4.445 -0.889)
          (stroke (width 0.254) (type default))
          (fill (type none))
        )
      )
      (symbol "R_1k_0402_1_1"
        (pin passive line (at 0 0 0) (length 0.635)
          (name "~" (effects (font (size 1.27 1.27))))
          (number "1" (effects (font (size 1.27 1.27))))
        )
        (pin passive line (at 5.08 0 180) (length 0.635)
          (name "~" (effects (font (size 1.27 1.27))))
          (number "2" (effects (font (size 1.27 1.27))))
        )
      )
    )
	(symbol "antmicroResistors0402:R_20k_0402" (pin_numbers hide) (pin_names hide) (in_bom yes) (on_board yes)
      (property "Reference" "R" (at 20.32 -5.08 0)
        (effects (font (size 1.27 1.27) (thickness 0.15)) (justify left bottom))
      )
      (property "Value" "R_20k_0402" (at 20.32 -12.7 0)
        (effects (font (size 1.27 1.27) (thickness 0.15)) (justify left bottom) hide)
      )
      (property "Footprint" "antmicro-footprints:R_0402_1005Metric" (at 20.32 -15.24 0)
        (effects (font (size 1.27 1.27) (thickness 0.15)) (justify left bottom) hide)
      )
      (property "Datasheet" "https://www.bourns.com/docs/product-datasheets/cr.pdf" (at 20.32 -17.78 0)
        (effects (font (size 1.27 1.27) (thickness 0.15)) (justify left bottom) hide)
      )
      (property "MPN" "CR0402-FX-2002GLF" (at 20.32 -20.32 0)
        (effects (font (size 1.27 1.27) (thickness 0.15)) (justify left bottom) hide)
      )
      (property "Manufacturer" "Bourns" (at 20.32 -22.86 0)
        (effects (font (size 1.27 1.27) (thickness 0.15)) (justify left bottom) hide)
      )
      (property "License" "Apache-2.0" (at 20.32 -25.4 0)
        (effects (font (size 1.27 1.27) (thickness 0.15)) (justify left bottom) hide)
      )
      (property "Author" "Antmicro" (at 20.32 -27.94 0)
        (effects (font (size 1.27 1.27) (thickness 0.15)) (justify left bottom) hide)
      )
      (property "Val" "20k" (at 20.32 -7.62 0)
        (effects (font (size 1.27 1.27) (thickness 0.15)) (justify left bottom))
      )
      (property "Tolerance" "1%" (at 20.32 -10.16 0)
        (effects (font (size 1.27 1.27)) (justify left bottom) hide)
      )
      (property "ki_description" "20k resistor in 0402 package with 1% tolerance" (at 0 0 0)
        (effects (font (size 1.27 1.27)) hide)
      )
      (symbol "R_20k_0402_0_1"
        (rectangle (start 0.635 0.889) (end 4.445 -0.889)
          (stroke (width 0.254) (type default))
          (fill (type none))
        )
      )
      (symbol "R_20k_0402_1_1"
        (pin passive line (at 0 0 0) (length 0.635)
          (name "~" (effects (font (size 1.27 1.27))))
          (number "1" (effects (font (size 1.27 1.27))))
        )
        (pin passive line (at 5.08 0 180) (length 0.635)
          (name "~" (effects (font (size 1.27 1.27))))
          (number "2" (effects (font (size 1.27 1.27))))
        )
      )
    )
	(symbol "antmicroResistors0402:R_220R_0402" (pin_numbers hide) (pin_names hide) (in_bom yes) (on_board yes)
      (property "Reference" "R" (at 20.32 -5.08 0)
        (effects (font (size 1.27 1.27) (thickness 0.15)) (justify left bottom))
      )
      (property "Value" "R_220R_0402" (at 20.32 -12.7 0)
        (effects (font (size 1.27 1.27) (thickness 0.15)) (justify left bottom) hide)
      )
      (property "Footprint" "antmicro-footprints:R_0402_1005Metric" (at 20.32 -15.24 0)
        (effects (font (size 1.27 1.27) (thickness 0.15)) (justify left bottom) hide)
      )
      (property "Datasheet" "https://www.bourns.com/docs/product-datasheets/cr.pdf" (at 20.32 -17.78 0)
        (effects (font (size 1.27 1.27) (thickness 0.15)) (justify left bottom) hide)
      )
      (property "MPN" "CR0402-FX-2200GLF" (at 20.32 -20.32 0)
        (effects (font (size 1.27 1.27) (thickness 0.15)) (justify left bottom) hide)
      )
      (property "Manufacturer" "Bourns" (at 20.32 -22.86 0)
        (effects (font (size 1.27 1.27) (thickness 0.15)) (justify left bottom) hide)
      )
      (property "License" "Apache-2.0" (at 20.32 -25.4 0)
        (effects (font (size 1.27 1.27) (thickness 0.15)) (justify left bottom) hide)
      )
      (property "Author" "Antmicro" (at 20.32 -27.94 0)
        (effects (font (size 1.27 1.27) (thickness 0.15)) (justify left bottom) hide)
      )
      (property "Val" "220R" (at 20.32 -7.62 0)
        (effects (font (size 1.27 1.27) (thickness 0.15)) (justify left bottom))
      )
      (property "Tolerance" "1%" (at 20.32 -10.16 0)
        (effects (font (size 1.27 1.27)) (justify left bottom) hide)
      )
      (property "ki_description" "220R resistor in 0402 package with 1% tolerance" (at 0 0 0)
        (effects (font (size 1.27 1.27)) hide)
      )
      (symbol "R_220R_0402_0_1"
        (rectangle (start 0.635 0.889) (end 4.445 -0.889)
          (stroke (width 0.254) (type default))
          (fill (type none))
        )
      )
      (symbol "R_220R_0402_1_1"
        (pin passive line (at 0 0 0) (length 0.635)
          (name "~" (effects (font (size 1.27 1.27))))
          (number "1" (effects (font (size 1.27 1.27))))
        )
        (pin passive line (at 5.08 0 180) (length 0.635)
          (name "~" (effects (font (size 1.27 1.27))))
          (number "2" (effects (font (size 1.27 1.27))))
        )
      )
    )
	(symbol "antmicroResistors0402:R_22R_0402" (pin_numbers hide) (pin_names hide) (in_bom yes) (on_board yes)
      (property "Reference" "R" (at 20.32 -5.08 0)
        (effects (font (size 1.27 1.27) (thickness 0.15)) (justify left bottom))
      )
      (property "Value" "R_22R_0402" (at 20.32 -12.7 0)
        (effects (font (size 1.27 1.27) (thickness 0.15)) (justify left bottom) hide)
      )
      (property "Footprint" "antmicro-footprints:R_0402_1005Metric" (at 20.32 -15.24 0)
        (effects (font (size 1.27 1.27) (thickness 0.15)) (justify left bottom) hide)
      )
      (property "Datasheet" "https://www.bourns.com/docs/product-datasheets/cr.pdf" (at 20.32 -17.78 0)
        (effects (font (size 1.27 1.27) (thickness 0.15)) (justify left bottom) hide)
      )
      (property "MPN" "CR0402-FX-22R0GLF" (at 20.32 -20.32 0)
        (effects (font (size 1.27 1.27) (thickness 0.15)) (justify left bottom) hide)
      )
      (property "Manufacturer" "Bourns" (at 20.32 -22.86 0)
        (effects (font (size 1.27 1.27) (thickness 0.15)) (justify left bottom) hide)
      )
      (property "License" "Apache-2.0" (at 20.32 -25.4 0)
        (effects (font (size 1.27 1.27) (thickness 0.15)) (justify left bottom) hide)
      )
      (property "Author" "Antmicro" (at 20.32 -27.94 0)
        (effects (font (size 1.27 1.27) (thickness 0.15)) (justify left bottom) hide)
      )
      (property "Val" "22R" (at 20.32 -7.62 0)
        (effects (font (size 1.27 1.27) (thickness 0.15)) (justify left bottom))
      )
      (property "Tolerance" "1%" (at 20.32 -10.16 0)
        (effects (font (size 1.27 1.27)) (justify left bottom) hide)
      )
      (property "ki_description" "22R resistor in 0402 package with 1% tolerance" (at 0 0 0)
        (effects (font (size 1.27 1.27)) hide)
      )
      (symbol "R_22R_0402_0_1"
        (rectangle (start 0.635 0.889) (end 4.445 -0.889)
          (stroke (width 0.254) (type default))
          (fill (type none))
        )
      )
      (symbol "R_22R_0402_1_1"
        (pin passive line (at 0 0 0) (length 0.635)
          (name "~" (effects (font (size 1.27 1.27))))
          (number "1" (effects (font (size 1.27 1.27))))
        )
        (pin passive line (at 5.08 0 180) (length 0.635)
          (name "~" (effects (font (size 1.27 1.27))))
          (number "2" (effects (font (size 1.27 1.27))))
        )
      )
    )
	(symbol "antmicroResistors0402:R_243k_0402" (pin_numbers hide) (pin_names hide) (in_bom yes) (on_board yes)
      (property "Reference" "R" (at 20.32 -5.08 0)
        (effects (font (size 1.27 1.27) (thickness 0.15)) (justify left bottom))
      )
      (property "Value" "R_243k_0402" (at 20.32 -12.7 0)
        (effects (font (size 1.27 1.27) (thickness 0.15)) (justify left bottom) hide)
      )
      (property "Footprint" "antmicro-footprints:R_0402_1005Metric" (at 20.32 -15.24 0)
        (effects (font (size 1.27 1.27) (thickness 0.15)) (justify left bottom) hide)
      )
      (property "Datasheet" "https://www.bourns.com/docs/product-datasheets/cr.pdf" (at 20.32 -17.78 0)
        (effects (font (size 1.27 1.27) (thickness 0.15)) (justify left bottom) hide)
      )
      (property "MPN" "CR0402-FX-2433GLF" (at 20.32 -20.32 0)
        (effects (font (size 1.27 1.27) (thickness 0.15)) (justify left bottom) hide)
      )
      (property "Manufacturer" "Bourns" (at 20.32 -22.86 0)
        (effects (font (size 1.27 1.27) (thickness 0.15)) (justify left bottom) hide)
      )
      (property "License" "Apache-2.0" (at 20.32 -25.4 0)
        (effects (font (size 1.27 1.27) (thickness 0.15)) (justify left bottom) hide)
      )
      (property "Author" "Antmicro" (at 20.32 -27.94 0)
        (effects (font (size 1.27 1.27) (thickness 0.15)) (justify left bottom) hide)
      )
      (property "Val" "243k" (at 20.32 -7.62 0)
        (effects (font (size 1.27 1.27) (thickness 0.15)) (justify left bottom))
      )
      (property "Tolerance" "1%" (at 20.32 -10.16 0)
        (effects (font (size 1.27 1.27)) (justify left bottom) hide)
      )
      (property "ki_description" "243k resistor in 0402 package with 1% tolerance" (at 0 0 0)
        (effects (font (size 1.27 1.27)) hide)
      )
      (symbol "R_243k_0402_0_1"
        (rectangle (start 0.635 0.889) (end 4.445 -0.889)
          (stroke (width 0.254) (type default))
          (fill (type none))
        )
      )
      (symbol "R_243k_0402_1_1"
        (pin passive line (at 0 0 0) (length 0.635)
          (name "~" (effects (font (size 1.27 1.27))))
          (number "1" (effects (font (size 1.27 1.27))))
        )
        (pin passive line (at 5.08 0 180) (length 0.635)
          (name "~" (effects (font (size 1.27 1.27))))
          (number "2" (effects (font (size 1.27 1.27))))
        )
      )
    )
	(symbol "antmicroResistors0402:R_24k9_0402" (pin_numbers hide) (pin_names hide) (in_bom yes) (on_board yes)
      (property "Reference" "R" (at 20.32 -5.08 0)
        (effects (font (size 1.27 1.27) (thickness 0.15)) (justify left bottom))
      )
      (property "Value" "R_24k9_0402" (at 20.32 -12.7 0)
        (effects (font (size 1.27 1.27) (thickness 0.15)) (justify left bottom) hide)
      )
      (property "Footprint" "antmicro-footprints:R_0402_1005Metric" (at 20.32 -15.24 0)
        (effects (font (size 1.27 1.27) (thickness 0.15)) (justify left bottom) hide)
      )
      (property "Datasheet" "https://www.bourns.com/docs/product-datasheets/cr.pdf" (at 20.32 -17.78 0)
        (effects (font (size 1.27 1.27) (thickness 0.15)) (justify left bottom) hide)
      )
      (property "MPN" "CR0402-FX-2492GLF" (at 20.32 -20.32 0)
        (effects (font (size 1.27 1.27) (thickness 0.15)) (justify left bottom) hide)
      )
      (property "Manufacturer" "Bourns" (at 20.32 -22.86 0)
        (effects (font (size 1.27 1.27) (thickness 0.15)) (justify left bottom) hide)
      )
      (property "License" "Apache-2.0" (at 20.32 -25.4 0)
        (effects (font (size 1.27 1.27) (thickness 0.15)) (justify left bottom) hide)
      )
      (property "Author" "Antmicro" (at 20.32 -27.94 0)
        (effects (font (size 1.27 1.27) (thickness 0.15)) (justify left bottom) hide)
      )
      (property "Val" "24k9" (at 20.32 -7.62 0)
        (effects (font (size 1.27 1.27) (thickness 0.15)) (justify left bottom))
      )
      (property "Tolerance" "1%" (at 20.32 -10.16 0)
        (effects (font (size 1.27 1.27)) (justify left bottom) hide)
      )
      (property "ki_description" "24k9 resistor in 0402 package with 1% tolerance" (at 0 0 0)
        (effects (font (size 1.27 1.27)) hide)
      )
      (symbol "R_24k9_0402_0_1"
        (rectangle (start 0.635 0.889) (end 4.445 -0.889)
          (stroke (width 0.254) (type default))
          (fill (type none))
        )
      )
      (symbol "R_24k9_0402_1_1"
        (pin passive line (at 0 0 0) (length 0.635)
          (name "~" (effects (font (size 1.27 1.27))))
          (number "1" (effects (font (size 1.27 1.27))))
        )
        (pin passive line (at 5.08 0 180) (length 0.635)
          (name "~" (effects (font (size 1.27 1.27))))
          (number "2" (effects (font (size 1.27 1.27))))
        )
      )
    )
	(symbol "antmicroResistors0402:R_2k2_0402" (pin_numbers hide) (pin_names hide) (in_bom yes) (on_board yes)
      (property "Reference" "R" (at 20.32 -5.08 0)
        (effects (font (size 1.27 1.27) (thickness 0.15)) (justify left bottom))
      )
      (property "Value" "R_2k2_0402" (at 20.32 -12.7 0)
        (effects (font (size 1.27 1.27) (thickness 0.15)) (justify left bottom) hide)
      )
      (property "Footprint" "antmicro-footprints:R_0402_1005Metric" (at 20.32 -15.24 0)
        (effects (font (size 1.27 1.27) (thickness 0.15)) (justify left bottom) hide)
      )
      (property "Datasheet" "https://www.bourns.com/docs/product-datasheets/cr.pdf" (at 20.32 -17.78 0)
        (effects (font (size 1.27 1.27) (thickness 0.15)) (justify left bottom) hide)
      )
      (property "MPN" "CR0402-FX-2201GLF" (at 20.32 -20.32 0)
        (effects (font (size 1.27 1.27) (thickness 0.15)) (justify left bottom) hide)
      )
      (property "Manufacturer" "Bourns" (at 20.32 -22.86 0)
        (effects (font (size 1.27 1.27) (thickness 0.15)) (justify left bottom) hide)
      )
      (property "License" "Apache-2.0" (at 20.32 -25.4 0)
        (effects (font (size 1.27 1.27) (thickness 0.15)) (justify left bottom) hide)
      )
      (property "Author" "Antmicro" (at 20.32 -27.94 0)
        (effects (font (size 1.27 1.27) (thickness 0.15)) (justify left bottom) hide)
      )
      (property "Val" "2k2" (at 20.32 -7.62 0)
        (effects (font (size 1.27 1.27) (thickness 0.15)) (justify left bottom))
      )
      (property "Tolerance" "1%" (at 20.32 -10.16 0)
        (effects (font (size 1.27 1.27)) (justify left bottom) hide)
      )
      (property "ki_description" "2k2 resistor in 0402 package with 1% tolerance" (at 0 0 0)
        (effects (font (size 1.27 1.27)) hide)
      )
      (symbol "R_2k2_0402_0_1"
        (rectangle (start 0.635 0.889) (end 4.445 -0.889)
          (stroke (width 0.254) (type default))
          (fill (type none))
        )
      )
      (symbol "R_2k2_0402_1_1"
        (pin passive line (at 0 0 0) (length 0.635)
          (name "~" (effects (font (size 1.27 1.27))))
          (number "1" (effects (font (size 1.27 1.27))))
        )
        (pin passive line (at 5.08 0 180) (length 0.635)
          (name "~" (effects (font (size 1.27 1.27))))
          (number "2" (effects (font (size 1.27 1.27))))
        )
      )
    )
	(symbol "antmicroResistors0402:R_31k6_0402" (pin_numbers hide) (pin_names hide) (in_bom yes) (on_board yes)
      (property "Reference" "R" (at 20.32 -5.08 0)
        (effects (font (size 1.27 1.27) (thickness 0.15)) (justify left bottom))
      )
      (property "Value" "R_31k6_0402" (at 20.32 -12.7 0)
        (effects (font (size 1.27 1.27) (thickness 0.15)) (justify left bottom) hide)
      )
      (property "Footprint" "antmicro-footprints:R_0402_1005Metric" (at 20.32 -15.24 0)
        (effects (font (size 1.27 1.27) (thickness 0.15)) (justify left bottom) hide)
      )
      (property "Datasheet" "https://www.bourns.com/docs/product-datasheets/cr.pdf" (at 20.32 -17.78 0)
        (effects (font (size 1.27 1.27) (thickness 0.15)) (justify left bottom) hide)
      )
      (property "MPN" "CR0402-FX-3162GLF" (at 20.32 -20.32 0)
        (effects (font (size 1.27 1.27) (thickness 0.15)) (justify left bottom) hide)
      )
      (property "Manufacturer" "Bourns" (at 20.32 -22.86 0)
        (effects (font (size 1.27 1.27) (thickness 0.15)) (justify left bottom) hide)
      )
      (property "License" "Apache-2.0" (at 20.32 -25.4 0)
        (effects (font (size 1.27 1.27) (thickness 0.15)) (justify left bottom) hide)
      )
      (property "Author" "Antmicro" (at 20.32 -27.94 0)
        (effects (font (size 1.27 1.27) (thickness 0.15)) (justify left bottom) hide)
      )
      (property "Val" "31k6" (at 20.32 -7.62 0)
        (effects (font (size 1.27 1.27) (thickness 0.15)) (justify left bottom))
      )
      (property "Tolerance" "1%" (at 20.32 -10.16 0)
        (effects (font (size 1.27 1.27)) (justify left bottom) hide)
      )
      (property "ki_description" "31k6 resistor in 0402 package with 1% tolerance" (at 0 0 0)
        (effects (font (size 1.27 1.27)) hide)
      )
      (symbol "R_31k6_0402_0_1"
        (rectangle (start 0.635 0.889) (end 4.445 -0.889)
          (stroke (width 0.254) (type default))
          (fill (type none))
        )
      )
      (symbol "R_31k6_0402_1_1"
        (pin passive line (at 0 0 0) (length 0.635)
          (name "~" (effects (font (size 1.27 1.27))))
          (number "1" (effects (font (size 1.27 1.27))))
        )
        (pin passive line (at 5.08 0 180) (length 0.635)
          (name "~" (effects (font (size 1.27 1.27))))
          (number "2" (effects (font (size 1.27 1.27))))
        )
      )
    )
	(symbol "antmicroResistors0402:R_32k4_0402" (pin_numbers hide) (pin_names hide) (in_bom yes) (on_board yes)
      (property "Reference" "R" (at 20.32 -5.08 0)
        (effects (font (size 1.27 1.27) (thickness 0.15)) (justify left bottom))
      )
      (property "Value" "R_32k4_0402" (at 20.32 -12.7 0)
        (effects (font (size 1.27 1.27) (thickness 0.15)) (justify left bottom) hide)
      )
      (property "Footprint" "antmicro-footprints:R_0402_1005Metric" (at 20.32 -15.24 0)
        (effects (font (size 1.27 1.27) (thickness 0.15)) (justify left bottom) hide)
      )
      (property "Datasheet" "https://www.bourns.com/docs/product-datasheets/cr.pdf" (at 20.32 -17.78 0)
        (effects (font (size 1.27 1.27) (thickness 0.15)) (justify left bottom) hide)
      )
      (property "MPN" "CR0402-FX-3242GLF" (at 20.32 -20.32 0)
        (effects (font (size 1.27 1.27) (thickness 0.15)) (justify left bottom) hide)
      )
      (property "Manufacturer" "Bourns" (at 20.32 -22.86 0)
        (effects (font (size 1.27 1.27) (thickness 0.15)) (justify left bottom) hide)
      )
      (property "License" "Apache-2.0" (at 20.32 -25.4 0)
        (effects (font (size 1.27 1.27) (thickness 0.15)) (justify left bottom) hide)
      )
      (property "Author" "Antmicro" (at 20.32 -27.94 0)
        (effects (font (size 1.27 1.27) (thickness 0.15)) (justify left bottom) hide)
      )
      (property "Val" "32k4" (at 20.32 -7.62 0)
        (effects (font (size 1.27 1.27) (thickness 0.15)) (justify left bottom))
      )
      (property "Tolerance" "1%" (at 20.32 -10.16 0)
        (effects (font (size 1.27 1.27)) (justify left bottom) hide)
      )
      (property "ki_description" "32k4 resistor in 0402 package with 1% tolerance" (at 0 0 0)
        (effects (font (size 1.27 1.27)) hide)
      )
      (symbol "R_32k4_0402_0_1"
        (rectangle (start 0.635 0.889) (end 4.445 -0.889)
          (stroke (width 0.254) (type default))
          (fill (type none))
        )
      )
      (symbol "R_32k4_0402_1_1"
        (pin passive line (at 0 0 0) (length 0.635)
          (name "~" (effects (font (size 1.27 1.27))))
          (number "1" (effects (font (size 1.27 1.27))))
        )
        (pin passive line (at 5.08 0 180) (length 0.635)
          (name "~" (effects (font (size 1.27 1.27))))
          (number "2" (effects (font (size 1.27 1.27))))
        )
      )
    )
	(symbol "antmicroResistors0402:R_330R_0402" (pin_numbers hide) (pin_names hide) (in_bom yes) (on_board yes)
      (property "Reference" "R" (at 20.32 -5.08 0)
        (effects (font (size 1.27 1.27) (thickness 0.15)) (justify left bottom))
      )
      (property "Value" "R_330R_0402" (at 20.32 -12.7 0)
        (effects (font (size 1.27 1.27) (thickness 0.15)) (justify left bottom) hide)
      )
      (property "Footprint" "antmicro-footprints:R_0402_1005Metric" (at 20.32 -15.24 0)
        (effects (font (size 1.27 1.27) (thickness 0.15)) (justify left bottom) hide)
      )
      (property "Datasheet" "https://www.bourns.com/docs/product-datasheets/cr.pdf" (at 20.32 -17.78 0)
        (effects (font (size 1.27 1.27) (thickness 0.15)) (justify left bottom) hide)
      )
      (property "MPN" "CR0402-FX-3300GLF" (at 20.32 -20.32 0)
        (effects (font (size 1.27 1.27) (thickness 0.15)) (justify left bottom) hide)
      )
      (property "Manufacturer" "Bourns" (at 20.32 -22.86 0)
        (effects (font (size 1.27 1.27) (thickness 0.15)) (justify left bottom) hide)
      )
      (property "License" "Apache-2.0" (at 20.32 -25.4 0)
        (effects (font (size 1.27 1.27) (thickness 0.15)) (justify left bottom) hide)
      )
      (property "Author" "Antmicro" (at 20.32 -27.94 0)
        (effects (font (size 1.27 1.27) (thickness 0.15)) (justify left bottom) hide)
      )
      (property "Val" "330R" (at 20.32 -7.62 0)
        (effects (font (size 1.27 1.27) (thickness 0.15)) (justify left bottom))
      )
      (property "Tolerance" "1%" (at 20.32 -10.16 0)
        (effects (font (size 1.27 1.27)) (justify left bottom) hide)
      )
      (property "ki_description" "330R resistor in 0402 package with 1% tolerance" (at 0 0 0)
        (effects (font (size 1.27 1.27)) hide)
      )
      (symbol "R_330R_0402_0_1"
        (rectangle (start 0.635 0.889) (end 4.445 -0.889)
          (stroke (width 0.254) (type default))
          (fill (type none))
        )
      )
      (symbol "R_330R_0402_1_1"
        (pin passive line (at 0 0 0) (length 0.635)
          (name "~" (effects (font (size 1.27 1.27))))
          (number "1" (effects (font (size 1.27 1.27))))
        )
        (pin passive line (at 5.08 0 180) (length 0.635)
          (name "~" (effects (font (size 1.27 1.27))))
          (number "2" (effects (font (size 1.27 1.27))))
        )
      )
    )
	(symbol "antmicroResistors0402:R_33R_0402" (pin_numbers hide) (pin_names hide) (in_bom yes) (on_board yes)
      (property "Reference" "R" (at 20.32 -5.08 0)
        (effects (font (size 1.27 1.27) (thickness 0.15)) (justify left bottom))
      )
      (property "Value" "R_33R_0402" (at 20.32 -12.7 0)
        (effects (font (size 1.27 1.27) (thickness 0.15)) (justify left bottom) hide)
      )
      (property "Footprint" "antmicro-footprints:R_0402_1005Metric" (at 20.32 -15.24 0)
        (effects (font (size 1.27 1.27) (thickness 0.15)) (justify left bottom) hide)
      )
      (property "Datasheet" "https://www.bourns.com/docs/product-datasheets/cr.pdf" (at 20.32 -17.78 0)
        (effects (font (size 1.27 1.27) (thickness 0.15)) (justify left bottom) hide)
      )
      (property "MPN" "CR0402-FX-33R0GLF" (at 20.32 -20.32 0)
        (effects (font (size 1.27 1.27) (thickness 0.15)) (justify left bottom) hide)
      )
      (property "Manufacturer" "Bourns" (at 20.32 -22.86 0)
        (effects (font (size 1.27 1.27) (thickness 0.15)) (justify left bottom) hide)
      )
      (property "License" "Apache-2.0" (at 20.32 -25.4 0)
        (effects (font (size 1.27 1.27) (thickness 0.15)) (justify left bottom) hide)
      )
      (property "Author" "Antmicro" (at 20.32 -27.94 0)
        (effects (font (size 1.27 1.27) (thickness 0.15)) (justify left bottom) hide)
      )
      (property "Val" "33R" (at 20.32 -7.62 0)
        (effects (font (size 1.27 1.27) (thickness 0.15)) (justify left bottom))
      )
      (property "Tolerance" "1%" (at 20.32 -10.16 0)
        (effects (font (size 1.27 1.27)) (justify left bottom) hide)
      )
      (property "ki_description" "33R resistor in 0402 package with 1% tolerance" (at 0 0 0)
        (effects (font (size 1.27 1.27)) hide)
      )
      (symbol "R_33R_0402_0_1"
        (rectangle (start 0.635 0.889) (end 4.445 -0.889)
          (stroke (width 0.254) (type default))
          (fill (type none))
        )
      )
      (symbol "R_33R_0402_1_1"
        (pin passive line (at 0 0 0) (length 0.635)
          (name "~" (effects (font (size 1.27 1.27))))
          (number "1" (effects (font (size 1.27 1.27))))
        )
        (pin passive line (at 5.08 0 180) (length 0.635)
          (name "~" (effects (font (size 1.27 1.27))))
          (number "2" (effects (font (size 1.27 1.27))))
        )
      )
    )
	(symbol "antmicroResistors0402:R_47k_0402" (pin_numbers hide) (pin_names hide) (in_bom yes) (on_board yes)
      (property "Reference" "R" (at 20.32 -5.08 0)
        (effects (font (size 1.27 1.27) (thickness 0.15)) (justify left bottom))
      )
      (property "Value" "R_47k_0402" (at 20.32 -12.7 0)
        (effects (font (size 1.27 1.27) (thickness 0.15)) (justify left bottom) hide)
      )
      (property "Footprint" "antmicro-footprints:R_0402_1005Metric" (at 20.32 -15.24 0)
        (effects (font (size 1.27 1.27) (thickness 0.15)) (justify left bottom) hide)
      )
      (property "Datasheet" "https://www.bourns.com/docs/product-datasheets/cr.pdf" (at 20.32 -17.78 0)
        (effects (font (size 1.27 1.27) (thickness 0.15)) (justify left bottom) hide)
      )
      (property "MPN" "CR0402-FX-4702GLF" (at 20.32 -20.32 0)
        (effects (font (size 1.27 1.27) (thickness 0.15)) (justify left bottom) hide)
      )
      (property "Manufacturer" "Bourns" (at 20.32 -22.86 0)
        (effects (font (size 1.27 1.27) (thickness 0.15)) (justify left bottom) hide)
      )
      (property "License" "Apache-2.0" (at 20.32 -25.4 0)
        (effects (font (size 1.27 1.27) (thickness 0.15)) (justify left bottom) hide)
      )
      (property "Author" "Antmicro" (at 20.32 -27.94 0)
        (effects (font (size 1.27 1.27) (thickness 0.15)) (justify left bottom) hide)
      )
      (property "Val" "47k" (at 20.32 -7.62 0)
        (effects (font (size 1.27 1.27) (thickness 0.15)) (justify left bottom))
      )
      (property "Tolerance" "1%" (at 20.32 -10.16 0)
        (effects (font (size 1.27 1.27)) (justify left bottom) hide)
      )
      (property "ki_description" "47k resistor in 0402 package with 1% tolerance" (at 0 0 0)
        (effects (font (size 1.27 1.27)) hide)
      )
      (symbol "R_47k_0402_0_1"
        (rectangle (start 0.635 0.889) (end 4.445 -0.889)
          (stroke (width 0.254) (type default))
          (fill (type none))
        )
      )
      (symbol "R_47k_0402_1_1"
        (pin passive line (at 0 0 0) (length 0.635)
          (name "~" (effects (font (size 1.27 1.27))))
          (number "1" (effects (font (size 1.27 1.27))))
        )
        (pin passive line (at 5.08 0 180) (length 0.635)
          (name "~" (effects (font (size 1.27 1.27))))
          (number "2" (effects (font (size 1.27 1.27))))
        )
      )
    )
	(symbol "antmicroResistors0402:R_49R9_0402" (pin_numbers hide) (pin_names hide) (in_bom yes) (on_board yes)
      (property "Reference" "R" (at 20.32 -5.08 0)
        (effects (font (size 1.27 1.27) (thickness 0.15)) (justify left bottom))
      )
      (property "Value" "R_49R9_0402" (at 20.32 -12.7 0)
        (effects (font (size 1.27 1.27) (thickness 0.15)) (justify left bottom) hide)
      )
      (property "Footprint" "antmicro-footprints:R_0402_1005Metric" (at 20.32 -15.24 0)
        (effects (font (size 1.27 1.27) (thickness 0.15)) (justify left bottom) hide)
      )
      (property "Datasheet" "https://www.bourns.com/docs/product-datasheets/cr.pdf" (at 20.32 -17.78 0)
        (effects (font (size 1.27 1.27) (thickness 0.15)) (justify left bottom) hide)
      )
      (property "MPN" "CR0402-FX-49R9GLF" (at 20.32 -20.32 0)
        (effects (font (size 1.27 1.27) (thickness 0.15)) (justify left bottom) hide)
      )
      (property "Manufacturer" "Bourns" (at 20.32 -22.86 0)
        (effects (font (size 1.27 1.27) (thickness 0.15)) (justify left bottom) hide)
      )
      (property "License" "Apache-2.0" (at 20.32 -25.4 0)
        (effects (font (size 1.27 1.27) (thickness 0.15)) (justify left bottom) hide)
      )
      (property "Author" "Antmicro" (at 20.32 -27.94 0)
        (effects (font (size 1.27 1.27) (thickness 0.15)) (justify left bottom) hide)
      )
      (property "Val" "49R9" (at 20.32 -7.62 0)
        (effects (font (size 1.27 1.27) (thickness 0.15)) (justify left bottom))
      )
      (property "Tolerance" "1%" (at 20.32 -10.16 0)
        (effects (font (size 1.27 1.27)) (justify left bottom) hide)
      )
      (property "ki_description" "49R9 resistor in 0402 package with 1% tolerance" (at 0 0 0)
        (effects (font (size 1.27 1.27)) hide)
      )
      (symbol "R_49R9_0402_0_1"
        (rectangle (start 0.635 0.889) (end 4.445 -0.889)
          (stroke (width 0.254) (type default))
          (fill (type none))
        )
      )
      (symbol "R_49R9_0402_1_1"
        (pin passive line (at 0 0 0) (length 0.635)
          (name "~" (effects (font (size 1.27 1.27))))
          (number "1" (effects (font (size 1.27 1.27))))
        )
        (pin passive line (at 5.08 0 180) (length 0.635)
          (name "~" (effects (font (size 1.27 1.27))))
          (number "2" (effects (font (size 1.27 1.27))))
        )
      )
    )
	(symbol "antmicroResistors0402:R_49k9_0402" (pin_numbers hide) (pin_names hide) (in_bom yes) (on_board yes)
      (property "Reference" "R" (at 20.32 -5.08 0)
        (effects (font (size 1.27 1.27) (thickness 0.15)) (justify left bottom))
      )
      (property "Value" "R_49k9_0402" (at 20.32 -12.7 0)
        (effects (font (size 1.27 1.27) (thickness 0.15)) (justify left bottom) hide)
      )
      (property "Footprint" "antmicro-footprints:R_0402_1005Metric" (at 20.32 -15.24 0)
        (effects (font (size 1.27 1.27) (thickness 0.15)) (justify left bottom) hide)
      )
      (property "Datasheet" "https://www.bourns.com/docs/product-datasheets/cr.pdf" (at 20.32 -17.78 0)
        (effects (font (size 1.27 1.27) (thickness 0.15)) (justify left bottom) hide)
      )
      (property "MPN" "CR0402-FX-4992GLF" (at 20.32 -20.32 0)
        (effects (font (size 1.27 1.27) (thickness 0.15)) (justify left bottom) hide)
      )
      (property "Manufacturer" "Bourns" (at 20.32 -22.86 0)
        (effects (font (size 1.27 1.27) (thickness 0.15)) (justify left bottom) hide)
      )
      (property "License" "Apache-2.0" (at 20.32 -25.4 0)
        (effects (font (size 1.27 1.27) (thickness 0.15)) (justify left bottom) hide)
      )
      (property "Author" "Antmicro" (at 20.32 -27.94 0)
        (effects (font (size 1.27 1.27) (thickness 0.15)) (justify left bottom) hide)
      )
      (property "Val" "49k9" (at 20.32 -7.62 0)
        (effects (font (size 1.27 1.27) (thickness 0.15)) (justify left bottom))
      )
      (property "Tolerance" "1%" (at 20.32 -10.16 0)
        (effects (font (size 1.27 1.27)) (justify left bottom) hide)
      )
      (property "ki_description" "49k9 resistor in 0402 package with 1% tolerance" (at 0 0 0)
        (effects (font (size 1.27 1.27)) hide)
      )
      (symbol "R_49k9_0402_0_1"
        (rectangle (start 0.635 0.889) (end 4.445 -0.889)
          (stroke (width 0.254) (type default))
          (fill (type none))
        )
      )
      (symbol "R_49k9_0402_1_1"
        (pin passive line (at 0 0 0) (length 0.635)
          (name "~" (effects (font (size 1.27 1.27))))
          (number "1" (effects (font (size 1.27 1.27))))
        )
        (pin passive line (at 5.08 0 180) (length 0.635)
          (name "~" (effects (font (size 1.27 1.27))))
          (number "2" (effects (font (size 1.27 1.27))))
        )
      )
    )
	(symbol "antmicroResistors0402:R_4k7_0402" (pin_numbers hide) (pin_names hide) (in_bom yes) (on_board yes)
      (property "Reference" "R" (at 20.32 -5.08 0)
        (effects (font (size 1.27 1.27) (thickness 0.15)) (justify left bottom))
      )
      (property "Value" "R_4k7_0402" (at 20.32 -12.7 0)
        (effects (font (size 1.27 1.27) (thickness 0.15)) (justify left bottom) hide)
      )
      (property "Footprint" "antmicro-footprints:R_0402_1005Metric" (at 20.32 -15.24 0)
        (effects (font (size 1.27 1.27) (thickness 0.15)) (justify left bottom) hide)
      )
      (property "Datasheet" "https://www.bourns.com/docs/product-datasheets/cr.pdf" (at 20.32 -17.78 0)
        (effects (font (size 1.27 1.27) (thickness 0.15)) (justify left bottom) hide)
      )
      (property "MPN" "CR0402-FX-4701GLF" (at 20.32 -20.32 0)
        (effects (font (size 1.27 1.27) (thickness 0.15)) (justify left bottom) hide)
      )
      (property "Manufacturer" "Bourns" (at 20.32 -22.86 0)
        (effects (font (size 1.27 1.27) (thickness 0.15)) (justify left bottom) hide)
      )
      (property "License" "Apache-2.0" (at 20.32 -25.4 0)
        (effects (font (size 1.27 1.27) (thickness 0.15)) (justify left bottom) hide)
      )
      (property "Author" "Antmicro" (at 20.32 -27.94 0)
        (effects (font (size 1.27 1.27) (thickness 0.15)) (justify left bottom) hide)
      )
      (property "Val" "4k7" (at 20.32 -7.62 0)
        (effects (font (size 1.27 1.27) (thickness 0.15)) (justify left bottom))
      )
      (property "Tolerance" "1%" (at 20.32 -10.16 0)
        (effects (font (size 1.27 1.27)) (justify left bottom) hide)
      )
      (property "ki_description" "4k7 resistor in 0402 package with 1% tolerance" (at 0 0 0)
        (effects (font (size 1.27 1.27)) hide)
      )
      (symbol "R_4k7_0402_0_1"
        (rectangle (start 0.635 0.889) (end 4.445 -0.889)
          (stroke (width 0.254) (type default))
          (fill (type none))
        )
      )
      (symbol "R_4k7_0402_1_1"
        (pin passive line (at 0 0 0) (length 0.635)
          (name "~" (effects (font (size 1.27 1.27))))
          (number "1" (effects (font (size 1.27 1.27))))
        )
        (pin passive line (at 5.08 0 180) (length 0.635)
          (name "~" (effects (font (size 1.27 1.27))))
          (number "2" (effects (font (size 1.27 1.27))))
        )
      )
    )
	(symbol "antmicroResistors0402:R_4k99_0402" (pin_numbers hide) (pin_names hide) (in_bom yes) (on_board yes)
      (property "Reference" "R" (at 20.32 -5.08 0)
        (effects (font (size 1.27 1.27) (thickness 0.15)) (justify left bottom))
      )
      (property "Value" "R_4k99_0402" (at 20.32 -12.7 0)
        (effects (font (size 1.27 1.27) (thickness 0.15)) (justify left bottom) hide)
      )
      (property "Footprint" "antmicro-footprints:R_0402_1005Metric" (at 20.32 -15.24 0)
        (effects (font (size 1.27 1.27) (thickness 0.15)) (justify left bottom) hide)
      )
      (property "Datasheet" "https://www.bourns.com/docs/product-datasheets/cr.pdf" (at 20.32 -17.78 0)
        (effects (font (size 1.27 1.27) (thickness 0.15)) (justify left bottom) hide)
      )
      (property "MPN" "CR0402-FX-4991GLF" (at 20.32 -20.32 0)
        (effects (font (size 1.27 1.27) (thickness 0.15)) (justify left bottom) hide)
      )
      (property "Manufacturer" "Bourns" (at 20.32 -22.86 0)
        (effects (font (size 1.27 1.27) (thickness 0.15)) (justify left bottom) hide)
      )
      (property "License" "Apache-2.0" (at 20.32 -25.4 0)
        (effects (font (size 1.27 1.27) (thickness 0.15)) (justify left bottom) hide)
      )
      (property "Author" "Antmicro" (at 20.32 -27.94 0)
        (effects (font (size 1.27 1.27) (thickness 0.15)) (justify left bottom) hide)
      )
      (property "Val" "4k99" (at 20.32 -7.62 0)
        (effects (font (size 1.27 1.27) (thickness 0.15)) (justify left bottom))
      )
      (property "Tolerance" "1%" (at 20.32 -10.16 0)
        (effects (font (size 1.27 1.27)) (justify left bottom) hide)
      )
      (property "ki_description" "4k99 resistor in 0402 package with 1% tolerance" (at 0 0 0)
        (effects (font (size 1.27 1.27)) hide)
      )
      (symbol "R_4k99_0402_0_1"
        (rectangle (start 0.635 0.889) (end 4.445 -0.889)
          (stroke (width 0.254) (type default))
          (fill (type none))
        )
      )
      (symbol "R_4k99_0402_1_1"
        (pin passive line (at 0 0 0) (length 0.635)
          (name "~" (effects (font (size 1.27 1.27))))
          (number "1" (effects (font (size 1.27 1.27))))
        )
        (pin passive line (at 5.08 0 180) (length 0.635)
          (name "~" (effects (font (size 1.27 1.27))))
          (number "2" (effects (font (size 1.27 1.27))))
        )
      )
    )
	(symbol "antmicroResistors0402:R_53k6_0402" (pin_numbers hide) (pin_names hide) (in_bom yes) (on_board yes)
      (property "Reference" "R" (at 20.32 -5.08 0)
        (effects (font (size 1.27 1.27) (thickness 0.15)) (justify left bottom))
      )
      (property "Value" "R_53k6_0402" (at 20.32 -12.7 0)
        (effects (font (size 1.27 1.27) (thickness 0.15)) (justify left bottom) hide)
      )
      (property "Footprint" "antmicro-footprints:R_0402_1005Metric" (at 20.32 -15.24 0)
        (effects (font (size 1.27 1.27) (thickness 0.15)) (justify left bottom) hide)
      )
      (property "Datasheet" "https://www.bourns.com/docs/product-datasheets/cr.pdf" (at 20.32 -17.78 0)
        (effects (font (size 1.27 1.27) (thickness 0.15)) (justify left bottom) hide)
      )
      (property "MPN" "CR0402-FX-5362GLF" (at 20.32 -20.32 0)
        (effects (font (size 1.27 1.27) (thickness 0.15)) (justify left bottom) hide)
      )
      (property "Manufacturer" "Bourns" (at 20.32 -22.86 0)
        (effects (font (size 1.27 1.27) (thickness 0.15)) (justify left bottom) hide)
      )
      (property "License" "Apache-2.0" (at 20.32 -25.4 0)
        (effects (font (size 1.27 1.27) (thickness 0.15)) (justify left bottom) hide)
      )
      (property "Author" "Antmicro" (at 20.32 -27.94 0)
        (effects (font (size 1.27 1.27) (thickness 0.15)) (justify left bottom) hide)
      )
      (property "Val" "53k6" (at 20.32 -7.62 0)
        (effects (font (size 1.27 1.27) (thickness 0.15)) (justify left bottom))
      )
      (property "Tolerance" "1%" (at 20.32 -10.16 0)
        (effects (font (size 1.27 1.27)) (justify left bottom) hide)
      )
      (property "ki_description" "53k6 resistor in 0402 package with 1% tolerance" (at 0 0 0)
        (effects (font (size 1.27 1.27)) hide)
      )
      (symbol "R_53k6_0402_0_1"
        (rectangle (start 0.635 0.889) (end 4.445 -0.889)
          (stroke (width 0.254) (type default))
          (fill (type none))
        )
      )
      (symbol "R_53k6_0402_1_1"
        (pin passive line (at 0 0 0) (length 0.635)
          (name "~" (effects (font (size 1.27 1.27))))
          (number "1" (effects (font (size 1.27 1.27))))
        )
        (pin passive line (at 5.08 0 180) (length 0.635)
          (name "~" (effects (font (size 1.27 1.27))))
          (number "2" (effects (font (size 1.27 1.27))))
        )
      )
    )
	(symbol "antmicroResistors0402:R_5R1_0402" (pin_numbers hide) (pin_names hide) (in_bom yes) (on_board yes)
      (property "Reference" "R" (at 20.32 -5.08 0)
        (effects (font (size 1.27 1.27) (thickness 0.15)) (justify left bottom))
      )
      (property "Value" "R_5R1_0402" (at 20.32 -12.7 0)
        (effects (font (size 1.27 1.27) (thickness 0.15)) (justify left bottom) hide)
      )
      (property "Footprint" "antmicro-footprints:R_0402_1005Metric" (at 20.32 -15.24 0)
        (effects (font (size 1.27 1.27) (thickness 0.15)) (justify left bottom) hide)
      )
      (property "Datasheet" "https://www.bourns.com/docs/product-datasheets/cr.pdf" (at 20.32 -17.78 0)
        (effects (font (size 1.27 1.27) (thickness 0.15)) (justify left bottom) hide)
      )
      (property "MPN" "CR0402-FX-5R10GLF" (at 20.32 -20.32 0)
        (effects (font (size 1.27 1.27) (thickness 0.15)) (justify left bottom) hide)
      )
      (property "Manufacturer" "Bourns" (at 20.32 -22.86 0)
        (effects (font (size 1.27 1.27) (thickness 0.15)) (justify left bottom) hide)
      )
      (property "License" "Apache-2.0" (at 20.32 -25.4 0)
        (effects (font (size 1.27 1.27) (thickness 0.15)) (justify left bottom) hide)
      )
      (property "Author" "Antmicro" (at 20.32 -27.94 0)
        (effects (font (size 1.27 1.27) (thickness 0.15)) (justify left bottom) hide)
      )
      (property "Val" "5R1" (at 20.32 -7.62 0)
        (effects (font (size 1.27 1.27) (thickness 0.15)) (justify left bottom))
      )
      (property "Tolerance" "1%" (at 20.32 -10.16 0)
        (effects (font (size 1.27 1.27)) (justify left bottom) hide)
      )
      (property "ki_description" "5R1 resistor in 0402 package with 1% tolerance" (at 0 0 0)
        (effects (font (size 1.27 1.27)) hide)
      )
      (symbol "R_5R1_0402_0_1"
        (rectangle (start 0.635 0.889) (end 4.445 -0.889)
          (stroke (width 0.254) (type default))
          (fill (type none))
        )
      )
      (symbol "R_5R1_0402_1_1"
        (pin passive line (at 0 0 0) (length 0.635)
          (name "~" (effects (font (size 1.27 1.27))))
          (number "1" (effects (font (size 1.27 1.27))))
        )
        (pin passive line (at 5.08 0 180) (length 0.635)
          (name "~" (effects (font (size 1.27 1.27))))
          (number "2" (effects (font (size 1.27 1.27))))
        )
      )
    )
	(symbol "antmicroResistors0402:R_5k11_0402" (pin_numbers hide) (pin_names hide) (in_bom yes) (on_board yes)
      (property "Reference" "R" (at 20.32 -5.08 0)
        (effects (font (size 1.27 1.27) (thickness 0.15)) (justify left bottom))
      )
      (property "Value" "R_5k11_0402" (at 20.32 -12.7 0)
        (effects (font (size 1.27 1.27) (thickness 0.15)) (justify left bottom) hide)
      )
      (property "Footprint" "antmicro-footprints:R_0402_1005Metric" (at 20.32 -15.24 0)
        (effects (font (size 1.27 1.27) (thickness 0.15)) (justify left bottom) hide)
      )
      (property "Datasheet" "https://www.bourns.com/docs/product-datasheets/cr.pdf" (at 20.32 -17.78 0)
        (effects (font (size 1.27 1.27) (thickness 0.15)) (justify left bottom) hide)
      )
      (property "MPN" "CR0402-FX-5111GLF" (at 20.32 -20.32 0)
        (effects (font (size 1.27 1.27) (thickness 0.15)) (justify left bottom) hide)
      )
      (property "Manufacturer" "Bourns" (at 20.32 -22.86 0)
        (effects (font (size 1.27 1.27) (thickness 0.15)) (justify left bottom) hide)
      )
      (property "License" "Apache-2.0" (at 20.32 -25.4 0)
        (effects (font (size 1.27 1.27) (thickness 0.15)) (justify left bottom) hide)
      )
      (property "Author" "Antmicro" (at 20.32 -27.94 0)
        (effects (font (size 1.27 1.27) (thickness 0.15)) (justify left bottom) hide)
      )
      (property "Val" "5k11" (at 20.32 -7.62 0)
        (effects (font (size 1.27 1.27) (thickness 0.15)) (justify left bottom))
      )
      (property "Tolerance" "1%" (at 20.32 -10.16 0)
        (effects (font (size 1.27 1.27)) (justify left bottom) hide)
      )
      (property "ki_description" "5k11 resistor in 0402 package with 1% tolerance" (at 0 0 0)
        (effects (font (size 1.27 1.27)) hide)
      )
      (symbol "R_5k11_0402_0_1"
        (rectangle (start 0.635 0.889) (end 4.445 -0.889)
          (stroke (width 0.254) (type default))
          (fill (type none))
        )
      )
      (symbol "R_5k11_0402_1_1"
        (pin passive line (at 0 0 0) (length 0.635)
          (name "~" (effects (font (size 1.27 1.27))))
          (number "1" (effects (font (size 1.27 1.27))))
        )
        (pin passive line (at 5.08 0 180) (length 0.635)
          (name "~" (effects (font (size 1.27 1.27))))
          (number "2" (effects (font (size 1.27 1.27))))
        )
      )
    )
	(symbol "antmicroResistors0603:R_1k3_0603" (pin_numbers hide) (pin_names hide) (in_bom yes) (on_board yes)
      (property "Reference" "R" (at 20.32 -5.08 0)
        (effects (font (size 1.27 1.27) (thickness 0.15)) (justify left bottom))
      )
      (property "Value" "R_1k3_0603" (at 20.32 -12.7 0)
        (effects (font (size 1.27 1.27) (thickness 0.15)) (justify left bottom) hide)
      )
      (property "Footprint" "antmicro-footprints:R_0603_1608Metric" (at 20.32 -15.24 0)
        (effects (font (size 1.27 1.27) (thickness 0.15)) (justify left bottom) hide)
      )
      (property "Datasheet" "https://www.bourns.com/docs/product-datasheets/cr.pdf" (at 20.32 -17.78 0)
        (effects (font (size 1.27 1.27) (thickness 0.15)) (justify left bottom) hide)
      )
      (property "MPN" "CR0603-FX-1301ELF" (at 20.32 -20.32 0)
        (effects (font (size 1.27 1.27) (thickness 0.15)) (justify left bottom) hide)
      )
      (property "Manufacturer" "Bourns" (at 20.32 -22.86 0)
        (effects (font (size 1.27 1.27) (thickness 0.15)) (justify left bottom) hide)
      )
      (property "License" "Apache-2.0" (at 20.32 -25.4 0)
        (effects (font (size 1.27 1.27) (thickness 0.15)) (justify left bottom) hide)
      )
      (property "Author" "Antmicro" (at 20.32 -27.94 0)
        (effects (font (size 1.27 1.27) (thickness 0.15)) (justify left bottom) hide)
      )
      (property "Val" "1k3" (at 20.32 -7.62 0)
        (effects (font (size 1.27 1.27) (thickness 0.15)) (justify left bottom))
      )
      (property "Tolerance" "1%" (at 20.32 -10.16 0)
        (effects (font (size 1.27 1.27)) (justify left bottom) hide)
      )
      (property "ki_description" "1k3 resistor in 0603 package with 1% tolerance" (at 0 0 0)
        (effects (font (size 1.27 1.27)) hide)
      )
      (symbol "R_1k3_0603_0_1"
        (rectangle (start 0.635 0.889) (end 4.445 -0.889)
          (stroke (width 0.254) (type default))
          (fill (type none))
        )
      )
      (symbol "R_1k3_0603_1_1"
        (pin passive line (at 0 0 0) (length 0.635)
          (name "~" (effects (font (size 1.27 1.27))))
          (number "1" (effects (font (size 1.27 1.27))))
        )
        (pin passive line (at 5.08 0 180) (length 0.635)
          (name "~" (effects (font (size 1.27 1.27))))
          (number "2" (effects (font (size 1.27 1.27))))
        )
      )
    )
	(symbol "antmicroResistors0603:R_1k_0603" (pin_numbers hide) (pin_names hide) (in_bom yes) (on_board yes)
      (property "Reference" "R" (at 20.32 -5.08 0)
        (effects (font (size 1.27 1.27) (thickness 0.15)) (justify left bottom))
      )
      (property "Value" "R_1k_0603" (at 20.32 -12.7 0)
        (effects (font (size 1.27 1.27) (thickness 0.15)) (justify left bottom) hide)
      )
      (property "Footprint" "antmicro-footprints:R_0603_1608Metric" (at 20.32 -15.24 0)
        (effects (font (size 1.27 1.27) (thickness 0.15)) (justify left bottom) hide)
      )
      (property "Datasheet" "https://www.bourns.com/docs/product-datasheets/cr.pdf" (at 20.32 -17.78 0)
        (effects (font (size 1.27 1.27) (thickness 0.15)) (justify left bottom) hide)
      )
      (property "MPN" "CR0603-FX-1001ELF" (at 20.32 -20.32 0)
        (effects (font (size 1.27 1.27) (thickness 0.15)) (justify left bottom) hide)
      )
      (property "Manufacturer" "Bourns" (at 20.32 -22.86 0)
        (effects (font (size 1.27 1.27) (thickness 0.15)) (justify left bottom) hide)
      )
      (property "License" "Apache-2.0" (at 20.32 -25.4 0)
        (effects (font (size 1.27 1.27) (thickness 0.15)) (justify left bottom) hide)
      )
      (property "Author" "Antmicro" (at 20.32 -27.94 0)
        (effects (font (size 1.27 1.27) (thickness 0.15)) (justify left bottom) hide)
      )
      (property "Val" "1k" (at 20.32 -7.62 0)
        (effects (font (size 1.27 1.27) (thickness 0.15)) (justify left bottom))
      )
      (property "Tolerance" "1%" (at 20.32 -10.16 0)
        (effects (font (size 1.27 1.27)) (justify left bottom) hide)
      )
      (property "ki_description" "1k resistor in 0603 package with 1% tolerance" (at 0 0 0)
        (effects (font (size 1.27 1.27)) hide)
      )
      (symbol "R_1k_0603_0_1"
        (rectangle (start 0.635 0.889) (end 4.445 -0.889)
          (stroke (width 0.254) (type default))
          (fill (type none))
        )
      )
      (symbol "R_1k_0603_1_1"
        (pin passive line (at 0 0 0) (length 0.635)
          (name "~" (effects (font (size 1.27 1.27))))
          (number "1" (effects (font (size 1.27 1.27))))
        )
        (pin passive line (at 5.08 0 180) (length 0.635)
          (name "~" (effects (font (size 1.27 1.27))))
          (number "2" (effects (font (size 1.27 1.27))))
        )
      )
    )
	(symbol "antmicroResistors0603:R_330R_0.25W_0603" (pin_numbers hide) (pin_names hide) (in_bom yes) (on_board yes)
      (property "Reference" "R" (at 20.32 -5.08 0)
        (effects (font (size 1.27 1.27) (thickness 0.15)) (justify left bottom))
      )
      (property "Value" "R_330R_0.25W_0603" (at 20.32 -12.7 0)
        (effects (font (size 1.27 1.27) (thickness 0.15)) (justify left bottom) hide)
      )
      (property "Footprint" "antmicro-footprints:R_0603_1608Metric" (at 20.32 -15.24 0)
        (effects (font (size 1.27 1.27) (thickness 0.15)) (justify left bottom) hide)
      )
      (property "Datasheet" "https://www.mouser.pl/datasheet/2/315/Panasonic_Resistors_Thick_Film_Anti_Sulf_Anti_Surg-1825099.pdf" (at 20.32 -17.78 0)
        (effects (font (size 1.27 1.27) (thickness 0.15)) (justify left bottom) hide)
      )
      (property "MPN" "ERJ-UP3F3300V" (at 20.32 -20.32 0)
        (effects (font (size 1.27 1.27) (thickness 0.15)) (justify left bottom) hide)
      )
      (property "Manufacturer" "Panasonic" (at 20.32 -22.86 0)
        (effects (font (size 1.27 1.27) (thickness 0.15)) (justify left bottom) hide)
      )
      (property "License" "Apache-2.0" (at 20.32 -25.4 0)
        (effects (font (size 1.27 1.27) (thickness 0.15)) (justify left bottom) hide)
      )
      (property "Author" "Antmicro" (at 20.32 -27.94 0)
        (effects (font (size 1.27 1.27) (thickness 0.15)) (justify left bottom) hide)
      )
      (property "Val" "330R" (at 20.32 -7.62 0)
        (effects (font (size 1.27 1.27) (thickness 0.15)) (justify left bottom))
      )
      (property "Tolerance" "1%" (at 20.32 -10.16 0)
        (effects (font (size 1.27 1.27)) (justify left bottom) hide)
      )
      (property "ki_description" "330R resistor in 0603 package with 1% tolerance" (at 0 0 0)
        (effects (font (size 1.27 1.27)) hide)
      )
      (symbol "R_330R_0.25W_0603_0_1"
        (rectangle (start 0.635 0.889) (end 4.445 -0.889)
          (stroke (width 0.254) (type default))
          (fill (type none))
        )
      )
      (symbol "R_330R_0.25W_0603_1_1"
        (pin passive line (at 0 0 0) (length 0.635)
          (name "~" (effects (font (size 1.27 1.27))))
          (number "1" (effects (font (size 1.27 1.27))))
        )
        (pin passive line (at 5.08 0 180) (length 0.635)
          (name "~" (effects (font (size 1.27 1.27))))
          (number "2" (effects (font (size 1.27 1.27))))
        )
      )
    )
	(symbol "antmicroResistors0603:R_63R4_0603" (pin_numbers hide) (pin_names hide) (in_bom yes) (on_board yes)
      (property "Reference" "R" (at 20.32 -5.08 0)
        (effects (font (size 1.27 1.27) (thickness 0.15)) (justify left bottom))
      )
      (property "Value" "R_63R4_0603" (at 20.32 -12.7 0)
        (effects (font (size 1.27 1.27) (thickness 0.15)) (justify left bottom) hide)
      )
      (property "Footprint" "antmicro-footprints:R_0603_1608Metric" (at 20.32 -15.24 0)
        (effects (font (size 1.27 1.27) (thickness 0.15)) (justify left bottom) hide)
      )
      (property "Datasheet" "https://www.bourns.com/docs/product-datasheets/cr.pdf" (at 20.32 -17.78 0)
        (effects (font (size 1.27 1.27) (thickness 0.15)) (justify left bottom) hide)
      )
      (property "MPN" "CR0603-FX-63R4ELF" (at 20.32 -20.32 0)
        (effects (font (size 1.27 1.27) (thickness 0.15)) (justify left bottom) hide)
      )
      (property "Manufacturer" "Bourns" (at 20.32 -22.86 0)
        (effects (font (size 1.27 1.27) (thickness 0.15)) (justify left bottom) hide)
      )
      (property "License" "Apache-2.0" (at 20.32 -25.4 0)
        (effects (font (size 1.27 1.27) (thickness 0.15)) (justify left bottom) hide)
      )
      (property "Author" "Antmicro" (at 20.32 -27.94 0)
        (effects (font (size 1.27 1.27) (thickness 0.15)) (justify left bottom) hide)
      )
      (property "Val" "63R4" (at 20.32 -7.62 0)
        (effects (font (size 1.27 1.27) (thickness 0.15)) (justify left bottom))
      )
      (property "Tolerance" "1%" (at 20.32 -10.16 0)
        (effects (font (size 1.27 1.27)) (justify left bottom) hide)
      )
      (property "ki_description" "63R4 resistor in 0603 package with 1% tolerance" (at 0 0 0)
        (effects (font (size 1.27 1.27)) hide)
      )
      (symbol "R_63R4_0603_0_1"
        (rectangle (start 0.635 0.889) (end 4.445 -0.889)
          (stroke (width 0.254) (type default))
          (fill (type none))
        )
      )
      (symbol "R_63R4_0603_1_1"
        (pin passive line (at 0 0 0) (length 0.635)
          (name "~" (effects (font (size 1.27 1.27))))
          (number "1" (effects (font (size 1.27 1.27))))
        )
        (pin passive line (at 5.08 0 180) (length 0.635)
          (name "~" (effects (font (size 1.27 1.27))))
          (number "2" (effects (font (size 1.27 1.27))))
        )
      )
    )
	(symbol "antmicroResistors0603:R_80R6_0603" (pin_numbers hide) (pin_names hide) (in_bom yes) (on_board yes)
      (property "Reference" "R" (at 20.32 -5.08 0)
        (effects (font (size 1.27 1.27) (thickness 0.15)) (justify left bottom))
      )
      (property "Value" "R_80R6_0603" (at 20.32 -12.7 0)
        (effects (font (size 1.27 1.27) (thickness 0.15)) (justify left bottom) hide)
      )
      (property "Footprint" "antmicro-footprints:R_0603_1608Metric" (at 20.32 -15.24 0)
        (effects (font (size 1.27 1.27) (thickness 0.15)) (justify left bottom) hide)
      )
      (property "Datasheet" "https://www.bourns.com/docs/product-datasheets/cr.pdf" (at 20.32 -17.78 0)
        (effects (font (size 1.27 1.27) (thickness 0.15)) (justify left bottom) hide)
      )
      (property "MPN" "CR0603-FX-80R6ELF" (at 20.32 -20.32 0)
        (effects (font (size 1.27 1.27) (thickness 0.15)) (justify left bottom) hide)
      )
      (property "Manufacturer" "Bourns" (at 20.32 -22.86 0)
        (effects (font (size 1.27 1.27) (thickness 0.15)) (justify left bottom) hide)
      )
      (property "License" "Apache-2.0" (at 20.32 -25.4 0)
        (effects (font (size 1.27 1.27) (thickness 0.15)) (justify left bottom) hide)
      )
      (property "Author" "Antmicro" (at 20.32 -27.94 0)
        (effects (font (size 1.27 1.27) (thickness 0.15)) (justify left bottom) hide)
      )
      (property "Val" "80R6" (at 20.32 -7.62 0)
        (effects (font (size 1.27 1.27) (thickness 0.15)) (justify left bottom))
      )
      (property "Tolerance" "1%" (at 20.32 -10.16 0)
        (effects (font (size 1.27 1.27)) (justify left bottom) hide)
      )
      (property "ki_description" "80R6 resistor in 0603 package with 1% tolerance" (at 0 0 0)
        (effects (font (size 1.27 1.27)) hide)
      )
      (symbol "R_80R6_0603_0_1"
        (rectangle (start 0.635 0.889) (end 4.445 -0.889)
          (stroke (width 0.254) (type default))
          (fill (type none))
        )
      )
      (symbol "R_80R6_0603_1_1"
        (pin passive line (at 0 0 0) (length 0.635)
          (name "~" (effects (font (size 1.27 1.27))))
          (number "1" (effects (font (size 1.27 1.27))))
        )
        (pin passive line (at 5.08 0 180) (length 0.635)
          (name "~" (effects (font (size 1.27 1.27))))
          (number "2" (effects (font (size 1.27 1.27))))
        )
      )
    )
	(symbol "antmicroResistorsmisc:R_0R005_1206" (pin_numbers hide) (pin_names hide) (in_bom yes) (on_board yes)
      (property "Reference" "R" (at 20.32 -5.08 0)
        (effects (font (size 1.27 1.27) (thickness 0.15)) (justify left bottom))
      )
      (property "Value" "R_0R005_1206" (at 20.32 -12.7 0)
        (effects (font (size 1.27 1.27) (thickness 0.15)) (justify left bottom) hide)
      )
      (property "Footprint" "antmicro-footprints:R_1206_3216Metric" (at 20.32 -15.24 0)
        (effects (font (size 1.27 1.27) (thickness 0.15)) (justify left bottom) hide)
      )
      (property "Datasheet" "https://www.bourns.com/docs/product-datasheets/cr.pdf" (at 20.32 -17.78 0)
        (effects (font (size 1.27 1.27) (thickness 0.15)) (justify left bottom) hide)
      )
      (property "MPN" "CR1206-J/-000ELF" (at 20.32 -20.32 0)
        (effects (font (size 1.27 1.27) (thickness 0.15)) (justify left bottom) hide)
      )
      (property "Manufacturer" "Bourns" (at 20.32 -22.86 0)
        (effects (font (size 1.27 1.27) (thickness 0.15)) (justify left bottom) hide)
      )
      (property "License" "Apache-2.0" (at 20.32 -25.4 0)
        (effects (font (size 1.27 1.27) (thickness 0.15)) (justify left bottom) hide)
      )
      (property "Author" "Antmicro" (at 20.32 -27.94 0)
        (effects (font (size 1.27 1.27) (thickness 0.15)) (justify left bottom) hide)
      )
      (property "Val" "0R005" (at 20.32 -7.62 0)
        (effects (font (size 1.27 1.27) (thickness 0.15)) (justify left bottom))
      )
      (property "Tolerance" "1%" (at 20.32 -10.16 0)
        (effects (font (size 1.27 1.27)) (justify left bottom) hide)
      )
      (property "ki_description" "0R005 resistor in 1206 package with 1% tolerance" (at 0 0 0)
        (effects (font (size 1.27 1.27)) hide)
      )
      (symbol "R_0R005_1206_0_1"
        (rectangle (start 0.635 0.889) (end 4.445 -0.889)
          (stroke (width 0.254) (type default))
          (fill (type none))
        )
      )
      (symbol "R_0R005_1206_1_1"
        (pin passive line (at 0 0 0) (length 0.635)
          (name "~" (effects (font (size 1.27 1.27))))
          (number "1" (effects (font (size 1.27 1.27))))
        )
        (pin passive line (at 5.08 0 180) (length 0.635)
          (name "~" (effects (font (size 1.27 1.27))))
          (number "2" (effects (font (size 1.27 1.27))))
        )
      )
    )
	(symbol "antmicroResistorsmisc:R_0R01_1206" (pin_numbers hide) (pin_names hide) (in_bom yes) (on_board yes)
      (property "Reference" "R" (at 20.32 -5.08 0)
        (effects (font (size 1.27 1.27) (thickness 0.15)) (justify left bottom))
      )
      (property "Value" "R_0R01_1206" (at 20.32 -12.7 0)
        (effects (font (size 1.27 1.27) (thickness 0.15)) (justify left bottom) hide)
      )
      (property "Footprint" "antmicro-footprints:R_1206_3216Metric" (at 20.32 -15.24 0)
        (effects (font (size 1.27 1.27) (thickness 0.15)) (justify left bottom) hide)
      )
      (property "Datasheet" "https://www.yageo.com/upload/media/product/productsearch/datasheet/rchip/PYu-RL_Group_521_RoHS_L_2.pdf" (at 20.32 -17.78 0)
        (effects (font (size 1.27 1.27) (thickness 0.15)) (justify left bottom) hide)
      )
      (property "MPN" "RL1206FR-7W0R01L" (at 20.32 -20.32 0)
        (effects (font (size 1.27 1.27) (thickness 0.15)) (justify left bottom) hide)
      )
      (property "Manufacturer" "Yaego" (at 20.32 -22.86 0)
        (effects (font (size 1.27 1.27) (thickness 0.15)) (justify left bottom) hide)
      )
      (property "License" "Apache-2.0" (at 20.32 -25.4 0)
        (effects (font (size 1.27 1.27) (thickness 0.15)) (justify left bottom) hide)
      )
      (property "Author" "Antmicro" (at 20.32 -27.94 0)
        (effects (font (size 1.27 1.27) (thickness 0.15)) (justify left bottom) hide)
      )
      (property "Val" "0R01" (at 20.32 -7.62 0)
        (effects (font (size 1.27 1.27) (thickness 0.15)) (justify left bottom))
      )
      (property "Tolerance" "1%" (at 20.32 -10.16 0)
        (effects (font (size 1.27 1.27)) (justify left bottom) hide)
      )
      (property "ki_description" "0R01 resistor in 1206 package with unspecified tolerance" (at 0 0 0)
        (effects (font (size 1.27 1.27)) hide)
      )
      (symbol "R_0R01_1206_0_1"
        (rectangle (start 0.635 0.889) (end 4.445 -0.889)
          (stroke (width 0.254) (type default))
          (fill (type none))
        )
      )
      (symbol "R_0R01_1206_1_1"
        (pin passive line (at 0 0 0) (length 0.635)
          (name "~" (effects (font (size 1.27 1.27))))
          (number "1" (effects (font (size 1.27 1.27))))
        )
        (pin passive line (at 5.08 0 180) (length 0.635)
          (name "~" (effects (font (size 1.27 1.27))))
          (number "2" (effects (font (size 1.27 1.27))))
        )
      )
    )
	(symbol "antmicroResistorsmisc:R_0R_0201" (pin_numbers hide) (pin_names hide) (in_bom yes) (on_board yes)
      (property "Reference" "R" (at 20.32 -5.08 0)
        (effects (font (size 1.27 1.27) (thickness 0.15)) (justify left bottom))
      )
      (property "Value" "R_0R_0201" (at 20.32 -12.7 0)
        (effects (font (size 1.27 1.27) (thickness 0.15)) (justify left bottom) hide)
      )
      (property "Footprint" "antmicro-footprints:R_0201" (at 20.32 -15.24 0)
        (effects (font (size 1.27 1.27) (thickness 0.15)) (justify left bottom) hide)
      )
      (property "Datasheet" "https://www.bourns.com/docs/product-datasheets/cr.pdf" (at 20.32 -17.78 0)
        (effects (font (size 1.27 1.27) (thickness 0.15)) (justify left bottom) hide)
      )
      (property "MPN" "CR0201-FX-0R00GLF" (at 20.32 -20.32 0)
        (effects (font (size 1.27 1.27) (thickness 0.15)) (justify left bottom) hide)
      )
      (property "Manufacturer" "Bourns" (at 20.32 -22.86 0)
        (effects (font (size 1.27 1.27) (thickness 0.15)) (justify left bottom) hide)
      )
      (property "License" "Apache-2.0" (at 20.32 -25.4 0)
        (effects (font (size 1.27 1.27) (thickness 0.15)) (justify left bottom) hide)
      )
      (property "Author" "Antmicro" (at 20.32 -27.94 0)
        (effects (font (size 1.27 1.27) (thickness 0.15)) (justify left bottom) hide)
      )
      (property "Val" "0R" (at 20.32 -7.62 0)
        (effects (font (size 1.27 1.27) (thickness 0.15)) (justify left bottom))
      )
      (property "Tolerance" "1%" (at 20.32 -10.16 0)
        (effects (font (size 1.27 1.27)) (justify left bottom) hide)
      )
      (property "ki_description" "0R resistor in 0201 package with 1% tolerance" (at 0 0 0)
        (effects (font (size 1.27 1.27)) hide)
      )
      (symbol "R_0R_0201_0_1"
        (rectangle (start 0.635 0.889) (end 4.445 -0.889)
          (stroke (width 0.254) (type default))
          (fill (type none))
        )
      )
      (symbol "R_0R_0201_1_1"
        (pin passive line (at 0 0 0) (length 0.635)
          (name "~" (effects (font (size 1.27 1.27))))
          (number "1" (effects (font (size 1.27 1.27))))
        )
        (pin passive line (at 5.08 0 180) (length 0.635)
          (name "~" (effects (font (size 1.27 1.27))))
          (number "2" (effects (font (size 1.27 1.27))))
        )
      )
    )
	(symbol "antmicroSlideSwitches:SW_DS04-254-1-01BK-SMT" (in_bom yes) (on_board yes)
      (property "Reference" "SW" (at 26.67 -2.54 0)
        (effects (font (size 1.27 1.27) (thickness 0.15)) (justify left bottom))
      )
      (property "Value" "SW_DS04-254-1-01BK-SMT" (at 26.67 -5.08 0)
        (effects (font (size 1.27 1.27) (thickness 0.15)) (justify left bottom))
      )
      (property "Footprint" "antmicro-footprints:SW_DS04-254-1-01BK-SMT" (at 26.67 -7.62 0)
        (effects (font (size 1.27 1.27) (thickness 0.15)) (justify left bottom) hide)
      )
      (property "Datasheet" "https://www.mouser.com/datasheet/2/670/ds04_254_smt-1777718.pdf" (at 26.67 -10.16 0)
        (effects (font (size 1.27 1.27) (thickness 0.15)) (justify left bottom) hide)
      )
      (property "MPN" "DS04-254-1-01BK-SMT" (at 26.67 -12.7 0)
        (effects (font (size 1.27 1.27) (thickness 0.15)) (justify left bottom) hide)
      )
      (property "Manufacturer" "CUI Inc" (at 26.67 -15.24 0)
        (effects (font (size 1.27 1.27) (thickness 0.15)) (justify left bottom) hide)
      )
      (property "Author" "Antmicro" (at 26.67 -17.78 0)
        (effects (font (size 1.27 1.27) (thickness 0.15)) (justify left bottom) hide)
      )
      (property "License" "Apache-2.0" (at 26.67 -20.32 0)
        (effects (font (size 1.27 1.27) (thickness 0.15)) (justify left bottom) hide)
      )
      (property "ki_keywords" "HORIZONTAL, SMT, SWITCH, MECHANICAL, SLIDE" (at 0 0 0)
        (effects (font (size 1.27 1.27)) hide)
      )
      (property "ki_description" "Slide switch" (at 0 0 0)
        (effects (font (size 1.27 1.27)) hide)
      )
      (property "ki_fp_filters" "SW?DIP?x1*" (at 0 0 0)
        (effects (font (size 1.27 1.27)) hide)
      )
      (symbol "SW_DS04-254-1-01BK-SMT_0_1"
        (polyline
          (pts
            (xy 3.81 0)
            (xy 2.54 0)
          )
          (stroke (width 0.254) (type default))
          (fill (type none))
        )
        (polyline
          (pts
            (xy 10.16 0)
            (xy 8.89 0)
          )
          (stroke (width 0.254) (type default))
          (fill (type none))
        )
      )
      (symbol "SW_DS04-254-1-01BK-SMT_1_1"
        (polyline
          (pts
            (xy 4.826 0.127)
            (xy 8.7122 1.1684)
          )
          (stroke (width 0.254) (type default))
          (fill (type background))
        )
        (rectangle (start 2.54 2.54) (end 10.16 -2.54)
          (stroke (width 0.254) (type default))
          (fill (type background))
        )
        (circle (center 4.318 0) (radius 0.508)
          (stroke (width 0.254) (type default))
          (fill (type background))
        )
        (circle (center 8.382 0) (radius 0.508)
          (stroke (width 0.254) (type default))
          (fill (type background))
        )
        (pin passive line (at 0 0 0) (length 2.54)
          (name "~" (effects (font (size 1.27 1.27))))
          (number "1" (effects (font (size 1.27 1.27))))
        )
        (pin passive line (at 12.7 0 180) (length 2.54)
          (name "~" (effects (font (size 1.27 1.27))))
          (number "2" (effects (font (size 1.27 1.27))))
        )
      )
    )
	(symbol "antmicroTVSDiodes:CD-MMBL110S" (pin_names hide) (in_bom yes) (on_board yes)
      (property "Reference" "D" (at 26.67 -2.54 0)
        (effects (font (size 1.27 1.27) (thickness 0.15)) (justify left bottom))
      )
      (property "Value" "CD-MMBL110S" (at 26.67 -5.08 0)
        (effects (font (size 1.27 1.27) (thickness 0.15)) (justify left bottom))
      )
      (property "Footprint" "antmicro-footprints:DFN3538" (at 26.67 -7.62 0)
        (effects (font (size 1.27 1.27) (thickness 0.15)) (justify left bottom) hide)
      )
      (property "Datasheet" "https://www.bourns.com/docs/product-datasheets/CD-MMBL110S.pdf" (at 26.67 -10.16 0)
        (effects (font (size 1.27 1.27) (thickness 0.15)) (justify left bottom) hide)
      )
      (property "MPN" "CD-MMBL110S" (at 26.67 -12.7 0)
        (effects (font (size 1.27 1.27) (thickness 0.15)) (justify left bottom) hide)
      )
      (property "Manufacturer" "Bourns" (at 26.67 -15.24 0)
        (effects (font (size 1.27 1.27) (thickness 0.15)) (justify left bottom) hide)
      )
      (property "Author" "Antmicro" (at 26.67 -17.78 0)
        (effects (font (size 1.27 1.27) (thickness 0.15)) (justify left bottom) hide)
      )
      (property "License" "Apache-2.0" (at 26.67 -20.32 0)
        (effects (font (size 1.27 1.27) (thickness 0.15)) (justify left bottom) hide)
      )
      (property "ki_description" "Bridge Rectifiers 1000V 1A MMBL DFN3538" (at 0 0 0)
        (effects (font (size 1.27 1.27)) hide)
      )
      (symbol "CD-MMBL110S_1_1"
        (polyline
          (pts
            (xy 2.54 -5.08)
            (xy 3.81 -5.08)
          )
          (stroke (width 0.254) (type default))
          (fill (type none))
        )
        (polyline
          (pts
            (xy 3.81 -10.16)
            (xy 2.54 -10.16)
          )
          (stroke (width 0.254) (type default))
          (fill (type none))
        )
        (polyline
          (pts
            (xy 3.81 -3.81)
            (xy 3.81 -7.62)
          )
          (stroke (width 0.254) (type default))
          (fill (type none))
        )
        (polyline
          (pts
            (xy 3.81 -2.54)
            (xy 3.81 -3.81)
          )
          (stroke (width 0.254) (type default))
          (fill (type none))
        )
        (polyline
          (pts
            (xy 3.81 0)
            (xy 2.54 0)
          )
          (stroke (width 0.254) (type default))
          (fill (type none))
        )
        (polyline
          (pts
            (xy 5.08 -7.62)
            (xy 3.81 -7.62)
          )
          (stroke (width 0.254) (type default))
          (fill (type none))
        )
        (polyline
          (pts
            (xy 5.08 -2.54)
            (xy 3.81 -2.54)
          )
          (stroke (width 0.254) (type default))
          (fill (type none))
        )
        (polyline
          (pts
            (xy 7.62 -6.35)
            (xy 7.62 -8.89)
          )
          (stroke (width 0.254) (type default))
          (fill (type none))
        )
        (polyline
          (pts
            (xy 7.62 -1.27)
            (xy 7.62 -3.81)
          )
          (stroke (width 0.254) (type default))
          (fill (type none))
        )
        (polyline
          (pts
            (xy 8.89 -7.62)
            (xy 7.62 -7.62)
          )
          (stroke (width 0.254) (type default))
          (fill (type none))
        )
        (polyline
          (pts
            (xy 8.89 -2.54)
            (xy 7.62 -2.54)
          )
          (stroke (width 0.254) (type default))
          (fill (type none))
        )
        (polyline
          (pts
            (xy 10.16 -7.62)
            (xy 6.35 -7.62)
          )
          (stroke (width 0.254) (type default))
          (fill (type none))
        )
        (polyline
          (pts
            (xy 10.16 -2.54)
            (xy 6.35 -2.54)
          )
          (stroke (width 0.254) (type default))
          (fill (type none))
        )
        (polyline
          (pts
            (xy 12.7 -7.62)
            (xy 13.97 -7.62)
          )
          (stroke (width 0.254) (type default))
          (fill (type none))
        )
        (polyline
          (pts
            (xy 12.7 -6.35)
            (xy 12.7 -8.89)
          )
          (stroke (width 0.254) (type default))
          (fill (type none))
        )
        (polyline
          (pts
            (xy 12.7 -2.54)
            (xy 13.97 -2.54)
          )
          (stroke (width 0.254) (type default))
          (fill (type none))
        )
        (polyline
          (pts
            (xy 12.7 -1.27)
            (xy 12.7 -3.81)
          )
          (stroke (width 0.254) (type default))
          (fill (type none))
        )
        (polyline
          (pts
            (xy 13.97 -5.08)
            (xy 15.24 -5.08)
          )
          (stroke (width 0.254) (type default))
          (fill (type none))
        )
        (polyline
          (pts
            (xy 13.97 -3.81)
            (xy 13.97 -7.62)
          )
          (stroke (width 0.254) (type default))
          (fill (type none))
        )
        (polyline
          (pts
            (xy 13.97 -2.54)
            (xy 13.97 -3.81)
          )
          (stroke (width 0.254) (type default))
          (fill (type none))
        )
        (polyline
          (pts
            (xy 8.89 -7.62)
            (xy 8.89 -10.16)
            (xy 3.81 -10.16)
          )
          (stroke (width 0.254) (type default))
          (fill (type none))
        )
        (polyline
          (pts
            (xy 8.89 -2.54)
            (xy 8.89 0)
            (xy 3.81 0)
          )
          (stroke (width 0.254) (type default))
          (fill (type none))
        )
        (polyline
          (pts
            (xy 5.08 -6.35)
            (xy 5.08 -8.89)
            (xy 7.62 -7.62)
            (xy 5.08 -6.35)
          )
          (stroke (width 0.254) (type default))
          (fill (type outline))
        )
        (polyline
          (pts
            (xy 5.08 -1.27)
            (xy 5.08 -3.81)
            (xy 7.62 -2.54)
            (xy 5.08 -1.27)
          )
          (stroke (width 0.254) (type default))
          (fill (type outline))
        )
        (polyline
          (pts
            (xy 10.16 -6.35)
            (xy 10.16 -8.89)
            (xy 12.7 -7.62)
            (xy 10.16 -6.35)
          )
          (stroke (width 0.254) (type default))
          (fill (type outline))
        )
        (polyline
          (pts
            (xy 10.16 -1.27)
            (xy 10.16 -3.81)
            (xy 12.7 -2.54)
            (xy 10.16 -1.27)
          )
          (stroke (width 0.254) (type default))
          (fill (type outline))
        )
        (rectangle (start 2.54 1.27) (end 15.24 -11.43)
          (stroke (width 0.254) (type default))
          (fill (type background))
        )
        (pin output line (at 0 -5.08 0) (length 2.54)
          (name "1" (effects (font (size 1.27 1.27))))
          (number "1" (effects (font (size 1.27 1.27))))
        )
        (pin output line (at 17.78 -5.08 180) (length 2.54)
          (name "2" (effects (font (size 1.27 1.27))))
          (number "2" (effects (font (size 1.27 1.27))))
        )
        (pin input line (at 0 0 0) (length 2.54)
          (name "3" (effects (font (size 1.27 1.27))))
          (number "3" (effects (font (size 1.27 1.27))))
        )
        (pin input line (at 0 -10.16 0) (length 2.54)
          (name "4" (effects (font (size 1.27 1.27))))
          (number "4" (effects (font (size 1.27 1.27))))
        )
      )
    )
	(symbol "antmicroTVSDiodes:TPD2E009_SOT-9X3" (pin_names hide) (in_bom yes) (on_board yes)
      (property "Reference" "D" (at 15.24 0 0)
        (effects (font (size 1.27 1.27) (thickness 0.15)) (justify left bottom))
      )
      (property "Value" "TPD2E009_SOT-9X3" (at 15.24 -2.54 0)
        (effects (font (size 1.27 1.27) (thickness 0.15)) (justify left bottom))
      )
      (property "Footprint" "antmicro-footprints:SOT-723" (at 15.24 -5.08 0)
        (effects (font (size 1.27 1.27) (thickness 0.15)) (justify left bottom) hide)
      )
      (property "Datasheet" "https://www.ti.com/lit/ds/symlink/tpd2e009.pdf?ts=1597910439511&ref_url=https%253A%252F%252Fwww.google.com%252F" (at 15.24 -7.62 0)
        (effects (font (size 1.27 1.27) (thickness 0.15)) (justify left bottom) hide)
      )
      (property "MPN" "TPD2E009DRTR" (at 15.24 -10.16 0)
        (effects (font (size 1.27 1.27) (thickness 0.15)) (justify left bottom) hide)
      )
      (property "Manufacturer" "Texas Instruments" (at 15.24 -12.7 0)
        (effects (font (size 1.27 1.27) (thickness 0.15)) (justify left bottom) hide)
      )
      (property "Author" "Antmicro" (at 15.24 -15.24 0)
        (effects (font (size 1.27 1.27) (thickness 0.15)) (justify left bottom) hide)
      )
      (property "License" "Apache-2.0" (at 15.24 -17.78 0)
        (effects (font (size 1.27 1.27) (thickness 0.15)) (justify left bottom) hide)
      )
      (property "ki_description" "2-Channel ESD Solution for High-Speed (6-Gbps) Differential Interface" (at 0 0 0)
        (effects (font (size 1.27 1.27)) hide)
      )
      (symbol "TPD2E009_SOT-9X3_1_1"
        (polyline
          (pts
            (xy 2.54 -2.54)
            (xy 7.62 -2.54)
          )
          (stroke (width 0.254) (type default))
          (fill (type background))
        )
        (polyline
          (pts
            (xy 2.54 0)
            (xy 7.62 0)
          )
          (stroke (width 0.254) (type default))
          (fill (type background))
        )
        (polyline
          (pts
            (xy 7.62 -5.08)
            (xy 2.54 -5.08)
          )
          (stroke (width 0.254) (type default))
          (fill (type background))
        )
        (polyline
          (pts
            (xy 7.62 -5.08)
            (xy 7.62 0)
          )
          (stroke (width 0.254) (type default))
          (fill (type background))
        )
        (polyline
          (pts
            (xy 4.826 -3.175)
            (xy 5.08 -2.921)
            (xy 5.08 -2.159)
            (xy 5.334 -1.905)
          )
          (stroke (width 0.254) (type default))
          (fill (type background))
        )
        (polyline
          (pts
            (xy 4.826 -0.635)
            (xy 5.08 -0.381)
            (xy 5.08 0.381)
            (xy 5.334 0.635)
          )
          (stroke (width 0.254) (type default))
          (fill (type background))
        )
        (polyline
          (pts
            (xy 5.08 -2.54)
            (xy 3.81 -3.175)
            (xy 3.81 -1.905)
            (xy 5.08 -2.54)
          )
          (stroke (width 0.254) (type default))
          (fill (type background))
        )
        (polyline
          (pts
            (xy 5.08 0)
            (xy 3.81 -0.635)
            (xy 3.81 0.635)
            (xy 5.08 0)
          )
          (stroke (width 0.254) (type default))
          (fill (type background))
        )
        (polyline
          (pts
            (xy 5.08 0)
            (xy 6.35 0.635)
            (xy 6.35 -0.635)
            (xy 5.08 0)
          )
          (stroke (width 0.254) (type default))
          (fill (type background))
        )
        (polyline
          (pts
            (xy 6.35 -1.905)
            (xy 6.35 -3.175)
            (xy 5.08 -2.54)
            (xy 6.35 -1.905)
          )
          (stroke (width 0.254) (type default))
          (fill (type background))
        )
        (rectangle (start 2.54 2.54) (end 8.89 -7.62)
          (stroke (width 0.254) (type default))
          (fill (type background))
        )
        (circle (center 7.62 -2.54) (radius 0.254)
          (stroke (width 0.254) (type default))
          (fill (type background))
        )
        (pin passive line (at 0 0 0) (length 2.54)
          (name "1" (effects (font (size 1.27 1.27))))
          (number "1" (effects (font (size 1.27 1.27))))
        )
        (pin passive line (at 0 -2.54 0) (length 2.54)
          (name "2" (effects (font (size 1.27 1.27))))
          (number "2" (effects (font (size 1.27 1.27))))
        )
        (pin passive line (at 0 -5.08 0) (length 2.54)
          (name "3" (effects (font (size 1.27 1.27))))
          (number "3" (effects (font (size 1.27 1.27))))
        )
      )
    )
	(symbol "antmicroTVSDiodes:TPD6E05U06RVZR" (in_bom yes) (on_board yes)
      (property "Reference" "D" (at 22.86 0 0)
        (effects (font (size 1.27 1.27) (thickness 0.15)) (justify left bottom))
      )
      (property "Value" "TPD6E05U06RVZR" (at 22.86 -2.54 0)
        (effects (font (size 1.27 1.27) (thickness 0.15)) (justify left bottom))
      )
      (property "Footprint" "antmicro-footprints:USON-14_3.5X1.3X0.5mm_P0.5mm" (at 22.86 -5.08 0)
        (effects (font (size 1.27 1.27) (thickness 0.15)) (justify left bottom) hide)
      )
      (property "Datasheet" "http://www.ti.com/lit/ds/symlink/tpd6e05u06.pdf" (at 22.86 -7.62 0)
        (effects (font (size 1.27 1.27) (thickness 0.15)) (justify left bottom) hide)
      )
      (property "MPN" "TPD6E05U06RVZR" (at 22.86 -10.16 0)
        (effects (font (size 1.27 1.27) (thickness 0.15)) (justify left bottom) hide)
      )
      (property "Manufacturer" "Texas Instruments" (at 22.86 -12.7 0)
        (effects (font (size 1.27 1.27) (thickness 0.15)) (justify left bottom) hide)
      )
      (property "Author" "Antmicro" (at 22.86 -15.24 0)
        (effects (font (size 1.27 1.27) (thickness 0.15)) (justify left bottom) hide)
      )
      (property "License" "Apache-2.0" (at 22.86 -17.78 0)
        (effects (font (size 1.27 1.27) (thickness 0.15)) (justify left bottom) hide)
      )
      (symbol "TPD6E05U06RVZR_0_0"
        (pin passive line (at 0 0 0) (length 2.54) hide
          (name "D1+" (effects (font (size 1.27 1.27))))
          (number "1" (effects (font (size 1.27 1.27))))
        )
        (pin passive line (at 0 -2.54 0) (length 2.54) hide
          (name "D1-" (effects (font (size 1.27 1.27))))
          (number "2" (effects (font (size 1.27 1.27))))
        )
        (pin passive line (at 0 -7.62 0) (length 2.54) hide
          (name "D2+" (effects (font (size 1.27 1.27))))
          (number "3" (effects (font (size 1.27 1.27))))
        )
        (pin passive line (at 0 -10.16 0) (length 2.54) hide
          (name "D2-" (effects (font (size 1.27 1.27))))
          (number "4" (effects (font (size 1.27 1.27))))
        )
        (pin passive line (at 0 -15.24 0) (length 2.54) hide
          (name "D3+" (effects (font (size 1.27 1.27))))
          (number "6" (effects (font (size 1.27 1.27))))
        )
        (pin passive line (at 0 -17.78 0) (length 2.54) hide
          (name "D3-" (effects (font (size 1.27 1.27))))
          (number "7" (effects (font (size 1.27 1.27))))
        )
      )
      (symbol "TPD6E05U06RVZR_0_1"
        (rectangle (start 2.54 2.54) (end 8.89 -25.4)
          (stroke (width 0) (type default))
          (fill (type background))
        )
      )
      (symbol "TPD6E05U06RVZR_1_1"
        (pin passive line (at 0 -22.86 0) (length 2.54) hide
          (name "GND" (effects (font (size 1.27 1.27))))
          (number "10" (effects (font (size 1.27 1.27))))
        )
        (pin passive line (at 0 -10.16 0) (length 2.54)
          (name "D2-" (effects (font (size 1.27 1.27))))
          (number "11" (effects (font (size 1.27 1.27))))
        )
        (pin passive line (at 0 -7.62 0) (length 2.54)
          (name "D2+" (effects (font (size 1.27 1.27))))
          (number "12" (effects (font (size 1.27 1.27))))
        )
        (pin passive line (at 0 -2.54 0) (length 2.54)
          (name "D1-" (effects (font (size 1.27 1.27))))
          (number "13" (effects (font (size 1.27 1.27))))
        )
        (pin passive line (at 0 0 0) (length 2.54)
          (name "D1+" (effects (font (size 1.27 1.27))))
          (number "14" (effects (font (size 1.27 1.27))))
        )
        (pin power_in line (at 0 -22.86 0) (length 2.54)
          (name "GND" (effects (font (size 1.27 1.27))))
          (number "5" (effects (font (size 1.27 1.27))))
        )
        (pin passive line (at 0 -17.78 0) (length 2.54)
          (name "D3-" (effects (font (size 1.27 1.27))))
          (number "8" (effects (font (size 1.27 1.27))))
        )
        (pin passive line (at 0 -15.24 0) (length 2.54)
          (name "D3+" (effects (font (size 1.27 1.27))))
          (number "9" (effects (font (size 1.27 1.27))))
        )
      )
    )
	(symbol "antmicroTVSDiodes:TPD8S009DSMR" (in_bom yes) (on_board yes)
      (property "Reference" "U" (at 30.48 -2.54 0)
        (effects (font (size 1.27 1.27) (thickness 0.15)) (justify left bottom))
      )
      (property "Value" "TPD8S009DSMR" (at 30.48 -5.08 0)
        (effects (font (size 1.27 1.27) (thickness 0.15)) (justify left bottom))
      )
      (property "Footprint" "antmicro-footprints:R-PDSO-N15" (at 30.48 -7.62 0)
        (effects (font (size 1.27 1.27) (thickness 0.15)) (justify left bottom) hide)
      )
      (property "Datasheet" "https://www.ti.com/lit/ds/symlink/tpd8s009.pdf?ts=1679406571326&ref_url=https%253A%252F%252Fwww.ti.com%252Fproduct%252FTPD8S009%252Fpart-details%252FTPD8S009DSMR" (at 30.48 -10.16 0)
        (effects (font (size 1.27 1.27) (thickness 0.15)) (justify left bottom) hide)
      )
      (property "MPN" "TPD8S009DSMR" (at 30.48 -12.7 0)
        (effects (font (size 1.27 1.27) (thickness 0.15)) (justify left bottom) hide)
      )
      (property "Manufacturer" "Texas Instruments" (at 30.48 -15.24 0)
        (effects (font (size 1.27 1.27) (thickness 0.15)) (justify left bottom) hide)
      )
      (property "Author" "Antmicro" (at 30.48 -17.78 0)
        (effects (font (size 1.27 1.27) (thickness 0.15)) (justify left bottom) hide)
      )
      (property "License" "Apache-2.0" (at 30.48 -20.32 0)
        (effects (font (size 1.27 1.27) (thickness 0.15)) (justify left bottom) hide)
      )
      (symbol "TPD8S009DSMR_1_1"
        (rectangle (start 2.54 -20.32) (end 13.97 2.54)
          (stroke (width 0.254) (type default))
          (fill (type background))
        )
        (pin passive line (at 0 0 0) (length 2.54)
          (name "D0+" (effects (font (size 1.27 1.27))))
          (number "1" (effects (font (size 1.27 1.27))))
        )
        (pin passive line (at 0 -15.24 0) (length 2.54)
          (name "D3+" (effects (font (size 1.27 1.27))))
          (number "10" (effects (font (size 1.27 1.27))))
        )
        (pin passive line (at 16.51 -17.78 180) (length 2.54) hide
          (name "GND" (effects (font (size 1.27 1.27))))
          (number "11" (effects (font (size 1.27 1.27))))
        )
        (pin passive line (at 0 -17.78 0) (length 2.54)
          (name "D3-" (effects (font (size 1.27 1.27))))
          (number "12" (effects (font (size 1.27 1.27))))
        )
        (pin power_in line (at 16.51 0 180) (length 2.54)
          (name "VCC" (effects (font (size 1.27 1.27))))
          (number "13" (effects (font (size 1.27 1.27))))
        )
        (pin no_connect line (at 13.97 -15.24 180) (length 2.54) hide
          (name "NC" (effects (font (size 1.27 1.27))))
          (number "14" (effects (font (size 1.27 1.27))))
        )
        (pin passive line (at 16.51 0 180) (length 2.54) hide
          (name "VCC" (effects (font (size 1.27 1.27))))
          (number "15" (effects (font (size 1.27 1.27))))
        )
        (pin passive line (at 16.51 -17.78 180) (length 2.54)
          (name "GND" (effects (font (size 1.27 1.27))))
          (number "2" (effects (font (size 1.27 1.27))))
        )
        (pin passive line (at 0 -2.54 0) (length 2.54)
          (name "D0-" (effects (font (size 1.27 1.27))))
          (number "3" (effects (font (size 1.27 1.27))))
        )
        (pin passive line (at 0 -5.08 0) (length 2.54)
          (name "D1+" (effects (font (size 1.27 1.27))))
          (number "4" (effects (font (size 1.27 1.27))))
        )
        (pin passive line (at 16.51 -17.78 180) (length 2.54) hide
          (name "GND" (effects (font (size 1.27 1.27))))
          (number "5" (effects (font (size 1.27 1.27))))
        )
        (pin passive line (at 0 -7.62 0) (length 2.54)
          (name "D1-" (effects (font (size 1.27 1.27))))
          (number "6" (effects (font (size 1.27 1.27))))
        )
        (pin passive line (at 0 -10.16 0) (length 2.54)
          (name "D2+" (effects (font (size 1.27 1.27))))
          (number "7" (effects (font (size 1.27 1.27))))
        )
        (pin passive line (at 16.51 -17.78 180) (length 2.54) hide
          (name "GND" (effects (font (size 1.27 1.27))))
          (number "8" (effects (font (size 1.27 1.27))))
        )
        (pin passive line (at 16.51 -17.78 180) (length 2.54) hide
          (name "GND" (effects (font (size 1.27 1.27))))
          (number "8" (effects (font (size 1.27 1.27))))
        )
        (pin passive line (at 0 -12.7 0) (length 2.54)
          (name "D2-" (effects (font (size 1.27 1.27))))
          (number "9" (effects (font (size 1.27 1.27))))
        )
      )
    )
	(symbol "antmicroTestPoints:TP_0.75mm_SMD" (pin_names hide) (in_bom yes) (on_board yes)
      (property "Reference" "TP" (at 15.24 -5.08 0)
        (effects (font (size 1.27 1.27) (thickness 0.15)) (justify left bottom))
      )
      (property "Value" "TP_0.75mm_SMD" (at 15.24 -7.62 0)
        (effects (font (size 1.27 1.27) (thickness 0.15)) (justify left bottom) hide)
      )
      (property "Footprint" "antmicro-footprints:TP_SMD_0.75mm" (at 15.24 -10.16 0)
        (effects (font (size 1.27 1.27) (thickness 0.15)) (justify left bottom) hide)
      )
      (property "Datasheet" "" (at 15.24 -12.7 0)
        (effects (font (size 1.27 1.27) (thickness 0.15)) (justify left bottom) hide)
      )
      (property "MPN" "" (at 0 0 0)
        (effects (font (size 1.27 1.27)) hide)
      )
      (property "Manufacturer" "" (at 0 0 0)
        (effects (font (size 1.27 1.27)) hide)
      )
      (property "Author" "Antmicro" (at 15.24 -15.24 0)
        (effects (font (size 1.27 1.27) (thickness 0.15)) (justify left bottom) hide)
      )
      (property "License" "Apache-2.0" (at 15.24 -17.78 0)
        (effects (font (size 1.27 1.27) (thickness 0.15)) (justify left bottom) hide)
      )
      (property "ki_description" "Test Point 0.75mm" (at 0 0 0)
        (effects (font (size 1.27 1.27)) hide)
      )
      (symbol "TP_0.75mm_SMD_1_1"
        (circle (center 3.175 0) (radius 0.635)
          (stroke (width 0.254) (type default))
          (fill (type none))
        )
        (pin passive line (at 0 0 0) (length 2.54)
          (name "1" (effects (font (size 1.27 1.27))))
          (number "1" (effects (font (size 1.27 1.27))))
        )
      )
    )
	(symbol "antmicroTestPoints:TP_1mm_SMD" (pin_numbers hide) (pin_names hide) (in_bom yes) (on_board yes)
      (property "Reference" "TP" (at 15.24 -5.08 0)
        (effects (font (size 1.27 1.27) (thickness 0.15)) (justify left bottom))
      )
      (property "Value" "TP_1mm_SMD" (at 15.24 -7.62 0)
        (effects (font (size 1.27 1.27) (thickness 0.15)) (justify left bottom) hide)
      )
      (property "Footprint" "antmicro-footprints:TP_SMD_1mm" (at 15.24 -10.16 0)
        (effects (font (size 1.27 1.27) (thickness 0.15)) (justify left bottom) hide)
      )
      (property "Datasheet" "" (at 15.24 -12.7 0)
        (effects (font (size 1.27 1.27) (thickness 0.15)) (justify left bottom) hide)
      )
      (property "MPN" "" (at 0 0 0)
        (effects (font (size 1.27 1.27)) hide)
      )
      (property "Manufacturer" "" (at 0 0 0)
        (effects (font (size 1.27 1.27)) hide)
      )
      (property "Author" "Antmicro" (at 15.24 -15.24 0)
        (effects (font (size 1.27 1.27) (thickness 0.15)) (justify left bottom) hide)
      )
      (property "License" "Apache-2.0" (at 15.24 -17.78 0)
        (effects (font (size 1.27 1.27) (thickness 0.15)) (justify left bottom) hide)
      )
      (property "ki_description" "Test Point 1mm" (at 0 0 0)
        (effects (font (size 1.27 1.27)) hide)
      )
      (symbol "TP_1mm_SMD_1_1"
        (circle (center 3.175 0) (radius 0.635)
          (stroke (width 0.254) (type default))
          (fill (type none))
        )
        (pin passive line (at 0 0 0) (length 2.54)
          (name "1" (effects (font (size 1.27 1.27))))
          (number "1" (effects (font (size 1.27 1.27))))
        )
      )
    )
	(symbol "antmicroTransistorsFETsMOSFETsSingle:BSS138PW" (pin_names (offset 0)) (in_bom yes) (on_board yes)
      (property "Reference" "Q" (at 3.81 -6.35 0)
        (effects (font (size 1.27 1.27) (thickness 0.15)) (justify left bottom))
      )
      (property "Value" "BSS138PW" (at 22.86 -8.89 0)
        (effects (font (size 1.27 1.27) (thickness 0.15)) (justify left bottom))
      )
      (property "Footprint" "antmicro-footprints:SC70-3" (at 22.86 -11.43 0)
        (effects (font (size 1.27 1.27) (thickness 0.15)) (justify left bottom) hide)
      )
      (property "Datasheet" "https://assets.nexperia.com/documents/data-sheet/BSS138PW.pdf" (at 22.86 -13.97 0)
        (effects (font (size 1.27 1.27) (thickness 0.15)) (justify left bottom) hide)
      )
      (property "MPN" "BSS138PW" (at 22.86 -16.51 0)
        (effects (font (size 1.27 1.27) (thickness 0.15)) (justify left bottom) hide)
      )
      (property "Manufacturer" "Nexperia" (at 22.86 -19.05 0)
        (effects (font (size 1.27 1.27) (thickness 0.15)) (justify left bottom) hide)
      )
      (property "Author" "Antmicro" (at 22.86 -21.59 0)
        (effects (font (size 1.27 1.27) (thickness 0.15)) (justify left bottom) hide)
      )
      (property "License" "Apache-2.0" (at 22.86 -24.13 0)
        (effects (font (size 1.27 1.27) (thickness 0.15)) (justify left bottom) hide)
      )
      (property "ki_keywords" "n-channel enhancement mosfet sc70 sc-70 sot-323 sot323" (at 0 0 0)
        (effects (font (size 1.27 1.27)) hide)
      )
      (property "ki_description" "60 V, 320 mA N-channel enhancement mode Trench MOSFET, SC-70-3 aka SOT-323 package" (at 0 0 0)
        (effects (font (size 1.27 1.27)) hide)
      )
      (symbol "BSS138PW_1_1"
        (polyline
          (pts
            (xy 5.08 1.143)
            (xy 5.08 0.635)
          )
          (stroke (width 0.254) (type default))
          (fill (type background))
        )
        (polyline
          (pts
            (xy 5.08 1.143)
            (xy 5.08 1.651)
          )
          (stroke (width 0.254) (type default))
          (fill (type background))
        )
        (polyline
          (pts
            (xy 5.08 2.54)
            (xy 5.08 2.032)
          )
          (stroke (width 0.254) (type default))
          (fill (type background))
        )
        (polyline
          (pts
            (xy 5.08 2.54)
            (xy 5.08 3.048)
          )
          (stroke (width 0.254) (type default))
          (fill (type background))
        )
        (polyline
          (pts
            (xy 5.08 4.445)
            (xy 5.08 3.429)
          )
          (stroke (width 0.254) (type default))
          (fill (type background))
        )
        (polyline
          (pts
            (xy 7.62 1.143)
            (xy 5.08 1.143)
          )
          (stroke (width 0.254) (type default))
          (fill (type background))
        )
        (polyline
          (pts
            (xy 9.144 3.048)
            (xy 8.128 3.048)
          )
          (stroke (width 0.254) (type default))
          (fill (type background))
        )
        (polyline
          (pts
            (xy 2.54 0)
            (xy 4.572 0)
            (xy 4.572 3.937)
          )
          (stroke (width 0.254) (type default))
          (fill (type none))
        )
        (polyline
          (pts
            (xy 7.62 -1.27)
            (xy 7.62 2.54)
            (xy 5.08 2.54)
          )
          (stroke (width 0.254) (type default))
          (fill (type background))
        )
        (polyline
          (pts
            (xy 7.62 6.35)
            (xy 7.62 3.937)
            (xy 5.08 3.937)
          )
          (stroke (width 0.254) (type default))
          (fill (type background))
        )
        (polyline
          (pts
            (xy 5.08 2.54)
            (xy 5.842 3.048)
            (xy 5.842 2.032)
            (xy 5.08 2.54)
          )
          (stroke (width 0.254) (type default))
          (fill (type outline))
        )
        (polyline
          (pts
            (xy 8.636 3.048)
            (xy 8.128 2.286)
            (xy 9.144 2.286)
            (xy 8.636 3.048)
          )
          (stroke (width 0.254) (type default))
          (fill (type outline))
        )
        (polyline
          (pts
            (xy 7.493 0.635)
            (xy 8.636 0.635)
            (xy 8.636 3.937)
            (xy 8.636 4.445)
            (xy 7.493 4.445)
          )
          (stroke (width 0.254) (type default))
          (fill (type background))
        )
        (circle (center 6.35 2.54) (radius 3.302)
          (stroke (width 0.254) (type default))
          (fill (type background))
        )
        (circle (center 7.62 0.635) (radius 0.127)
          (stroke (width 0.254) (type default))
          (fill (type background))
        )
        (circle (center 7.62 1.143) (radius 0.127)
          (stroke (width 0.254) (type default))
          (fill (type background))
        )
        (circle (center 7.62 4.445) (radius 0.127)
          (stroke (width 0.254) (type default))
          (fill (type background))
        )
        (pin bidirectional line (at 0 0 0) (length 2.54)
          (name "G" (effects (font (size 1.27 1.27))))
          (number "1" (effects (font (size 1.27 1.27))))
        )
        (pin bidirectional line (at 7.62 -3.81 90) (length 2.54)
          (name "S" (effects (font (size 1.27 1.27))))
          (number "2" (effects (font (size 1.27 1.27))))
        )
        (pin bidirectional line (at 7.62 8.89 270) (length 2.54)
          (name "D" (effects (font (size 1.27 1.27))))
          (number "3" (effects (font (size 1.27 1.27))))
        )
      )
    )
	(symbol "antmicroVideoConnectors:HDMI-A_WE_685119134923" (in_bom yes) (on_board yes)
      (property "Reference" "J" (at 35.56 -2.54 0)
        (effects (font (size 1.27 1.27) (thickness 0.15)) (justify left bottom))
      )
      (property "Value" "HDMI-A_WE_685119134923" (at 35.56 -5.08 0)
        (effects (font (size 1.27 1.27) (thickness 0.15)) (justify left bottom))
      )
      (property "Footprint" "antmicro-footprints:HDMI-A_Receptacle_WE_685119134923" (at 35.56 -7.62 0)
        (effects (font (size 1.27 1.27) (thickness 0.15)) (justify left bottom) hide)
      )
      (property "Datasheet" "https://www.we-online.com/components/products/datasheet/685119134923.pdf" (at 35.56 -10.16 0)
        (effects (font (size 1.27 1.27) (thickness 0.15)) (justify left bottom) hide)
      )
      (property "MPN" "685119134923" (at 35.56 -12.7 0)
        (effects (font (size 1.27 1.27) (thickness 0.15)) (justify left bottom) hide)
      )
      (property "Manufacturer" "Würth Elektronik" (at 35.56 -15.24 0)
        (effects (font (size 1.27 1.27) (thickness 0.15)) (justify left bottom) hide)
      )
      (property "Author" "Antmicro" (at 35.56 -17.78 0)
        (effects (font (size 1.27 1.27) (thickness 0.15)) (justify left bottom) hide)
      )
      (property "License" "Apache-2.0" (at 35.56 -20.32 0)
        (effects (font (size 1.27 1.27) (thickness 0.15)) (justify left bottom) hide)
      )
      (property "ki_keywords" "HDMI, CONNECTOR, THT" (at 0 0 0)
        (effects (font (size 1.27 1.27)) hide)
      )
      (property "ki_description" "HDMI Receptacle Connector 19 Position Surface Mount, Right Angle; Through Hole" (at 0 0 0)
        (effects (font (size 1.27 1.27)) hide)
      )
      (property "ki_fp_filters" "685119134923" (at 0 0 0)
        (effects (font (size 1.27 1.27)) hide)
      )
      (symbol "HDMI-A_WE_685119134923_0_0"
        (polyline
          (pts
            (xy 22.098 0)
            (xy 22.098 1.524)
          )
          (stroke (width 0.635) (type default))
          (fill (type none))
        )
        (polyline
          (pts
            (xy 13.97 0)
            (xy 13.97 1.524)
            (xy 13.97 0.762)
            (xy 15.875 0.762)
            (xy 15.875 1.524)
            (xy 15.875 0)
          )
          (stroke (width 0.635) (type default))
          (fill (type none))
        )
        (polyline
          (pts
            (xy 16.637 1.524)
            (xy 18.288 1.524)
            (xy 18.542 1.27)
            (xy 18.542 0.254)
            (xy 18.288 0)
            (xy 16.637 0)
            (xy 16.637 0.762)
          )
          (stroke (width 0.635) (type default))
          (fill (type none))
        )
      )
      (symbol "HDMI-A_WE_685119134923_0_1"
        (polyline
          (pts
            (xy 10.16 -15.24)
            (xy 13.97 -15.24)
            (xy 15.875 -17.145)
            (xy 15.875 -28.575)
            (xy 13.97 -30.48)
            (xy 10.16 -30.48)
            (xy 10.16 -15.24)
          )
          (stroke (width 0.635) (type default))
          (fill (type none))
        )
        (polyline
          (pts
            (xy 12.065 -16.51)
            (xy 13.335 -16.51)
            (xy 13.97 -17.145)
            (xy 13.97 -28.575)
            (xy 13.335 -29.21)
            (xy 12.065 -29.21)
            (xy 12.065 -16.51)
          )
          (stroke (width 0.254) (type default))
          (fill (type outline))
        )
        (polyline
          (pts
            (xy 19.304 0)
            (xy 19.304 1.524)
            (xy 20.32 1.524)
            (xy 20.32 0)
            (xy 20.32 1.524)
            (xy 21.082 1.524)
            (xy 21.336 1.27)
            (xy 21.336 0)
          )
          (stroke (width 0.635) (type default))
          (fill (type none))
        )
      )
      (symbol "HDMI-A_WE_685119134923_1_1"
        (rectangle (start 2.54 2.54) (end 22.86 -53.34)
          (stroke (width 0.254) (type default))
          (fill (type background))
        )
        (pin bidirectional line (at 0 0 0) (length 2.54)
          (name "D2+" (effects (font (size 1.27 1.27))))
          (number "1" (effects (font (size 1.27 1.27))))
        )
        (pin bidirectional line (at 0 -22.86 0) (length 2.54)
          (name "CK+" (effects (font (size 1.27 1.27))))
          (number "10" (effects (font (size 1.27 1.27))))
        )
        (pin passive line (at 25.4 -45.72 180) (length 2.54)
          (name "CKS" (effects (font (size 1.27 1.27))))
          (number "11" (effects (font (size 1.27 1.27))))
        )
        (pin bidirectional line (at 0 -25.4 0) (length 2.54)
          (name "CK-" (effects (font (size 1.27 1.27))))
          (number "12" (effects (font (size 1.27 1.27))))
        )
        (pin bidirectional line (at 0 -38.1 0) (length 2.54)
          (name "CEC" (effects (font (size 1.27 1.27))))
          (number "13" (effects (font (size 1.27 1.27))))
        )
        (pin bidirectional line (at 0 -45.72 0) (length 2.54)
          (name "UTILITY/HEAC+" (effects (font (size 1.27 1.27))))
          (number "14" (effects (font (size 1.27 1.27))))
          (alternate "HEAC+" passive line)
          (alternate "UTILITY" passive line)
        )
        (pin bidirectional line (at 0 -30.48 0) (length 2.54)
          (name "SCL" (effects (font (size 1.27 1.27))))
          (number "15" (effects (font (size 1.27 1.27))))
        )
        (pin bidirectional line (at 0 -33.02 0) (length 2.54)
          (name "SDA" (effects (font (size 1.27 1.27))))
          (number "16" (effects (font (size 1.27 1.27))))
        )
        (pin power_in line (at 25.4 -48.26 180) (length 2.54)
          (name "GND" (effects (font (size 1.27 1.27))))
          (number "17" (effects (font (size 1.27 1.27))))
        )
        (pin power_in line (at 0 -50.8 0) (length 2.54)
          (name "+5V" (effects (font (size 1.27 1.27))))
          (number "18" (effects (font (size 1.27 1.27))))
        )
        (pin bidirectional line (at 0 -43.18 0) (length 2.54)
          (name "HPD/HEAC-" (effects (font (size 1.27 1.27))))
          (number "19" (effects (font (size 1.27 1.27))))
          (alternate "HEAC-" passive line)
          (alternate "HPD" passive line)
        )
        (pin passive line (at 25.4 -38.1 180) (length 2.54)
          (name "D2S" (effects (font (size 1.27 1.27))))
          (number "2" (effects (font (size 1.27 1.27))))
        )
        (pin bidirectional line (at 0 -2.54 0) (length 2.54)
          (name "D2-" (effects (font (size 1.27 1.27))))
          (number "3" (effects (font (size 1.27 1.27))))
        )
        (pin bidirectional line (at 0 -7.62 0) (length 2.54)
          (name "D1+" (effects (font (size 1.27 1.27))))
          (number "4" (effects (font (size 1.27 1.27))))
        )
        (pin passive line (at 25.4 -40.64 180) (length 2.54)
          (name "D1S" (effects (font (size 1.27 1.27))))
          (number "5" (effects (font (size 1.27 1.27))))
        )
        (pin bidirectional line (at 0 -10.16 0) (length 2.54)
          (name "D1-" (effects (font (size 1.27 1.27))))
          (number "6" (effects (font (size 1.27 1.27))))
        )
        (pin bidirectional line (at 0 -15.24 0) (length 2.54)
          (name "D0+" (effects (font (size 1.27 1.27))))
          (number "7" (effects (font (size 1.27 1.27))))
        )
        (pin passive line (at 25.4 -43.18 180) (length 2.54)
          (name "D0S" (effects (font (size 1.27 1.27))))
          (number "8" (effects (font (size 1.27 1.27))))
        )
        (pin bidirectional line (at 0 -17.78 0) (length 2.54)
          (name "D0-" (effects (font (size 1.27 1.27))))
          (number "9" (effects (font (size 1.27 1.27))))
        )
        (pin passive line (at 25.4 -50.8 180) (length 2.54)
          (name "SH" (effects (font (size 1.27 1.27))))
          (number "SH" (effects (font (size 1.27 1.27))))
        )
      )
    )
	(symbol "antmicropower:GND" (power) (pin_numbers hide) (pin_names hide) (in_bom yes) (on_board yes)
      (property "Reference" "#PWR" (at 8.89 -2.54 0)
        (effects (font (size 1.27 1.27) (thickness 0.15)) (justify left bottom) hide)
      )
      (property "Value" "GND" (at 8.89 -5.08 0)
        (effects (font (size 1.27 1.27) (thickness 0.15)) (justify left bottom))
      )
      (property "Footprint" "" (at 8.89 -7.62 0)
        (effects (font (size 1.27 1.27) (thickness 0.15)) (justify left bottom) hide)
      )
      (property "Datasheet" "" (at 8.89 -12.7 0)
        (effects (font (size 1.27 1.27) (thickness 0.15)) (justify left bottom) hide)
      )
      (property "Author" "Antmicro" (at 8.89 -7.62 0)
        (effects (font (size 1.27 1.27) (thickness 0.15)) (justify left bottom) hide)
      )
      (property "License" "Apache-2.0" (at 8.89 -10.16 0)
        (effects (font (size 1.27 1.27) (thickness 0.15)) (justify left bottom) hide)
      )
      (symbol "GND_1_1"
        (polyline
          (pts
            (xy 0 0)
            (xy 0 -1.27)
            (xy 1.27 -1.27)
            (xy 0 -2.54)
            (xy -1.27 -1.27)
            (xy 0 -1.27)
          )
          (stroke (width 0) (type default))
          (fill (type none))
        )
        (pin power_in line (at 0 0 270) (length 0)
          (name "GND" (effects (font (size 1.27 1.27))))
          (number "1" (effects (font (size 1.27 1.27))))
        )
      )
    )
	(symbol "antmicropower:GND1" (power) (pin_names (offset 0)) (in_bom yes) (on_board yes)
      (property "Reference" "#PWR" (at 0 -6.35 0)
        (effects (font (size 1.27 1.27)) hide)
      )
      (property "Value" "GND1" (at 0 -3.81 0)
        (effects (font (size 1.27 1.27)))
      )
      (property "Footprint" "" (at 0 0 0)
        (effects (font (size 1.27 1.27)) hide)
      )
      (property "Datasheet" "" (at 0 0 0)
        (effects (font (size 1.27 1.27)) hide)
      )
      (symbol "GND1_0_1"
        (polyline
          (pts
            (xy 0 0)
            (xy 0 -1.27)
            (xy 1.27 -1.27)
            (xy 0 -2.54)
            (xy -1.27 -1.27)
            (xy 0 -1.27)
          )
          (stroke (width 0) (type default))
          (fill (type none))
        )
      )
      (symbol "GND1_1_1"
        (pin power_in line (at 0 0 270) (length 0) hide
          (name "GND1" (effects (font (size 1.27 1.27))))
          (number "1" (effects (font (size 1.27 1.27))))
        )
      )
    )
	(symbol "antmicropower:GNDD" (power) (pin_numbers hide) (pin_names hide) (in_bom yes) (on_board yes)
      (property "Reference" "#PWR" (at 15.24 -2.54 0)
        (effects (font (size 1.27 1.27) (thickness 0.15)) (justify left bottom) hide)
      )
      (property "Value" "GNDD" (at 15.24 -5.08 0)
        (effects (font (size 1.27 1.27) (thickness 0.15)) (justify left bottom))
      )
      (property "Footprint" "" (at 15.24 -10.16 0)
        (effects (font (size 1.27 1.27) (thickness 0.15)) (justify left bottom) hide)
      )
      (property "Datasheet" "" (at 15.24 -12.7 0)
        (effects (font (size 1.27 1.27) (thickness 0.15)) (justify left bottom) hide)
      )
      (property "Author" "Antmicro" (at 15.24 -7.62 0)
        (effects (font (size 1.27 1.27) (thickness 0.15)) (justify left bottom) hide)
      )
      (property "License" "Apache-2.0" (at 15.24 -10.16 0)
        (effects (font (size 1.27 1.27) (thickness 0.15)) (justify left bottom) hide)
      )
      (symbol "GNDD_1_1"
        (rectangle (start -1.27 -1.524) (end 1.27 -2.032)
          (stroke (width 0) (type default))
          (fill (type outline))
        )
        (polyline
          (pts
            (xy 0 0)
            (xy 0 -1.524)
          )
          (stroke (width 0) (type default))
          (fill (type background))
        )
        (pin power_in line (at 0 0 270) (length 0)
          (name "GNDD" (effects (font (size 1.27 1.27))))
          (number "1" (effects (font (size 1.27 1.27))))
        )
      )
    )
	(symbol "antmicropower:GNDS" (power) (pin_names (offset 0)) (in_bom yes) (on_board yes)
      (property "Reference" "#PWR" (at 0 -6.35 0)
        (effects (font (size 1.27 1.27)) hide)
      )
      (property "Value" "GNDS" (at 0 -3.81 0)
        (effects (font (size 1.27 1.27)))
      )
      (property "Footprint" "" (at 0 0 0)
        (effects (font (size 1.27 1.27)) hide)
      )
      (property "Datasheet" "" (at 0 0 0)
        (effects (font (size 1.27 1.27)) hide)
      )
      (symbol "GNDS_0_1"
        (polyline
          (pts
            (xy 0 0)
            (xy 0 -1.27)
            (xy 1.27 -1.27)
            (xy 0 -2.54)
            (xy -1.27 -1.27)
            (xy 0 -1.27)
          )
          (stroke (width 0) (type default))
          (fill (type none))
        )
      )
      (symbol "GNDS_1_1"
        (pin power_in line (at 0 0 270) (length 0) hide
          (name "GNDS" (effects (font (size 1.27 1.27))))
          (number "1" (effects (font (size 1.27 1.27))))
        )
      )
    )
	(symbol "data-center-rdimm-ddr4-tester:AP62301WU-7" (in_bom yes) (on_board yes)
      (property "Reference" "U" (at 35.56 7.62 0)
        (effects (font (size 1.27 1.27) (thickness 0.15)) (justify left bottom))
      )
      (property "Value" "AP62301WU-7" (at 35.56 5.08 0)
        (effects (font (size 1.27 1.27) (thickness 0.15)) (justify left bottom))
      )
      (property "Footprint" "data-center-rdimm-ddr4-tester-footprints:AP62301WU-7-TSOT23-6" (at 35.56 2.54 0)
        (effects (font (size 1.27 1.27) (thickness 0.15)) (justify left bottom) hide)
      )
      (property "Datasheet" "https://www.diodes.com/assets/Datasheets/AP62300_AP62301_AP62300T.pdf" (at 35.56 0 0)
        (effects (font (size 1.27 1.27) (thickness 0.15)) (justify left bottom) hide)
      )
      (property "MPN" "AP62301WU-7" (at 35.56 -2.54 0)
        (effects (font (size 1.27 1.27) (thickness 0.15)) (justify left bottom) hide)
      )
      (property "Manufacturer" "Diodes Incorporated" (at 35.56 -5.08 0)
        (effects (font (size 1.27 1.27) (thickness 0.15)) (justify left bottom) hide)
      )
      (property "Author" "Antmicro" (at 35.56 -7.62 0)
        (effects (font (size 1.27 1.27) (thickness 0.15)) (justify left bottom) hide)
      )
      (property "License" "Apache-2.0" (at 35.56 -10.16 0)
        (effects (font (size 1.27 1.27) (thickness 0.15)) (justify left bottom) hide)
      )
      (symbol "AP62301WU-7_1_1"
        (rectangle (start 2.54 12.7) (end 17.78 -2.54)
          (stroke (width 0.254) (type default))
          (fill (type background))
        )
        (pin power_in line (at 0 0 0) (length 2.54)
          (name "GND" (effects (font (size 1.27 1.27))))
          (number "1" (effects (font (size 1.27 1.27))))
        )
        (pin power_out line (at 20.32 10.16 180) (length 2.54)
          (name "SW" (effects (font (size 1.27 1.27))))
          (number "2" (effects (font (size 1.27 1.27))))
        )
        (pin power_in line (at 0 10.16 0) (length 2.54)
          (name "VIN" (effects (font (size 1.27 1.27))))
          (number "3" (effects (font (size 1.27 1.27))))
        )
        (pin input line (at 20.32 0 180) (length 2.54)
          (name "FB" (effects (font (size 1.27 1.27))))
          (number "4" (effects (font (size 1.27 1.27))))
        )
        (pin input line (at 0 5.08 0) (length 2.54)
          (name "EN" (effects (font (size 1.27 1.27))))
          (number "5" (effects (font (size 1.27 1.27))))
        )
        (pin output line (at 20.32 5.08 180) (length 2.54)
          (name "BST" (effects (font (size 1.27 1.27))))
          (number "6" (effects (font (size 1.27 1.27))))
        )
      )
    )
	(symbol "data-center-rdimm-ddr4-tester:C_100n_0201_10" (pin_numbers hide) (pin_names hide) (in_bom yes) (on_board yes)
      (property "Reference" "C" (at 20.32 -5.08 0)
        (effects (font (size 1.27 1.27) (thickness 0.15)) (justify left bottom))
      )
      (property "Value" "C_100n_0201_10" (at 20.32 -10.16 0)
        (effects (font (size 1.27 1.27) (thickness 0.15)) (justify left bottom) hide)
      )
      (property "Footprint" "data-center-rdimm-ddr4-tester-footprints:C_0201" (at 20.32 -12.7 0)
        (effects (font (size 1.27 1.27) (thickness 0.15)) (justify left bottom) hide)
      )
      (property "Datasheet" " " (at 20.32 -15.24 0)
        (effects (font (size 1.27 1.27) (thickness 0.15)) (justify left bottom) hide)
      )
      (property "MPN" "CC0201KRX6S5BB104" (at 20.32 -17.78 0)
        (effects (font (size 1.27 1.27) (thickness 0.15)) (justify left bottom) hide)
      )
      (property "Manufacturer" "Yaego" (at 20.32 -20.32 0)
        (effects (font (size 1.27 1.27) (thickness 0.15)) (justify left bottom) hide)
      )
      (property "License" "Apache-2.0" (at 20.32 -22.86 0)
        (effects (font (size 1.27 1.27) (thickness 0.15)) (justify left bottom) hide)
      )
      (property "Author" "Antmicro" (at 20.32 -25.4 0)
        (effects (font (size 1.27 1.27) (thickness 0.15)) (justify left bottom) hide)
      )
      (property "Val" "100n" (at 20.32 -7.62 0)
        (effects (font (size 1.27 1.27) (thickness 0.15)) (justify left bottom))
      )
      (property "Voltage" "" (at 20.32 -27.94 0)
        (effects (font (size 1.27 1.27)) (justify left bottom) hide)
      )
      (property "Dielectric" "" (at 20.32 -30.48 0)
        (effects (font (size 1.27 1.27)) (justify left bottom) hide)
      )
      (property "ki_description" " " (at 0 0 0)
        (effects (font (size 1.27 1.27)) hide)
      )
      (symbol "C_100n_0201_10_0_1"
        (polyline
          (pts
            (xy 2.032 -1.524)
            (xy 2.032 1.524)
          )
          (stroke (width 0.3048) (type default))
          (fill (type none))
        )
        (polyline
          (pts
            (xy 3.048 -1.524)
            (xy 3.048 1.524)
          )
          (stroke (width 0.3302) (type default))
          (fill (type none))
        )
      )
      (symbol "C_100n_0201_10_1_1"
        (pin passive line (at 0 0 0) (length 2.032)
          (name "~" (effects (font (size 1.27 1.27))))
          (number "1" (effects (font (size 1.27 1.27))))
        )
        (pin passive line (at 5.08 0 180) (length 2.032)
          (name "~" (effects (font (size 1.27 1.27))))
          (number "2" (effects (font (size 1.27 1.27))))
        )
      )
    )
	(symbol "data-center-rdimm-ddr4-tester:C_100n_0201_11" (pin_numbers hide) (pin_names hide) (in_bom yes) (on_board yes)
      (property "Reference" "C" (at 20.32 -5.08 0)
        (effects (font (size 1.27 1.27) (thickness 0.15)) (justify left bottom))
      )
      (property "Value" "C_100n_0201_11" (at 20.32 -10.16 0)
        (effects (font (size 1.27 1.27) (thickness 0.15)) (justify left bottom) hide)
      )
      (property "Footprint" "data-center-rdimm-ddr4-tester-footprints:C_0201" (at 20.32 -12.7 0)
        (effects (font (size 1.27 1.27) (thickness 0.15)) (justify left bottom) hide)
      )
      (property "Datasheet" " " (at 20.32 -15.24 0)
        (effects (font (size 1.27 1.27) (thickness 0.15)) (justify left bottom) hide)
      )
      (property "MPN" "CC0201KRX6S5BB104" (at 20.32 -17.78 0)
        (effects (font (size 1.27 1.27) (thickness 0.15)) (justify left bottom) hide)
      )
      (property "Manufacturer" "Yaego" (at 20.32 -20.32 0)
        (effects (font (size 1.27 1.27) (thickness 0.15)) (justify left bottom) hide)
      )
      (property "License" "Apache-2.0" (at 20.32 -22.86 0)
        (effects (font (size 1.27 1.27) (thickness 0.15)) (justify left bottom) hide)
      )
      (property "Author" "Antmicro" (at 20.32 -25.4 0)
        (effects (font (size 1.27 1.27) (thickness 0.15)) (justify left bottom) hide)
      )
      (property "Val" "100n" (at 20.32 -7.62 0)
        (effects (font (size 1.27 1.27) (thickness 0.15)) (justify left bottom))
      )
      (property "Voltage" "" (at 20.32 -27.94 0)
        (effects (font (size 1.27 1.27)) (justify left bottom) hide)
      )
      (property "Dielectric" "" (at 20.32 -30.48 0)
        (effects (font (size 1.27 1.27)) (justify left bottom) hide)
      )
      (property "ki_description" " " (at 0 0 0)
        (effects (font (size 1.27 1.27)) hide)
      )
      (symbol "C_100n_0201_11_0_1"
        (polyline
          (pts
            (xy 2.032 -1.524)
            (xy 2.032 1.524)
          )
          (stroke (width 0.3048) (type default))
          (fill (type none))
        )
        (polyline
          (pts
            (xy 3.048 -1.524)
            (xy 3.048 1.524)
          )
          (stroke (width 0.3302) (type default))
          (fill (type none))
        )
      )
      (symbol "C_100n_0201_11_1_1"
        (pin passive line (at 0 0 0) (length 2.032)
          (name "~" (effects (font (size 1.27 1.27))))
          (number "1" (effects (font (size 1.27 1.27))))
        )
        (pin passive line (at 5.08 0 180) (length 2.032)
          (name "~" (effects (font (size 1.27 1.27))))
          (number "2" (effects (font (size 1.27 1.27))))
        )
      )
    )
	(symbol "data-center-rdimm-ddr4-tester:C_100n_0201_12" (pin_numbers hide) (pin_names hide) (in_bom yes) (on_board yes)
      (property "Reference" "C" (at 20.32 -5.08 0)
        (effects (font (size 1.27 1.27) (thickness 0.15)) (justify left bottom))
      )
      (property "Value" "C_100n_0201_12" (at 20.32 -10.16 0)
        (effects (font (size 1.27 1.27) (thickness 0.15)) (justify left bottom) hide)
      )
      (property "Footprint" "data-center-rdimm-ddr4-tester-footprints:C_0201" (at 20.32 -12.7 0)
        (effects (font (size 1.27 1.27) (thickness 0.15)) (justify left bottom) hide)
      )
      (property "Datasheet" " " (at 20.32 -15.24 0)
        (effects (font (size 1.27 1.27) (thickness 0.15)) (justify left bottom) hide)
      )
      (property "MPN" "CC0201KRX6S5BB104" (at 20.32 -17.78 0)
        (effects (font (size 1.27 1.27) (thickness 0.15)) (justify left bottom) hide)
      )
      (property "Manufacturer" "Yaego" (at 20.32 -20.32 0)
        (effects (font (size 1.27 1.27) (thickness 0.15)) (justify left bottom) hide)
      )
      (property "License" "Apache-2.0" (at 20.32 -22.86 0)
        (effects (font (size 1.27 1.27) (thickness 0.15)) (justify left bottom) hide)
      )
      (property "Author" "Antmicro" (at 20.32 -25.4 0)
        (effects (font (size 1.27 1.27) (thickness 0.15)) (justify left bottom) hide)
      )
      (property "Val" "100n" (at 20.32 -7.62 0)
        (effects (font (size 1.27 1.27) (thickness 0.15)) (justify left bottom))
      )
      (property "Voltage" "" (at 20.32 -27.94 0)
        (effects (font (size 1.27 1.27)) (justify left bottom) hide)
      )
      (property "Dielectric" "" (at 20.32 -30.48 0)
        (effects (font (size 1.27 1.27)) (justify left bottom) hide)
      )
      (property "ki_description" " " (at 0 0 0)
        (effects (font (size 1.27 1.27)) hide)
      )
      (symbol "C_100n_0201_12_0_1"
        (polyline
          (pts
            (xy 2.032 -1.524)
            (xy 2.032 1.524)
          )
          (stroke (width 0.3048) (type default))
          (fill (type none))
        )
        (polyline
          (pts
            (xy 3.048 -1.524)
            (xy 3.048 1.524)
          )
          (stroke (width 0.3302) (type default))
          (fill (type none))
        )
      )
      (symbol "C_100n_0201_12_1_1"
        (pin passive line (at 0 0 0) (length 2.032)
          (name "~" (effects (font (size 1.27 1.27))))
          (number "1" (effects (font (size 1.27 1.27))))
        )
        (pin passive line (at 5.08 0 180) (length 2.032)
          (name "~" (effects (font (size 1.27 1.27))))
          (number "2" (effects (font (size 1.27 1.27))))
        )
      )
    )
	(symbol "data-center-rdimm-ddr4-tester:C_100n_0201_13" (pin_numbers hide) (pin_names hide) (in_bom yes) (on_board yes)
      (property "Reference" "C" (at 20.32 -5.08 0)
        (effects (font (size 1.27 1.27) (thickness 0.15)) (justify left bottom))
      )
      (property "Value" "C_100n_0201_13" (at 20.32 -10.16 0)
        (effects (font (size 1.27 1.27) (thickness 0.15)) (justify left bottom) hide)
      )
      (property "Footprint" "data-center-rdimm-ddr4-tester-footprints:C_0201" (at 20.32 -12.7 0)
        (effects (font (size 1.27 1.27) (thickness 0.15)) (justify left bottom) hide)
      )
      (property "Datasheet" " " (at 20.32 -15.24 0)
        (effects (font (size 1.27 1.27) (thickness 0.15)) (justify left bottom) hide)
      )
      (property "MPN" "CC0201KRX6S5BB104" (at 20.32 -17.78 0)
        (effects (font (size 1.27 1.27) (thickness 0.15)) (justify left bottom) hide)
      )
      (property "Manufacturer" "Yaego" (at 20.32 -20.32 0)
        (effects (font (size 1.27 1.27) (thickness 0.15)) (justify left bottom) hide)
      )
      (property "License" "Apache-2.0" (at 20.32 -22.86 0)
        (effects (font (size 1.27 1.27) (thickness 0.15)) (justify left bottom) hide)
      )
      (property "Author" "Antmicro" (at 20.32 -25.4 0)
        (effects (font (size 1.27 1.27) (thickness 0.15)) (justify left bottom) hide)
      )
      (property "Val" "100n" (at 20.32 -7.62 0)
        (effects (font (size 1.27 1.27) (thickness 0.15)) (justify left bottom))
      )
      (property "Voltage" "" (at 20.32 -27.94 0)
        (effects (font (size 1.27 1.27)) (justify left bottom) hide)
      )
      (property "Dielectric" "" (at 20.32 -30.48 0)
        (effects (font (size 1.27 1.27)) (justify left bottom) hide)
      )
      (property "ki_description" " " (at 0 0 0)
        (effects (font (size 1.27 1.27)) hide)
      )
      (symbol "C_100n_0201_13_0_1"
        (polyline
          (pts
            (xy 2.032 -1.524)
            (xy 2.032 1.524)
          )
          (stroke (width 0.3048) (type default))
          (fill (type none))
        )
        (polyline
          (pts
            (xy 3.048 -1.524)
            (xy 3.048 1.524)
          )
          (stroke (width 0.3302) (type default))
          (fill (type none))
        )
      )
      (symbol "C_100n_0201_13_1_1"
        (pin passive line (at 0 0 0) (length 2.032)
          (name "~" (effects (font (size 1.27 1.27))))
          (number "1" (effects (font (size 1.27 1.27))))
        )
        (pin passive line (at 5.08 0 180) (length 2.032)
          (name "~" (effects (font (size 1.27 1.27))))
          (number "2" (effects (font (size 1.27 1.27))))
        )
      )
    )
	(symbol "data-center-rdimm-ddr4-tester:C_100n_0201_14" (pin_numbers hide) (pin_names hide) (in_bom yes) (on_board yes)
      (property "Reference" "C" (at 20.32 -5.08 0)
        (effects (font (size 1.27 1.27) (thickness 0.15)) (justify left bottom))
      )
      (property "Value" "C_100n_0201_14" (at 20.32 -10.16 0)
        (effects (font (size 1.27 1.27) (thickness 0.15)) (justify left bottom) hide)
      )
      (property "Footprint" "data-center-rdimm-ddr4-tester-footprints:C_0201" (at 20.32 -12.7 0)
        (effects (font (size 1.27 1.27) (thickness 0.15)) (justify left bottom) hide)
      )
      (property "Datasheet" " " (at 20.32 -15.24 0)
        (effects (font (size 1.27 1.27) (thickness 0.15)) (justify left bottom) hide)
      )
      (property "MPN" "CC0201KRX6S5BB104" (at 20.32 -17.78 0)
        (effects (font (size 1.27 1.27) (thickness 0.15)) (justify left bottom) hide)
      )
      (property "Manufacturer" "Yaego" (at 20.32 -20.32 0)
        (effects (font (size 1.27 1.27) (thickness 0.15)) (justify left bottom) hide)
      )
      (property "License" "Apache-2.0" (at 20.32 -22.86 0)
        (effects (font (size 1.27 1.27) (thickness 0.15)) (justify left bottom) hide)
      )
      (property "Author" "Antmicro" (at 20.32 -25.4 0)
        (effects (font (size 1.27 1.27) (thickness 0.15)) (justify left bottom) hide)
      )
      (property "Val" "100n" (at 20.32 -7.62 0)
        (effects (font (size 1.27 1.27) (thickness 0.15)) (justify left bottom))
      )
      (property "Voltage" "" (at 20.32 -27.94 0)
        (effects (font (size 1.27 1.27)) (justify left bottom) hide)
      )
      (property "Dielectric" "" (at 20.32 -30.48 0)
        (effects (font (size 1.27 1.27)) (justify left bottom) hide)
      )
      (property "ki_description" " " (at 0 0 0)
        (effects (font (size 1.27 1.27)) hide)
      )
      (symbol "C_100n_0201_14_0_1"
        (polyline
          (pts
            (xy 2.032 -1.524)
            (xy 2.032 1.524)
          )
          (stroke (width 0.3048) (type default))
          (fill (type none))
        )
        (polyline
          (pts
            (xy 3.048 -1.524)
            (xy 3.048 1.524)
          )
          (stroke (width 0.3302) (type default))
          (fill (type none))
        )
      )
      (symbol "C_100n_0201_14_1_1"
        (pin passive line (at 0 0 0) (length 2.032)
          (name "~" (effects (font (size 1.27 1.27))))
          (number "1" (effects (font (size 1.27 1.27))))
        )
        (pin passive line (at 5.08 0 180) (length 2.032)
          (name "~" (effects (font (size 1.27 1.27))))
          (number "2" (effects (font (size 1.27 1.27))))
        )
      )
    )
	(symbol "data-center-rdimm-ddr4-tester:C_100n_0201_15" (pin_numbers hide) (pin_names hide) (in_bom yes) (on_board yes)
      (property "Reference" "C" (at 20.32 -5.08 0)
        (effects (font (size 1.27 1.27) (thickness 0.15)) (justify left bottom))
      )
      (property "Value" "C_100n_0201_15" (at 20.32 -10.16 0)
        (effects (font (size 1.27 1.27) (thickness 0.15)) (justify left bottom) hide)
      )
      (property "Footprint" "data-center-rdimm-ddr4-tester-footprints:C_0201" (at 20.32 -12.7 0)
        (effects (font (size 1.27 1.27) (thickness 0.15)) (justify left bottom) hide)
      )
      (property "Datasheet" " " (at 20.32 -15.24 0)
        (effects (font (size 1.27 1.27) (thickness 0.15)) (justify left bottom) hide)
      )
      (property "MPN" "CC0201KRX6S5BB104" (at 20.32 -17.78 0)
        (effects (font (size 1.27 1.27) (thickness 0.15)) (justify left bottom) hide)
      )
      (property "Manufacturer" "Yaego" (at 20.32 -20.32 0)
        (effects (font (size 1.27 1.27) (thickness 0.15)) (justify left bottom) hide)
      )
      (property "License" "Apache-2.0" (at 20.32 -22.86 0)
        (effects (font (size 1.27 1.27) (thickness 0.15)) (justify left bottom) hide)
      )
      (property "Author" "Antmicro" (at 20.32 -25.4 0)
        (effects (font (size 1.27 1.27) (thickness 0.15)) (justify left bottom) hide)
      )
      (property "Val" "100n" (at 20.32 -7.62 0)
        (effects (font (size 1.27 1.27) (thickness 0.15)) (justify left bottom))
      )
      (property "Voltage" "" (at 20.32 -27.94 0)
        (effects (font (size 1.27 1.27)) (justify left bottom) hide)
      )
      (property "Dielectric" "" (at 20.32 -30.48 0)
        (effects (font (size 1.27 1.27)) (justify left bottom) hide)
      )
      (property "ki_description" " " (at 0 0 0)
        (effects (font (size 1.27 1.27)) hide)
      )
      (symbol "C_100n_0201_15_0_1"
        (polyline
          (pts
            (xy 2.032 -1.524)
            (xy 2.032 1.524)
          )
          (stroke (width 0.3048) (type default))
          (fill (type none))
        )
        (polyline
          (pts
            (xy 3.048 -1.524)
            (xy 3.048 1.524)
          )
          (stroke (width 0.3302) (type default))
          (fill (type none))
        )
      )
      (symbol "C_100n_0201_15_1_1"
        (pin passive line (at 0 0 0) (length 2.032)
          (name "~" (effects (font (size 1.27 1.27))))
          (number "1" (effects (font (size 1.27 1.27))))
        )
        (pin passive line (at 5.08 0 180) (length 2.032)
          (name "~" (effects (font (size 1.27 1.27))))
          (number "2" (effects (font (size 1.27 1.27))))
        )
      )
    )
	(symbol "data-center-rdimm-ddr4-tester:C_100n_0201_16" (pin_numbers hide) (pin_names hide) (in_bom yes) (on_board yes)
      (property "Reference" "C" (at 20.32 -5.08 0)
        (effects (font (size 1.27 1.27) (thickness 0.15)) (justify left bottom))
      )
      (property "Value" "C_100n_0201_16" (at 20.32 -10.16 0)
        (effects (font (size 1.27 1.27) (thickness 0.15)) (justify left bottom) hide)
      )
      (property "Footprint" "data-center-rdimm-ddr4-tester-footprints:C_0201" (at 20.32 -12.7 0)
        (effects (font (size 1.27 1.27) (thickness 0.15)) (justify left bottom) hide)
      )
      (property "Datasheet" " " (at 20.32 -15.24 0)
        (effects (font (size 1.27 1.27) (thickness 0.15)) (justify left bottom) hide)
      )
      (property "MPN" "CC0201KRX6S5BB104" (at 20.32 -17.78 0)
        (effects (font (size 1.27 1.27) (thickness 0.15)) (justify left bottom) hide)
      )
      (property "Manufacturer" "Yaego" (at 20.32 -20.32 0)
        (effects (font (size 1.27 1.27) (thickness 0.15)) (justify left bottom) hide)
      )
      (property "License" "Apache-2.0" (at 20.32 -22.86 0)
        (effects (font (size 1.27 1.27) (thickness 0.15)) (justify left bottom) hide)
      )
      (property "Author" "Antmicro" (at 20.32 -25.4 0)
        (effects (font (size 1.27 1.27) (thickness 0.15)) (justify left bottom) hide)
      )
      (property "Val" "100n" (at 20.32 -7.62 0)
        (effects (font (size 1.27 1.27) (thickness 0.15)) (justify left bottom))
      )
      (property "Voltage" "" (at 20.32 -27.94 0)
        (effects (font (size 1.27 1.27)) (justify left bottom) hide)
      )
      (property "Dielectric" "" (at 20.32 -30.48 0)
        (effects (font (size 1.27 1.27)) (justify left bottom) hide)
      )
      (property "ki_description" " " (at 0 0 0)
        (effects (font (size 1.27 1.27)) hide)
      )
      (symbol "C_100n_0201_16_0_1"
        (polyline
          (pts
            (xy 2.032 -1.524)
            (xy 2.032 1.524)
          )
          (stroke (width 0.3048) (type default))
          (fill (type none))
        )
        (polyline
          (pts
            (xy 3.048 -1.524)
            (xy 3.048 1.524)
          )
          (stroke (width 0.3302) (type default))
          (fill (type none))
        )
      )
      (symbol "C_100n_0201_16_1_1"
        (pin passive line (at 0 0 0) (length 2.032)
          (name "~" (effects (font (size 1.27 1.27))))
          (number "1" (effects (font (size 1.27 1.27))))
        )
        (pin passive line (at 5.08 0 180) (length 2.032)
          (name "~" (effects (font (size 1.27 1.27))))
          (number "2" (effects (font (size 1.27 1.27))))
        )
      )
    )
	(symbol "data-center-rdimm-ddr4-tester:C_100n_0201_17" (pin_numbers hide) (pin_names hide) (in_bom yes) (on_board yes)
      (property "Reference" "C" (at 20.32 -5.08 0)
        (effects (font (size 1.27 1.27) (thickness 0.15)) (justify left bottom))
      )
      (property "Value" "C_100n_0201_17" (at 20.32 -10.16 0)
        (effects (font (size 1.27 1.27) (thickness 0.15)) (justify left bottom) hide)
      )
      (property "Footprint" "data-center-rdimm-ddr4-tester-footprints:C_0201" (at 20.32 -12.7 0)
        (effects (font (size 1.27 1.27) (thickness 0.15)) (justify left bottom) hide)
      )
      (property "Datasheet" " " (at 20.32 -15.24 0)
        (effects (font (size 1.27 1.27) (thickness 0.15)) (justify left bottom) hide)
      )
      (property "MPN" "CC0201KRX6S5BB104" (at 20.32 -17.78 0)
        (effects (font (size 1.27 1.27) (thickness 0.15)) (justify left bottom) hide)
      )
      (property "Manufacturer" "Yaego" (at 20.32 -20.32 0)
        (effects (font (size 1.27 1.27) (thickness 0.15)) (justify left bottom) hide)
      )
      (property "License" "Apache-2.0" (at 20.32 -22.86 0)
        (effects (font (size 1.27 1.27) (thickness 0.15)) (justify left bottom) hide)
      )
      (property "Author" "Antmicro" (at 20.32 -25.4 0)
        (effects (font (size 1.27 1.27) (thickness 0.15)) (justify left bottom) hide)
      )
      (property "Val" "100n" (at 20.32 -7.62 0)
        (effects (font (size 1.27 1.27) (thickness 0.15)) (justify left bottom))
      )
      (property "Voltage" "" (at 20.32 -27.94 0)
        (effects (font (size 1.27 1.27)) (justify left bottom) hide)
      )
      (property "Dielectric" "" (at 20.32 -30.48 0)
        (effects (font (size 1.27 1.27)) (justify left bottom) hide)
      )
      (property "ki_description" " " (at 0 0 0)
        (effects (font (size 1.27 1.27)) hide)
      )
      (symbol "C_100n_0201_17_0_1"
        (polyline
          (pts
            (xy 2.032 -1.524)
            (xy 2.032 1.524)
          )
          (stroke (width 0.3048) (type default))
          (fill (type none))
        )
        (polyline
          (pts
            (xy 3.048 -1.524)
            (xy 3.048 1.524)
          )
          (stroke (width 0.3302) (type default))
          (fill (type none))
        )
      )
      (symbol "C_100n_0201_17_1_1"
        (pin passive line (at 0 0 0) (length 2.032)
          (name "~" (effects (font (size 1.27 1.27))))
          (number "1" (effects (font (size 1.27 1.27))))
        )
        (pin passive line (at 5.08 0 180) (length 2.032)
          (name "~" (effects (font (size 1.27 1.27))))
          (number "2" (effects (font (size 1.27 1.27))))
        )
      )
    )
	(symbol "data-center-rdimm-ddr4-tester:C_100n_0201_18" (pin_numbers hide) (pin_names hide) (in_bom yes) (on_board yes)
      (property "Reference" "C" (at 20.32 -5.08 0)
        (effects (font (size 1.27 1.27) (thickness 0.15)) (justify left bottom))
      )
      (property "Value" "C_100n_0201_18" (at 20.32 -10.16 0)
        (effects (font (size 1.27 1.27) (thickness 0.15)) (justify left bottom) hide)
      )
      (property "Footprint" "data-center-rdimm-ddr4-tester-footprints:C_0201" (at 20.32 -12.7 0)
        (effects (font (size 1.27 1.27) (thickness 0.15)) (justify left bottom) hide)
      )
      (property "Datasheet" " " (at 20.32 -15.24 0)
        (effects (font (size 1.27 1.27) (thickness 0.15)) (justify left bottom) hide)
      )
      (property "MPN" "CC0201KRX6S5BB104" (at 20.32 -17.78 0)
        (effects (font (size 1.27 1.27) (thickness 0.15)) (justify left bottom) hide)
      )
      (property "Manufacturer" "Yaego" (at 20.32 -20.32 0)
        (effects (font (size 1.27 1.27) (thickness 0.15)) (justify left bottom) hide)
      )
      (property "License" "Apache-2.0" (at 20.32 -22.86 0)
        (effects (font (size 1.27 1.27) (thickness 0.15)) (justify left bottom) hide)
      )
      (property "Author" "Antmicro" (at 20.32 -25.4 0)
        (effects (font (size 1.27 1.27) (thickness 0.15)) (justify left bottom) hide)
      )
      (property "Val" "100n" (at 20.32 -7.62 0)
        (effects (font (size 1.27 1.27) (thickness 0.15)) (justify left bottom))
      )
      (property "Voltage" "" (at 20.32 -27.94 0)
        (effects (font (size 1.27 1.27)) (justify left bottom) hide)
      )
      (property "Dielectric" "" (at 20.32 -30.48 0)
        (effects (font (size 1.27 1.27)) (justify left bottom) hide)
      )
      (property "ki_description" " " (at 0 0 0)
        (effects (font (size 1.27 1.27)) hide)
      )
      (symbol "C_100n_0201_18_0_1"
        (polyline
          (pts
            (xy 2.032 -1.524)
            (xy 2.032 1.524)
          )
          (stroke (width 0.3048) (type default))
          (fill (type none))
        )
        (polyline
          (pts
            (xy 3.048 -1.524)
            (xy 3.048 1.524)
          )
          (stroke (width 0.3302) (type default))
          (fill (type none))
        )
      )
      (symbol "C_100n_0201_18_1_1"
        (pin passive line (at 0 0 0) (length 2.032)
          (name "~" (effects (font (size 1.27 1.27))))
          (number "1" (effects (font (size 1.27 1.27))))
        )
        (pin passive line (at 5.08 0 180) (length 2.032)
          (name "~" (effects (font (size 1.27 1.27))))
          (number "2" (effects (font (size 1.27 1.27))))
        )
      )
    )
	(symbol "data-center-rdimm-ddr4-tester:C_100n_0201_19" (pin_numbers hide) (pin_names hide) (in_bom yes) (on_board yes)
      (property "Reference" "C" (at 20.32 -5.08 0)
        (effects (font (size 1.27 1.27) (thickness 0.15)) (justify left bottom))
      )
      (property "Value" "C_100n_0201_19" (at 20.32 -10.16 0)
        (effects (font (size 1.27 1.27) (thickness 0.15)) (justify left bottom) hide)
      )
      (property "Footprint" "data-center-rdimm-ddr4-tester-footprints:C_0201" (at 20.32 -12.7 0)
        (effects (font (size 1.27 1.27) (thickness 0.15)) (justify left bottom) hide)
      )
      (property "Datasheet" " " (at 20.32 -15.24 0)
        (effects (font (size 1.27 1.27) (thickness 0.15)) (justify left bottom) hide)
      )
      (property "MPN" "CC0201KRX6S5BB104" (at 20.32 -17.78 0)
        (effects (font (size 1.27 1.27) (thickness 0.15)) (justify left bottom) hide)
      )
      (property "Manufacturer" "Yaego" (at 20.32 -20.32 0)
        (effects (font (size 1.27 1.27) (thickness 0.15)) (justify left bottom) hide)
      )
      (property "License" "Apache-2.0" (at 20.32 -22.86 0)
        (effects (font (size 1.27 1.27) (thickness 0.15)) (justify left bottom) hide)
      )
      (property "Author" "Antmicro" (at 20.32 -25.4 0)
        (effects (font (size 1.27 1.27) (thickness 0.15)) (justify left bottom) hide)
      )
      (property "Val" "100n" (at 20.32 -7.62 0)
        (effects (font (size 1.27 1.27) (thickness 0.15)) (justify left bottom))
      )
      (property "Voltage" "" (at 20.32 -27.94 0)
        (effects (font (size 1.27 1.27)) (justify left bottom) hide)
      )
      (property "Dielectric" "" (at 20.32 -30.48 0)
        (effects (font (size 1.27 1.27)) (justify left bottom) hide)
      )
      (property "ki_description" " " (at 0 0 0)
        (effects (font (size 1.27 1.27)) hide)
      )
      (symbol "C_100n_0201_19_0_1"
        (polyline
          (pts
            (xy 2.032 -1.524)
            (xy 2.032 1.524)
          )
          (stroke (width 0.3048) (type default))
          (fill (type none))
        )
        (polyline
          (pts
            (xy 3.048 -1.524)
            (xy 3.048 1.524)
          )
          (stroke (width 0.3302) (type default))
          (fill (type none))
        )
      )
      (symbol "C_100n_0201_19_1_1"
        (pin passive line (at 0 0 0) (length 2.032)
          (name "~" (effects (font (size 1.27 1.27))))
          (number "1" (effects (font (size 1.27 1.27))))
        )
        (pin passive line (at 5.08 0 180) (length 2.032)
          (name "~" (effects (font (size 1.27 1.27))))
          (number "2" (effects (font (size 1.27 1.27))))
        )
      )
    )
	(symbol "data-center-rdimm-ddr4-tester:C_100n_0201_20" (pin_numbers hide) (pin_names hide) (in_bom yes) (on_board yes)
      (property "Reference" "C" (at 20.32 -5.08 0)
        (effects (font (size 1.27 1.27) (thickness 0.15)) (justify left bottom))
      )
      (property "Value" "C_100n_0201_20" (at 20.32 -10.16 0)
        (effects (font (size 1.27 1.27) (thickness 0.15)) (justify left bottom) hide)
      )
      (property "Footprint" "data-center-rdimm-ddr4-tester-footprints:C_0201" (at 20.32 -12.7 0)
        (effects (font (size 1.27 1.27) (thickness 0.15)) (justify left bottom) hide)
      )
      (property "Datasheet" " " (at 20.32 -15.24 0)
        (effects (font (size 1.27 1.27) (thickness 0.15)) (justify left bottom) hide)
      )
      (property "MPN" "CC0201KRX6S5BB104" (at 20.32 -17.78 0)
        (effects (font (size 1.27 1.27) (thickness 0.15)) (justify left bottom) hide)
      )
      (property "Manufacturer" "Yaego" (at 20.32 -20.32 0)
        (effects (font (size 1.27 1.27) (thickness 0.15)) (justify left bottom) hide)
      )
      (property "License" "Apache-2.0" (at 20.32 -22.86 0)
        (effects (font (size 1.27 1.27) (thickness 0.15)) (justify left bottom) hide)
      )
      (property "Author" "Antmicro" (at 20.32 -25.4 0)
        (effects (font (size 1.27 1.27) (thickness 0.15)) (justify left bottom) hide)
      )
      (property "Val" "100n" (at 20.32 -7.62 0)
        (effects (font (size 1.27 1.27) (thickness 0.15)) (justify left bottom))
      )
      (property "Voltage" "" (at 20.32 -27.94 0)
        (effects (font (size 1.27 1.27)) (justify left bottom) hide)
      )
      (property "Dielectric" "" (at 20.32 -30.48 0)
        (effects (font (size 1.27 1.27)) (justify left bottom) hide)
      )
      (property "ki_description" " " (at 0 0 0)
        (effects (font (size 1.27 1.27)) hide)
      )
      (symbol "C_100n_0201_20_0_1"
        (polyline
          (pts
            (xy 2.032 -1.524)
            (xy 2.032 1.524)
          )
          (stroke (width 0.3048) (type default))
          (fill (type none))
        )
        (polyline
          (pts
            (xy 3.048 -1.524)
            (xy 3.048 1.524)
          )
          (stroke (width 0.3302) (type default))
          (fill (type none))
        )
      )
      (symbol "C_100n_0201_20_1_1"
        (pin passive line (at 0 0 0) (length 2.032)
          (name "~" (effects (font (size 1.27 1.27))))
          (number "1" (effects (font (size 1.27 1.27))))
        )
        (pin passive line (at 5.08 0 180) (length 2.032)
          (name "~" (effects (font (size 1.27 1.27))))
          (number "2" (effects (font (size 1.27 1.27))))
        )
      )
    )
	(symbol "data-center-rdimm-ddr4-tester:C_100n_0201_21" (pin_numbers hide) (pin_names hide) (in_bom yes) (on_board yes)
      (property "Reference" "C" (at 20.32 -5.08 0)
        (effects (font (size 1.27 1.27) (thickness 0.15)) (justify left bottom))
      )
      (property "Value" "C_100n_0201_21" (at 20.32 -10.16 0)
        (effects (font (size 1.27 1.27) (thickness 0.15)) (justify left bottom) hide)
      )
      (property "Footprint" "data-center-rdimm-ddr4-tester-footprints:C_0201" (at 20.32 -12.7 0)
        (effects (font (size 1.27 1.27) (thickness 0.15)) (justify left bottom) hide)
      )
      (property "Datasheet" " " (at 20.32 -15.24 0)
        (effects (font (size 1.27 1.27) (thickness 0.15)) (justify left bottom) hide)
      )
      (property "MPN" "CC0201KRX6S5BB104" (at 20.32 -17.78 0)
        (effects (font (size 1.27 1.27) (thickness 0.15)) (justify left bottom) hide)
      )
      (property "Manufacturer" "Yaego" (at 20.32 -20.32 0)
        (effects (font (size 1.27 1.27) (thickness 0.15)) (justify left bottom) hide)
      )
      (property "License" "Apache-2.0" (at 20.32 -22.86 0)
        (effects (font (size 1.27 1.27) (thickness 0.15)) (justify left bottom) hide)
      )
      (property "Author" "Antmicro" (at 20.32 -25.4 0)
        (effects (font (size 1.27 1.27) (thickness 0.15)) (justify left bottom) hide)
      )
      (property "Val" "100n" (at 20.32 -7.62 0)
        (effects (font (size 1.27 1.27) (thickness 0.15)) (justify left bottom))
      )
      (property "Voltage" "" (at 20.32 -27.94 0)
        (effects (font (size 1.27 1.27)) (justify left bottom) hide)
      )
      (property "Dielectric" "" (at 20.32 -30.48 0)
        (effects (font (size 1.27 1.27)) (justify left bottom) hide)
      )
      (property "ki_description" " " (at 0 0 0)
        (effects (font (size 1.27 1.27)) hide)
      )
      (symbol "C_100n_0201_21_0_1"
        (polyline
          (pts
            (xy 2.032 -1.524)
            (xy 2.032 1.524)
          )
          (stroke (width 0.3048) (type default))
          (fill (type none))
        )
        (polyline
          (pts
            (xy 3.048 -1.524)
            (xy 3.048 1.524)
          )
          (stroke (width 0.3302) (type default))
          (fill (type none))
        )
      )
      (symbol "C_100n_0201_21_1_1"
        (pin passive line (at 0 0 0) (length 2.032)
          (name "~" (effects (font (size 1.27 1.27))))
          (number "1" (effects (font (size 1.27 1.27))))
        )
        (pin passive line (at 5.08 0 180) (length 2.032)
          (name "~" (effects (font (size 1.27 1.27))))
          (number "2" (effects (font (size 1.27 1.27))))
        )
      )
    )
	(symbol "data-center-rdimm-ddr4-tester:C_100n_0201_22" (pin_numbers hide) (pin_names hide) (in_bom yes) (on_board yes)
      (property "Reference" "C" (at 20.32 -5.08 0)
        (effects (font (size 1.27 1.27) (thickness 0.15)) (justify left bottom))
      )
      (property "Value" "C_100n_0201_22" (at 20.32 -10.16 0)
        (effects (font (size 1.27 1.27) (thickness 0.15)) (justify left bottom) hide)
      )
      (property "Footprint" "data-center-rdimm-ddr4-tester-footprints:C_0201" (at 20.32 -12.7 0)
        (effects (font (size 1.27 1.27) (thickness 0.15)) (justify left bottom) hide)
      )
      (property "Datasheet" " " (at 20.32 -15.24 0)
        (effects (font (size 1.27 1.27) (thickness 0.15)) (justify left bottom) hide)
      )
      (property "MPN" "CC0201KRX6S5BB104" (at 20.32 -17.78 0)
        (effects (font (size 1.27 1.27) (thickness 0.15)) (justify left bottom) hide)
      )
      (property "Manufacturer" "Yaego" (at 20.32 -20.32 0)
        (effects (font (size 1.27 1.27) (thickness 0.15)) (justify left bottom) hide)
      )
      (property "License" "Apache-2.0" (at 20.32 -22.86 0)
        (effects (font (size 1.27 1.27) (thickness 0.15)) (justify left bottom) hide)
      )
      (property "Author" "Antmicro" (at 20.32 -25.4 0)
        (effects (font (size 1.27 1.27) (thickness 0.15)) (justify left bottom) hide)
      )
      (property "Val" "100n" (at 20.32 -7.62 0)
        (effects (font (size 1.27 1.27) (thickness 0.15)) (justify left bottom))
      )
      (property "Voltage" "" (at 20.32 -27.94 0)
        (effects (font (size 1.27 1.27)) (justify left bottom) hide)
      )
      (property "Dielectric" "" (at 20.32 -30.48 0)
        (effects (font (size 1.27 1.27)) (justify left bottom) hide)
      )
      (property "ki_description" " " (at 0 0 0)
        (effects (font (size 1.27 1.27)) hide)
      )
      (symbol "C_100n_0201_22_0_1"
        (polyline
          (pts
            (xy 2.032 -1.524)
            (xy 2.032 1.524)
          )
          (stroke (width 0.3048) (type default))
          (fill (type none))
        )
        (polyline
          (pts
            (xy 3.048 -1.524)
            (xy 3.048 1.524)
          )
          (stroke (width 0.3302) (type default))
          (fill (type none))
        )
      )
      (symbol "C_100n_0201_22_1_1"
        (pin passive line (at 0 0 0) (length 2.032)
          (name "~" (effects (font (size 1.27 1.27))))
          (number "1" (effects (font (size 1.27 1.27))))
        )
        (pin passive line (at 5.08 0 180) (length 2.032)
          (name "~" (effects (font (size 1.27 1.27))))
          (number "2" (effects (font (size 1.27 1.27))))
        )
      )
    )
	(symbol "data-center-rdimm-ddr4-tester:C_100n_0201_23" (pin_numbers hide) (pin_names hide) (in_bom yes) (on_board yes)
      (property "Reference" "C" (at 20.32 -5.08 0)
        (effects (font (size 1.27 1.27) (thickness 0.15)) (justify left bottom))
      )
      (property "Value" "C_100n_0201_23" (at 20.32 -10.16 0)
        (effects (font (size 1.27 1.27) (thickness 0.15)) (justify left bottom) hide)
      )
      (property "Footprint" "data-center-rdimm-ddr4-tester-footprints:C_0201" (at 20.32 -12.7 0)
        (effects (font (size 1.27 1.27) (thickness 0.15)) (justify left bottom) hide)
      )
      (property "Datasheet" " " (at 20.32 -15.24 0)
        (effects (font (size 1.27 1.27) (thickness 0.15)) (justify left bottom) hide)
      )
      (property "MPN" "CC0201KRX6S5BB104" (at 20.32 -17.78 0)
        (effects (font (size 1.27 1.27) (thickness 0.15)) (justify left bottom) hide)
      )
      (property "Manufacturer" "Yaego" (at 20.32 -20.32 0)
        (effects (font (size 1.27 1.27) (thickness 0.15)) (justify left bottom) hide)
      )
      (property "License" "Apache-2.0" (at 20.32 -22.86 0)
        (effects (font (size 1.27 1.27) (thickness 0.15)) (justify left bottom) hide)
      )
      (property "Author" "Antmicro" (at 20.32 -25.4 0)
        (effects (font (size 1.27 1.27) (thickness 0.15)) (justify left bottom) hide)
      )
      (property "Val" "100n" (at 20.32 -7.62 0)
        (effects (font (size 1.27 1.27) (thickness 0.15)) (justify left bottom))
      )
      (property "Voltage" "" (at 20.32 -27.94 0)
        (effects (font (size 1.27 1.27)) (justify left bottom) hide)
      )
      (property "Dielectric" "" (at 20.32 -30.48 0)
        (effects (font (size 1.27 1.27)) (justify left bottom) hide)
      )
      (property "ki_description" " " (at 0 0 0)
        (effects (font (size 1.27 1.27)) hide)
      )
      (symbol "C_100n_0201_23_0_1"
        (polyline
          (pts
            (xy 2.032 -1.524)
            (xy 2.032 1.524)
          )
          (stroke (width 0.3048) (type default))
          (fill (type none))
        )
        (polyline
          (pts
            (xy 3.048 -1.524)
            (xy 3.048 1.524)
          )
          (stroke (width 0.3302) (type default))
          (fill (type none))
        )
      )
      (symbol "C_100n_0201_23_1_1"
        (pin passive line (at 0 0 0) (length 2.032)
          (name "~" (effects (font (size 1.27 1.27))))
          (number "1" (effects (font (size 1.27 1.27))))
        )
        (pin passive line (at 5.08 0 180) (length 2.032)
          (name "~" (effects (font (size 1.27 1.27))))
          (number "2" (effects (font (size 1.27 1.27))))
        )
      )
    )
	(symbol "data-center-rdimm-ddr4-tester:C_100n_0201_24" (pin_numbers hide) (pin_names hide) (in_bom yes) (on_board yes)
      (property "Reference" "C" (at 20.32 -5.08 0)
        (effects (font (size 1.27 1.27) (thickness 0.15)) (justify left bottom))
      )
      (property "Value" "C_100n_0201_24" (at 20.32 -10.16 0)
        (effects (font (size 1.27 1.27) (thickness 0.15)) (justify left bottom) hide)
      )
      (property "Footprint" "data-center-rdimm-ddr4-tester-footprints:C_0201" (at 20.32 -12.7 0)
        (effects (font (size 1.27 1.27) (thickness 0.15)) (justify left bottom) hide)
      )
      (property "Datasheet" " " (at 20.32 -15.24 0)
        (effects (font (size 1.27 1.27) (thickness 0.15)) (justify left bottom) hide)
      )
      (property "MPN" "CC0201KRX6S5BB104" (at 20.32 -17.78 0)
        (effects (font (size 1.27 1.27) (thickness 0.15)) (justify left bottom) hide)
      )
      (property "Manufacturer" "Yaego" (at 20.32 -20.32 0)
        (effects (font (size 1.27 1.27) (thickness 0.15)) (justify left bottom) hide)
      )
      (property "License" "Apache-2.0" (at 20.32 -22.86 0)
        (effects (font (size 1.27 1.27) (thickness 0.15)) (justify left bottom) hide)
      )
      (property "Author" "Antmicro" (at 20.32 -25.4 0)
        (effects (font (size 1.27 1.27) (thickness 0.15)) (justify left bottom) hide)
      )
      (property "Val" "100n" (at 20.32 -7.62 0)
        (effects (font (size 1.27 1.27) (thickness 0.15)) (justify left bottom))
      )
      (property "Voltage" "" (at 20.32 -27.94 0)
        (effects (font (size 1.27 1.27)) (justify left bottom) hide)
      )
      (property "Dielectric" "" (at 20.32 -30.48 0)
        (effects (font (size 1.27 1.27)) (justify left bottom) hide)
      )
      (property "ki_description" " " (at 0 0 0)
        (effects (font (size 1.27 1.27)) hide)
      )
      (symbol "C_100n_0201_24_0_1"
        (polyline
          (pts
            (xy 2.032 -1.524)
            (xy 2.032 1.524)
          )
          (stroke (width 0.3048) (type default))
          (fill (type none))
        )
        (polyline
          (pts
            (xy 3.048 -1.524)
            (xy 3.048 1.524)
          )
          (stroke (width 0.3302) (type default))
          (fill (type none))
        )
      )
      (symbol "C_100n_0201_24_1_1"
        (pin passive line (at 0 0 0) (length 2.032)
          (name "~" (effects (font (size 1.27 1.27))))
          (number "1" (effects (font (size 1.27 1.27))))
        )
        (pin passive line (at 5.08 0 180) (length 2.032)
          (name "~" (effects (font (size 1.27 1.27))))
          (number "2" (effects (font (size 1.27 1.27))))
        )
      )
    )
	(symbol "data-center-rdimm-ddr4-tester:C_100n_0201_25" (pin_numbers hide) (pin_names hide) (in_bom yes) (on_board yes)
      (property "Reference" "C" (at 20.32 -5.08 0)
        (effects (font (size 1.27 1.27) (thickness 0.15)) (justify left bottom))
      )
      (property "Value" "C_100n_0201_25" (at 20.32 -10.16 0)
        (effects (font (size 1.27 1.27) (thickness 0.15)) (justify left bottom) hide)
      )
      (property "Footprint" "data-center-rdimm-ddr4-tester-footprints:C_0201" (at 20.32 -12.7 0)
        (effects (font (size 1.27 1.27) (thickness 0.15)) (justify left bottom) hide)
      )
      (property "Datasheet" " " (at 20.32 -15.24 0)
        (effects (font (size 1.27 1.27) (thickness 0.15)) (justify left bottom) hide)
      )
      (property "MPN" "CC0201KRX6S5BB104" (at 20.32 -17.78 0)
        (effects (font (size 1.27 1.27) (thickness 0.15)) (justify left bottom) hide)
      )
      (property "Manufacturer" "Yaego" (at 20.32 -20.32 0)
        (effects (font (size 1.27 1.27) (thickness 0.15)) (justify left bottom) hide)
      )
      (property "License" "Apache-2.0" (at 20.32 -22.86 0)
        (effects (font (size 1.27 1.27) (thickness 0.15)) (justify left bottom) hide)
      )
      (property "Author" "Antmicro" (at 20.32 -25.4 0)
        (effects (font (size 1.27 1.27) (thickness 0.15)) (justify left bottom) hide)
      )
      (property "Val" "100n" (at 20.32 -7.62 0)
        (effects (font (size 1.27 1.27) (thickness 0.15)) (justify left bottom))
      )
      (property "Voltage" "" (at 20.32 -27.94 0)
        (effects (font (size 1.27 1.27)) (justify left bottom) hide)
      )
      (property "Dielectric" "" (at 20.32 -30.48 0)
        (effects (font (size 1.27 1.27)) (justify left bottom) hide)
      )
      (property "ki_description" " " (at 0 0 0)
        (effects (font (size 1.27 1.27)) hide)
      )
      (symbol "C_100n_0201_25_0_1"
        (polyline
          (pts
            (xy 2.032 -1.524)
            (xy 2.032 1.524)
          )
          (stroke (width 0.3048) (type default))
          (fill (type none))
        )
        (polyline
          (pts
            (xy 3.048 -1.524)
            (xy 3.048 1.524)
          )
          (stroke (width 0.3302) (type default))
          (fill (type none))
        )
      )
      (symbol "C_100n_0201_25_1_1"
        (pin passive line (at 0 0 0) (length 2.032)
          (name "~" (effects (font (size 1.27 1.27))))
          (number "1" (effects (font (size 1.27 1.27))))
        )
        (pin passive line (at 5.08 0 180) (length 2.032)
          (name "~" (effects (font (size 1.27 1.27))))
          (number "2" (effects (font (size 1.27 1.27))))
        )
      )
    )
	(symbol "data-center-rdimm-ddr4-tester:C_100n_0201_26" (pin_numbers hide) (pin_names hide) (in_bom yes) (on_board yes)
      (property "Reference" "C" (at 20.32 -5.08 0)
        (effects (font (size 1.27 1.27) (thickness 0.15)) (justify left bottom))
      )
      (property "Value" "C_100n_0201_26" (at 20.32 -10.16 0)
        (effects (font (size 1.27 1.27) (thickness 0.15)) (justify left bottom) hide)
      )
      (property "Footprint" "data-center-rdimm-ddr4-tester-footprints:C_0201" (at 20.32 -12.7 0)
        (effects (font (size 1.27 1.27) (thickness 0.15)) (justify left bottom) hide)
      )
      (property "Datasheet" " " (at 20.32 -15.24 0)
        (effects (font (size 1.27 1.27) (thickness 0.15)) (justify left bottom) hide)
      )
      (property "MPN" "CC0201KRX6S5BB104" (at 20.32 -17.78 0)
        (effects (font (size 1.27 1.27) (thickness 0.15)) (justify left bottom) hide)
      )
      (property "Manufacturer" "Yaego" (at 20.32 -20.32 0)
        (effects (font (size 1.27 1.27) (thickness 0.15)) (justify left bottom) hide)
      )
      (property "License" "Apache-2.0" (at 20.32 -22.86 0)
        (effects (font (size 1.27 1.27) (thickness 0.15)) (justify left bottom) hide)
      )
      (property "Author" "Antmicro" (at 20.32 -25.4 0)
        (effects (font (size 1.27 1.27) (thickness 0.15)) (justify left bottom) hide)
      )
      (property "Val" "100n" (at 20.32 -7.62 0)
        (effects (font (size 1.27 1.27) (thickness 0.15)) (justify left bottom))
      )
      (property "Voltage" "" (at 20.32 -27.94 0)
        (effects (font (size 1.27 1.27)) (justify left bottom) hide)
      )
      (property "Dielectric" "" (at 20.32 -30.48 0)
        (effects (font (size 1.27 1.27)) (justify left bottom) hide)
      )
      (property "ki_description" " " (at 0 0 0)
        (effects (font (size 1.27 1.27)) hide)
      )
      (symbol "C_100n_0201_26_0_1"
        (polyline
          (pts
            (xy 2.032 -1.524)
            (xy 2.032 1.524)
          )
          (stroke (width 0.3048) (type default))
          (fill (type none))
        )
        (polyline
          (pts
            (xy 3.048 -1.524)
            (xy 3.048 1.524)
          )
          (stroke (width 0.3302) (type default))
          (fill (type none))
        )
      )
      (symbol "C_100n_0201_26_1_1"
        (pin passive line (at 0 0 0) (length 2.032)
          (name "~" (effects (font (size 1.27 1.27))))
          (number "1" (effects (font (size 1.27 1.27))))
        )
        (pin passive line (at 5.08 0 180) (length 2.032)
          (name "~" (effects (font (size 1.27 1.27))))
          (number "2" (effects (font (size 1.27 1.27))))
        )
      )
    )
	(symbol "data-center-rdimm-ddr4-tester:C_100n_0201_27" (pin_numbers hide) (pin_names hide) (in_bom yes) (on_board yes)
      (property "Reference" "C" (at 20.32 -5.08 0)
        (effects (font (size 1.27 1.27) (thickness 0.15)) (justify left bottom))
      )
      (property "Value" "C_100n_0201_27" (at 20.32 -10.16 0)
        (effects (font (size 1.27 1.27) (thickness 0.15)) (justify left bottom) hide)
      )
      (property "Footprint" "data-center-rdimm-ddr4-tester-footprints:C_0201" (at 20.32 -12.7 0)
        (effects (font (size 1.27 1.27) (thickness 0.15)) (justify left bottom) hide)
      )
      (property "Datasheet" " " (at 20.32 -15.24 0)
        (effects (font (size 1.27 1.27) (thickness 0.15)) (justify left bottom) hide)
      )
      (property "MPN" "CC0201KRX6S5BB104" (at 20.32 -17.78 0)
        (effects (font (size 1.27 1.27) (thickness 0.15)) (justify left bottom) hide)
      )
      (property "Manufacturer" "Yaego" (at 20.32 -20.32 0)
        (effects (font (size 1.27 1.27) (thickness 0.15)) (justify left bottom) hide)
      )
      (property "License" "Apache-2.0" (at 20.32 -22.86 0)
        (effects (font (size 1.27 1.27) (thickness 0.15)) (justify left bottom) hide)
      )
      (property "Author" "Antmicro" (at 20.32 -25.4 0)
        (effects (font (size 1.27 1.27) (thickness 0.15)) (justify left bottom) hide)
      )
      (property "Val" "100n" (at 20.32 -7.62 0)
        (effects (font (size 1.27 1.27) (thickness 0.15)) (justify left bottom))
      )
      (property "Voltage" "" (at 20.32 -27.94 0)
        (effects (font (size 1.27 1.27)) (justify left bottom) hide)
      )
      (property "Dielectric" "" (at 20.32 -30.48 0)
        (effects (font (size 1.27 1.27)) (justify left bottom) hide)
      )
      (property "ki_description" " " (at 0 0 0)
        (effects (font (size 1.27 1.27)) hide)
      )
      (symbol "C_100n_0201_27_0_1"
        (polyline
          (pts
            (xy 2.032 -1.524)
            (xy 2.032 1.524)
          )
          (stroke (width 0.3048) (type default))
          (fill (type none))
        )
        (polyline
          (pts
            (xy 3.048 -1.524)
            (xy 3.048 1.524)
          )
          (stroke (width 0.3302) (type default))
          (fill (type none))
        )
      )
      (symbol "C_100n_0201_27_1_1"
        (pin passive line (at 0 0 0) (length 2.032)
          (name "~" (effects (font (size 1.27 1.27))))
          (number "1" (effects (font (size 1.27 1.27))))
        )
        (pin passive line (at 5.08 0 180) (length 2.032)
          (name "~" (effects (font (size 1.27 1.27))))
          (number "2" (effects (font (size 1.27 1.27))))
        )
      )
    )
	(symbol "data-center-rdimm-ddr4-tester:C_100n_0201_28" (pin_numbers hide) (pin_names hide) (in_bom yes) (on_board yes)
      (property "Reference" "C" (at 20.32 -5.08 0)
        (effects (font (size 1.27 1.27) (thickness 0.15)) (justify left bottom))
      )
      (property "Value" "C_100n_0201_28" (at 20.32 -10.16 0)
        (effects (font (size 1.27 1.27) (thickness 0.15)) (justify left bottom) hide)
      )
      (property "Footprint" "data-center-rdimm-ddr4-tester-footprints:C_0201" (at 20.32 -12.7 0)
        (effects (font (size 1.27 1.27) (thickness 0.15)) (justify left bottom) hide)
      )
      (property "Datasheet" " " (at 20.32 -15.24 0)
        (effects (font (size 1.27 1.27) (thickness 0.15)) (justify left bottom) hide)
      )
      (property "MPN" "CC0201KRX6S5BB104" (at 20.32 -17.78 0)
        (effects (font (size 1.27 1.27) (thickness 0.15)) (justify left bottom) hide)
      )
      (property "Manufacturer" "Yaego" (at 20.32 -20.32 0)
        (effects (font (size 1.27 1.27) (thickness 0.15)) (justify left bottom) hide)
      )
      (property "License" "Apache-2.0" (at 20.32 -22.86 0)
        (effects (font (size 1.27 1.27) (thickness 0.15)) (justify left bottom) hide)
      )
      (property "Author" "Antmicro" (at 20.32 -25.4 0)
        (effects (font (size 1.27 1.27) (thickness 0.15)) (justify left bottom) hide)
      )
      (property "Val" "100n" (at 20.32 -7.62 0)
        (effects (font (size 1.27 1.27) (thickness 0.15)) (justify left bottom))
      )
      (property "Voltage" "" (at 20.32 -27.94 0)
        (effects (font (size 1.27 1.27)) (justify left bottom) hide)
      )
      (property "Dielectric" "" (at 20.32 -30.48 0)
        (effects (font (size 1.27 1.27)) (justify left bottom) hide)
      )
      (property "ki_description" " " (at 0 0 0)
        (effects (font (size 1.27 1.27)) hide)
      )
      (symbol "C_100n_0201_28_0_1"
        (polyline
          (pts
            (xy 2.032 -1.524)
            (xy 2.032 1.524)
          )
          (stroke (width 0.3048) (type default))
          (fill (type none))
        )
        (polyline
          (pts
            (xy 3.048 -1.524)
            (xy 3.048 1.524)
          )
          (stroke (width 0.3302) (type default))
          (fill (type none))
        )
      )
      (symbol "C_100n_0201_28_1_1"
        (pin passive line (at 0 0 0) (length 2.032)
          (name "~" (effects (font (size 1.27 1.27))))
          (number "1" (effects (font (size 1.27 1.27))))
        )
        (pin passive line (at 5.08 0 180) (length 2.032)
          (name "~" (effects (font (size 1.27 1.27))))
          (number "2" (effects (font (size 1.27 1.27))))
        )
      )
    )
	(symbol "data-center-rdimm-ddr4-tester:C_100n_0201_29" (pin_numbers hide) (pin_names hide) (in_bom yes) (on_board yes)
      (property "Reference" "C" (at 20.32 -5.08 0)
        (effects (font (size 1.27 1.27) (thickness 0.15)) (justify left bottom))
      )
      (property "Value" "C_100n_0201_29" (at 20.32 -10.16 0)
        (effects (font (size 1.27 1.27) (thickness 0.15)) (justify left bottom) hide)
      )
      (property "Footprint" "data-center-rdimm-ddr4-tester-footprints:C_0201" (at 20.32 -12.7 0)
        (effects (font (size 1.27 1.27) (thickness 0.15)) (justify left bottom) hide)
      )
      (property "Datasheet" " " (at 20.32 -15.24 0)
        (effects (font (size 1.27 1.27) (thickness 0.15)) (justify left bottom) hide)
      )
      (property "MPN" "CC0201KRX6S5BB104" (at 20.32 -17.78 0)
        (effects (font (size 1.27 1.27) (thickness 0.15)) (justify left bottom) hide)
      )
      (property "Manufacturer" "Yaego" (at 20.32 -20.32 0)
        (effects (font (size 1.27 1.27) (thickness 0.15)) (justify left bottom) hide)
      )
      (property "License" "Apache-2.0" (at 20.32 -22.86 0)
        (effects (font (size 1.27 1.27) (thickness 0.15)) (justify left bottom) hide)
      )
      (property "Author" "Antmicro" (at 20.32 -25.4 0)
        (effects (font (size 1.27 1.27) (thickness 0.15)) (justify left bottom) hide)
      )
      (property "Val" "100n" (at 20.32 -7.62 0)
        (effects (font (size 1.27 1.27) (thickness 0.15)) (justify left bottom))
      )
      (property "Voltage" "" (at 20.32 -27.94 0)
        (effects (font (size 1.27 1.27)) (justify left bottom) hide)
      )
      (property "Dielectric" "" (at 20.32 -30.48 0)
        (effects (font (size 1.27 1.27)) (justify left bottom) hide)
      )
      (property "ki_description" " " (at 0 0 0)
        (effects (font (size 1.27 1.27)) hide)
      )
      (symbol "C_100n_0201_29_0_1"
        (polyline
          (pts
            (xy 2.032 -1.524)
            (xy 2.032 1.524)
          )
          (stroke (width 0.3048) (type default))
          (fill (type none))
        )
        (polyline
          (pts
            (xy 3.048 -1.524)
            (xy 3.048 1.524)
          )
          (stroke (width 0.3302) (type default))
          (fill (type none))
        )
      )
      (symbol "C_100n_0201_29_1_1"
        (pin passive line (at 0 0 0) (length 2.032)
          (name "~" (effects (font (size 1.27 1.27))))
          (number "1" (effects (font (size 1.27 1.27))))
        )
        (pin passive line (at 5.08 0 180) (length 2.032)
          (name "~" (effects (font (size 1.27 1.27))))
          (number "2" (effects (font (size 1.27 1.27))))
        )
      )
    )
	(symbol "data-center-rdimm-ddr4-tester:C_100n_0201_30" (pin_numbers hide) (pin_names hide) (in_bom yes) (on_board yes)
      (property "Reference" "C" (at 20.32 -5.08 0)
        (effects (font (size 1.27 1.27) (thickness 0.15)) (justify left bottom))
      )
      (property "Value" "C_100n_0201_30" (at 20.32 -10.16 0)
        (effects (font (size 1.27 1.27) (thickness 0.15)) (justify left bottom) hide)
      )
      (property "Footprint" "data-center-rdimm-ddr4-tester-footprints:C_0201" (at 20.32 -12.7 0)
        (effects (font (size 1.27 1.27) (thickness 0.15)) (justify left bottom) hide)
      )
      (property "Datasheet" " " (at 20.32 -15.24 0)
        (effects (font (size 1.27 1.27) (thickness 0.15)) (justify left bottom) hide)
      )
      (property "MPN" "CC0201KRX6S5BB104" (at 20.32 -17.78 0)
        (effects (font (size 1.27 1.27) (thickness 0.15)) (justify left bottom) hide)
      )
      (property "Manufacturer" "Yaego" (at 20.32 -20.32 0)
        (effects (font (size 1.27 1.27) (thickness 0.15)) (justify left bottom) hide)
      )
      (property "License" "Apache-2.0" (at 20.32 -22.86 0)
        (effects (font (size 1.27 1.27) (thickness 0.15)) (justify left bottom) hide)
      )
      (property "Author" "Antmicro" (at 20.32 -25.4 0)
        (effects (font (size 1.27 1.27) (thickness 0.15)) (justify left bottom) hide)
      )
      (property "Val" "100n" (at 20.32 -7.62 0)
        (effects (font (size 1.27 1.27) (thickness 0.15)) (justify left bottom))
      )
      (property "Voltage" "" (at 20.32 -27.94 0)
        (effects (font (size 1.27 1.27)) (justify left bottom) hide)
      )
      (property "Dielectric" "" (at 20.32 -30.48 0)
        (effects (font (size 1.27 1.27)) (justify left bottom) hide)
      )
      (property "ki_description" " " (at 0 0 0)
        (effects (font (size 1.27 1.27)) hide)
      )
      (symbol "C_100n_0201_30_0_1"
        (polyline
          (pts
            (xy 2.032 -1.524)
            (xy 2.032 1.524)
          )
          (stroke (width 0.3048) (type default))
          (fill (type none))
        )
        (polyline
          (pts
            (xy 3.048 -1.524)
            (xy 3.048 1.524)
          )
          (stroke (width 0.3302) (type default))
          (fill (type none))
        )
      )
      (symbol "C_100n_0201_30_1_1"
        (pin passive line (at 0 0 0) (length 2.032)
          (name "~" (effects (font (size 1.27 1.27))))
          (number "1" (effects (font (size 1.27 1.27))))
        )
        (pin passive line (at 5.08 0 180) (length 2.032)
          (name "~" (effects (font (size 1.27 1.27))))
          (number "2" (effects (font (size 1.27 1.27))))
        )
      )
    )
	(symbol "data-center-rdimm-ddr4-tester:C_100n_0201_31" (pin_numbers hide) (pin_names hide) (in_bom yes) (on_board yes)
      (property "Reference" "C" (at 20.32 -5.08 0)
        (effects (font (size 1.27 1.27) (thickness 0.15)) (justify left bottom))
      )
      (property "Value" "C_100n_0201_31" (at 20.32 -10.16 0)
        (effects (font (size 1.27 1.27) (thickness 0.15)) (justify left bottom) hide)
      )
      (property "Footprint" "data-center-rdimm-ddr4-tester-footprints:C_0201" (at 20.32 -12.7 0)
        (effects (font (size 1.27 1.27) (thickness 0.15)) (justify left bottom) hide)
      )
      (property "Datasheet" " " (at 20.32 -15.24 0)
        (effects (font (size 1.27 1.27) (thickness 0.15)) (justify left bottom) hide)
      )
      (property "MPN" "CC0201KRX6S5BB104" (at 20.32 -17.78 0)
        (effects (font (size 1.27 1.27) (thickness 0.15)) (justify left bottom) hide)
      )
      (property "Manufacturer" "Yaego" (at 20.32 -20.32 0)
        (effects (font (size 1.27 1.27) (thickness 0.15)) (justify left bottom) hide)
      )
      (property "License" "Apache-2.0" (at 20.32 -22.86 0)
        (effects (font (size 1.27 1.27) (thickness 0.15)) (justify left bottom) hide)
      )
      (property "Author" "Antmicro" (at 20.32 -25.4 0)
        (effects (font (size 1.27 1.27) (thickness 0.15)) (justify left bottom) hide)
      )
      (property "Val" "100n" (at 20.32 -7.62 0)
        (effects (font (size 1.27 1.27) (thickness 0.15)) (justify left bottom))
      )
      (property "Voltage" "" (at 20.32 -27.94 0)
        (effects (font (size 1.27 1.27)) (justify left bottom) hide)
      )
      (property "Dielectric" "" (at 20.32 -30.48 0)
        (effects (font (size 1.27 1.27)) (justify left bottom) hide)
      )
      (property "ki_description" " " (at 0 0 0)
        (effects (font (size 1.27 1.27)) hide)
      )
      (symbol "C_100n_0201_31_0_1"
        (polyline
          (pts
            (xy 2.032 -1.524)
            (xy 2.032 1.524)
          )
          (stroke (width 0.3048) (type default))
          (fill (type none))
        )
        (polyline
          (pts
            (xy 3.048 -1.524)
            (xy 3.048 1.524)
          )
          (stroke (width 0.3302) (type default))
          (fill (type none))
        )
      )
      (symbol "C_100n_0201_31_1_1"
        (pin passive line (at 0 0 0) (length 2.032)
          (name "~" (effects (font (size 1.27 1.27))))
          (number "1" (effects (font (size 1.27 1.27))))
        )
        (pin passive line (at 5.08 0 180) (length 2.032)
          (name "~" (effects (font (size 1.27 1.27))))
          (number "2" (effects (font (size 1.27 1.27))))
        )
      )
    )
	(symbol "data-center-rdimm-ddr4-tester:C_100n_0201_32" (pin_numbers hide) (pin_names hide) (in_bom yes) (on_board yes)
      (property "Reference" "C" (at 20.32 -5.08 0)
        (effects (font (size 1.27 1.27) (thickness 0.15)) (justify left bottom))
      )
      (property "Value" "C_100n_0201_32" (at 20.32 -10.16 0)
        (effects (font (size 1.27 1.27) (thickness 0.15)) (justify left bottom) hide)
      )
      (property "Footprint" "data-center-rdimm-ddr4-tester-footprints:C_0201" (at 20.32 -12.7 0)
        (effects (font (size 1.27 1.27) (thickness 0.15)) (justify left bottom) hide)
      )
      (property "Datasheet" " " (at 20.32 -15.24 0)
        (effects (font (size 1.27 1.27) (thickness 0.15)) (justify left bottom) hide)
      )
      (property "MPN" "CC0201KRX6S5BB104" (at 20.32 -17.78 0)
        (effects (font (size 1.27 1.27) (thickness 0.15)) (justify left bottom) hide)
      )
      (property "Manufacturer" "Yaego" (at 20.32 -20.32 0)
        (effects (font (size 1.27 1.27) (thickness 0.15)) (justify left bottom) hide)
      )
      (property "License" "Apache-2.0" (at 20.32 -22.86 0)
        (effects (font (size 1.27 1.27) (thickness 0.15)) (justify left bottom) hide)
      )
      (property "Author" "Antmicro" (at 20.32 -25.4 0)
        (effects (font (size 1.27 1.27) (thickness 0.15)) (justify left bottom) hide)
      )
      (property "Val" "100n" (at 20.32 -7.62 0)
        (effects (font (size 1.27 1.27) (thickness 0.15)) (justify left bottom))
      )
      (property "Voltage" "" (at 20.32 -27.94 0)
        (effects (font (size 1.27 1.27)) (justify left bottom) hide)
      )
      (property "Dielectric" "" (at 20.32 -30.48 0)
        (effects (font (size 1.27 1.27)) (justify left bottom) hide)
      )
      (property "ki_description" " " (at 0 0 0)
        (effects (font (size 1.27 1.27)) hide)
      )
      (symbol "C_100n_0201_32_0_1"
        (polyline
          (pts
            (xy 2.032 -1.524)
            (xy 2.032 1.524)
          )
          (stroke (width 0.3048) (type default))
          (fill (type none))
        )
        (polyline
          (pts
            (xy 3.048 -1.524)
            (xy 3.048 1.524)
          )
          (stroke (width 0.3302) (type default))
          (fill (type none))
        )
      )
      (symbol "C_100n_0201_32_1_1"
        (pin passive line (at 0 0 0) (length 2.032)
          (name "~" (effects (font (size 1.27 1.27))))
          (number "1" (effects (font (size 1.27 1.27))))
        )
        (pin passive line (at 5.08 0 180) (length 2.032)
          (name "~" (effects (font (size 1.27 1.27))))
          (number "2" (effects (font (size 1.27 1.27))))
        )
      )
    )
	(symbol "data-center-rdimm-ddr4-tester:C_100n_0201_33" (pin_numbers hide) (pin_names hide) (in_bom yes) (on_board yes)
      (property "Reference" "C" (at 20.32 -5.08 0)
        (effects (font (size 1.27 1.27) (thickness 0.15)) (justify left bottom))
      )
      (property "Value" "C_100n_0201_33" (at 20.32 -10.16 0)
        (effects (font (size 1.27 1.27) (thickness 0.15)) (justify left bottom) hide)
      )
      (property "Footprint" "data-center-rdimm-ddr4-tester-footprints:C_0201" (at 20.32 -12.7 0)
        (effects (font (size 1.27 1.27) (thickness 0.15)) (justify left bottom) hide)
      )
      (property "Datasheet" " " (at 20.32 -15.24 0)
        (effects (font (size 1.27 1.27) (thickness 0.15)) (justify left bottom) hide)
      )
      (property "MPN" "CC0201KRX6S5BB104" (at 20.32 -17.78 0)
        (effects (font (size 1.27 1.27) (thickness 0.15)) (justify left bottom) hide)
      )
      (property "Manufacturer" "Yaego" (at 20.32 -20.32 0)
        (effects (font (size 1.27 1.27) (thickness 0.15)) (justify left bottom) hide)
      )
      (property "License" "Apache-2.0" (at 20.32 -22.86 0)
        (effects (font (size 1.27 1.27) (thickness 0.15)) (justify left bottom) hide)
      )
      (property "Author" "Antmicro" (at 20.32 -25.4 0)
        (effects (font (size 1.27 1.27) (thickness 0.15)) (justify left bottom) hide)
      )
      (property "Val" "100n" (at 20.32 -7.62 0)
        (effects (font (size 1.27 1.27) (thickness 0.15)) (justify left bottom))
      )
      (property "Voltage" "" (at 20.32 -27.94 0)
        (effects (font (size 1.27 1.27)) (justify left bottom) hide)
      )
      (property "Dielectric" "" (at 20.32 -30.48 0)
        (effects (font (size 1.27 1.27)) (justify left bottom) hide)
      )
      (property "ki_description" " " (at 0 0 0)
        (effects (font (size 1.27 1.27)) hide)
      )
      (symbol "C_100n_0201_33_0_1"
        (polyline
          (pts
            (xy 2.032 -1.524)
            (xy 2.032 1.524)
          )
          (stroke (width 0.3048) (type default))
          (fill (type none))
        )
        (polyline
          (pts
            (xy 3.048 -1.524)
            (xy 3.048 1.524)
          )
          (stroke (width 0.3302) (type default))
          (fill (type none))
        )
      )
      (symbol "C_100n_0201_33_1_1"
        (pin passive line (at 0 0 0) (length 2.032)
          (name "~" (effects (font (size 1.27 1.27))))
          (number "1" (effects (font (size 1.27 1.27))))
        )
        (pin passive line (at 5.08 0 180) (length 2.032)
          (name "~" (effects (font (size 1.27 1.27))))
          (number "2" (effects (font (size 1.27 1.27))))
        )
      )
    )
	(symbol "data-center-rdimm-ddr4-tester:C_100n_0201_34" (pin_numbers hide) (pin_names hide) (in_bom yes) (on_board yes)
      (property "Reference" "C" (at 20.32 -5.08 0)
        (effects (font (size 1.27 1.27) (thickness 0.15)) (justify left bottom))
      )
      (property "Value" "C_100n_0201_34" (at 20.32 -10.16 0)
        (effects (font (size 1.27 1.27) (thickness 0.15)) (justify left bottom) hide)
      )
      (property "Footprint" "data-center-rdimm-ddr4-tester-footprints:C_0201" (at 20.32 -12.7 0)
        (effects (font (size 1.27 1.27) (thickness 0.15)) (justify left bottom) hide)
      )
      (property "Datasheet" " " (at 20.32 -15.24 0)
        (effects (font (size 1.27 1.27) (thickness 0.15)) (justify left bottom) hide)
      )
      (property "MPN" "CC0201KRX6S5BB104" (at 20.32 -17.78 0)
        (effects (font (size 1.27 1.27) (thickness 0.15)) (justify left bottom) hide)
      )
      (property "Manufacturer" "Yaego" (at 20.32 -20.32 0)
        (effects (font (size 1.27 1.27) (thickness 0.15)) (justify left bottom) hide)
      )
      (property "License" "Apache-2.0" (at 20.32 -22.86 0)
        (effects (font (size 1.27 1.27) (thickness 0.15)) (justify left bottom) hide)
      )
      (property "Author" "Antmicro" (at 20.32 -25.4 0)
        (effects (font (size 1.27 1.27) (thickness 0.15)) (justify left bottom) hide)
      )
      (property "Val" "100n" (at 20.32 -7.62 0)
        (effects (font (size 1.27 1.27) (thickness 0.15)) (justify left bottom))
      )
      (property "Voltage" "" (at 20.32 -27.94 0)
        (effects (font (size 1.27 1.27)) (justify left bottom) hide)
      )
      (property "Dielectric" "" (at 20.32 -30.48 0)
        (effects (font (size 1.27 1.27)) (justify left bottom) hide)
      )
      (property "ki_description" " " (at 0 0 0)
        (effects (font (size 1.27 1.27)) hide)
      )
      (symbol "C_100n_0201_34_0_1"
        (polyline
          (pts
            (xy 2.032 -1.524)
            (xy 2.032 1.524)
          )
          (stroke (width 0.3048) (type default))
          (fill (type none))
        )
        (polyline
          (pts
            (xy 3.048 -1.524)
            (xy 3.048 1.524)
          )
          (stroke (width 0.3302) (type default))
          (fill (type none))
        )
      )
      (symbol "C_100n_0201_34_1_1"
        (pin passive line (at 0 0 0) (length 2.032)
          (name "~" (effects (font (size 1.27 1.27))))
          (number "1" (effects (font (size 1.27 1.27))))
        )
        (pin passive line (at 5.08 0 180) (length 2.032)
          (name "~" (effects (font (size 1.27 1.27))))
          (number "2" (effects (font (size 1.27 1.27))))
        )
      )
    )
	(symbol "data-center-rdimm-ddr4-tester:C_100n_0201_35" (pin_numbers hide) (pin_names hide) (in_bom yes) (on_board yes)
      (property "Reference" "C" (at 20.32 -5.08 0)
        (effects (font (size 1.27 1.27) (thickness 0.15)) (justify left bottom))
      )
      (property "Value" "C_100n_0201_35" (at 20.32 -10.16 0)
        (effects (font (size 1.27 1.27) (thickness 0.15)) (justify left bottom) hide)
      )
      (property "Footprint" "data-center-rdimm-ddr4-tester-footprints:C_0201" (at 20.32 -12.7 0)
        (effects (font (size 1.27 1.27) (thickness 0.15)) (justify left bottom) hide)
      )
      (property "Datasheet" " " (at 20.32 -15.24 0)
        (effects (font (size 1.27 1.27) (thickness 0.15)) (justify left bottom) hide)
      )
      (property "MPN" "CC0201KRX6S5BB104" (at 20.32 -17.78 0)
        (effects (font (size 1.27 1.27) (thickness 0.15)) (justify left bottom) hide)
      )
      (property "Manufacturer" "Yaego" (at 20.32 -20.32 0)
        (effects (font (size 1.27 1.27) (thickness 0.15)) (justify left bottom) hide)
      )
      (property "License" "Apache-2.0" (at 20.32 -22.86 0)
        (effects (font (size 1.27 1.27) (thickness 0.15)) (justify left bottom) hide)
      )
      (property "Author" "Antmicro" (at 20.32 -25.4 0)
        (effects (font (size 1.27 1.27) (thickness 0.15)) (justify left bottom) hide)
      )
      (property "Val" "100n" (at 20.32 -7.62 0)
        (effects (font (size 1.27 1.27) (thickness 0.15)) (justify left bottom))
      )
      (property "Voltage" "" (at 20.32 -27.94 0)
        (effects (font (size 1.27 1.27)) (justify left bottom) hide)
      )
      (property "Dielectric" "" (at 20.32 -30.48 0)
        (effects (font (size 1.27 1.27)) (justify left bottom) hide)
      )
      (property "ki_description" " " (at 0 0 0)
        (effects (font (size 1.27 1.27)) hide)
      )
      (symbol "C_100n_0201_35_0_1"
        (polyline
          (pts
            (xy 2.032 -1.524)
            (xy 2.032 1.524)
          )
          (stroke (width 0.3048) (type default))
          (fill (type none))
        )
        (polyline
          (pts
            (xy 3.048 -1.524)
            (xy 3.048 1.524)
          )
          (stroke (width 0.3302) (type default))
          (fill (type none))
        )
      )
      (symbol "C_100n_0201_35_1_1"
        (pin passive line (at 0 0 0) (length 2.032)
          (name "~" (effects (font (size 1.27 1.27))))
          (number "1" (effects (font (size 1.27 1.27))))
        )
        (pin passive line (at 5.08 0 180) (length 2.032)
          (name "~" (effects (font (size 1.27 1.27))))
          (number "2" (effects (font (size 1.27 1.27))))
        )
      )
    )
	(symbol "data-center-rdimm-ddr4-tester:C_100n_0201_36" (pin_numbers hide) (pin_names hide) (in_bom yes) (on_board yes)
      (property "Reference" "C" (at 20.32 -5.08 0)
        (effects (font (size 1.27 1.27) (thickness 0.15)) (justify left bottom))
      )
      (property "Value" "C_100n_0201_36" (at 20.32 -10.16 0)
        (effects (font (size 1.27 1.27) (thickness 0.15)) (justify left bottom) hide)
      )
      (property "Footprint" "data-center-rdimm-ddr4-tester-footprints:C_0201" (at 20.32 -12.7 0)
        (effects (font (size 1.27 1.27) (thickness 0.15)) (justify left bottom) hide)
      )
      (property "Datasheet" " " (at 20.32 -15.24 0)
        (effects (font (size 1.27 1.27) (thickness 0.15)) (justify left bottom) hide)
      )
      (property "MPN" "CC0201KRX6S5BB104" (at 20.32 -17.78 0)
        (effects (font (size 1.27 1.27) (thickness 0.15)) (justify left bottom) hide)
      )
      (property "Manufacturer" "Yaego" (at 20.32 -20.32 0)
        (effects (font (size 1.27 1.27) (thickness 0.15)) (justify left bottom) hide)
      )
      (property "License" "Apache-2.0" (at 20.32 -22.86 0)
        (effects (font (size 1.27 1.27) (thickness 0.15)) (justify left bottom) hide)
      )
      (property "Author" "Antmicro" (at 20.32 -25.4 0)
        (effects (font (size 1.27 1.27) (thickness 0.15)) (justify left bottom) hide)
      )
      (property "Val" "100n" (at 20.32 -7.62 0)
        (effects (font (size 1.27 1.27) (thickness 0.15)) (justify left bottom))
      )
      (property "Voltage" "" (at 20.32 -27.94 0)
        (effects (font (size 1.27 1.27)) (justify left bottom) hide)
      )
      (property "Dielectric" "" (at 20.32 -30.48 0)
        (effects (font (size 1.27 1.27)) (justify left bottom) hide)
      )
      (property "ki_description" " " (at 0 0 0)
        (effects (font (size 1.27 1.27)) hide)
      )
      (symbol "C_100n_0201_36_0_1"
        (polyline
          (pts
            (xy 2.032 -1.524)
            (xy 2.032 1.524)
          )
          (stroke (width 0.3048) (type default))
          (fill (type none))
        )
        (polyline
          (pts
            (xy 3.048 -1.524)
            (xy 3.048 1.524)
          )
          (stroke (width 0.3302) (type default))
          (fill (type none))
        )
      )
      (symbol "C_100n_0201_36_1_1"
        (pin passive line (at 0 0 0) (length 2.032)
          (name "~" (effects (font (size 1.27 1.27))))
          (number "1" (effects (font (size 1.27 1.27))))
        )
        (pin passive line (at 5.08 0 180) (length 2.032)
          (name "~" (effects (font (size 1.27 1.27))))
          (number "2" (effects (font (size 1.27 1.27))))
        )
      )
    )
	(symbol "data-center-rdimm-ddr4-tester:C_100n_0201_37" (pin_numbers hide) (pin_names hide) (in_bom yes) (on_board yes)
      (property "Reference" "C" (at 20.32 -5.08 0)
        (effects (font (size 1.27 1.27) (thickness 0.15)) (justify left bottom))
      )
      (property "Value" "C_100n_0201_37" (at 20.32 -10.16 0)
        (effects (font (size 1.27 1.27) (thickness 0.15)) (justify left bottom) hide)
      )
      (property "Footprint" "data-center-rdimm-ddr4-tester-footprints:C_0201" (at 20.32 -12.7 0)
        (effects (font (size 1.27 1.27) (thickness 0.15)) (justify left bottom) hide)
      )
      (property "Datasheet" " " (at 20.32 -15.24 0)
        (effects (font (size 1.27 1.27) (thickness 0.15)) (justify left bottom) hide)
      )
      (property "MPN" "CC0201KRX6S5BB104" (at 20.32 -17.78 0)
        (effects (font (size 1.27 1.27) (thickness 0.15)) (justify left bottom) hide)
      )
      (property "Manufacturer" "Yaego" (at 20.32 -20.32 0)
        (effects (font (size 1.27 1.27) (thickness 0.15)) (justify left bottom) hide)
      )
      (property "License" "Apache-2.0" (at 20.32 -22.86 0)
        (effects (font (size 1.27 1.27) (thickness 0.15)) (justify left bottom) hide)
      )
      (property "Author" "Antmicro" (at 20.32 -25.4 0)
        (effects (font (size 1.27 1.27) (thickness 0.15)) (justify left bottom) hide)
      )
      (property "Val" "100n" (at 20.32 -7.62 0)
        (effects (font (size 1.27 1.27) (thickness 0.15)) (justify left bottom))
      )
      (property "Voltage" "" (at 20.32 -27.94 0)
        (effects (font (size 1.27 1.27)) (justify left bottom) hide)
      )
      (property "Dielectric" "" (at 20.32 -30.48 0)
        (effects (font (size 1.27 1.27)) (justify left bottom) hide)
      )
      (property "ki_description" " " (at 0 0 0)
        (effects (font (size 1.27 1.27)) hide)
      )
      (symbol "C_100n_0201_37_0_1"
        (polyline
          (pts
            (xy 2.032 -1.524)
            (xy 2.032 1.524)
          )
          (stroke (width 0.3048) (type default))
          (fill (type none))
        )
        (polyline
          (pts
            (xy 3.048 -1.524)
            (xy 3.048 1.524)
          )
          (stroke (width 0.3302) (type default))
          (fill (type none))
        )
      )
      (symbol "C_100n_0201_37_1_1"
        (pin passive line (at 0 0 0) (length 2.032)
          (name "~" (effects (font (size 1.27 1.27))))
          (number "1" (effects (font (size 1.27 1.27))))
        )
        (pin passive line (at 5.08 0 180) (length 2.032)
          (name "~" (effects (font (size 1.27 1.27))))
          (number "2" (effects (font (size 1.27 1.27))))
        )
      )
    )
	(symbol "data-center-rdimm-ddr4-tester:C_100n_0201_38" (pin_numbers hide) (pin_names hide) (in_bom yes) (on_board yes)
      (property "Reference" "C" (at 20.32 -5.08 0)
        (effects (font (size 1.27 1.27) (thickness 0.15)) (justify left bottom))
      )
      (property "Value" "C_100n_0201_38" (at 20.32 -10.16 0)
        (effects (font (size 1.27 1.27) (thickness 0.15)) (justify left bottom) hide)
      )
      (property "Footprint" "data-center-rdimm-ddr4-tester-footprints:C_0201" (at 20.32 -12.7 0)
        (effects (font (size 1.27 1.27) (thickness 0.15)) (justify left bottom) hide)
      )
      (property "Datasheet" " " (at 20.32 -15.24 0)
        (effects (font (size 1.27 1.27) (thickness 0.15)) (justify left bottom) hide)
      )
      (property "MPN" "CC0201KRX6S5BB104" (at 20.32 -17.78 0)
        (effects (font (size 1.27 1.27) (thickness 0.15)) (justify left bottom) hide)
      )
      (property "Manufacturer" "Yaego" (at 20.32 -20.32 0)
        (effects (font (size 1.27 1.27) (thickness 0.15)) (justify left bottom) hide)
      )
      (property "License" "Apache-2.0" (at 20.32 -22.86 0)
        (effects (font (size 1.27 1.27) (thickness 0.15)) (justify left bottom) hide)
      )
      (property "Author" "Antmicro" (at 20.32 -25.4 0)
        (effects (font (size 1.27 1.27) (thickness 0.15)) (justify left bottom) hide)
      )
      (property "Val" "100n" (at 20.32 -7.62 0)
        (effects (font (size 1.27 1.27) (thickness 0.15)) (justify left bottom))
      )
      (property "Voltage" "" (at 20.32 -27.94 0)
        (effects (font (size 1.27 1.27)) (justify left bottom) hide)
      )
      (property "Dielectric" "" (at 20.32 -30.48 0)
        (effects (font (size 1.27 1.27)) (justify left bottom) hide)
      )
      (property "ki_description" " " (at 0 0 0)
        (effects (font (size 1.27 1.27)) hide)
      )
      (symbol "C_100n_0201_38_0_1"
        (polyline
          (pts
            (xy 2.032 -1.524)
            (xy 2.032 1.524)
          )
          (stroke (width 0.3048) (type default))
          (fill (type none))
        )
        (polyline
          (pts
            (xy 3.048 -1.524)
            (xy 3.048 1.524)
          )
          (stroke (width 0.3302) (type default))
          (fill (type none))
        )
      )
      (symbol "C_100n_0201_38_1_1"
        (pin passive line (at 0 0 0) (length 2.032)
          (name "~" (effects (font (size 1.27 1.27))))
          (number "1" (effects (font (size 1.27 1.27))))
        )
        (pin passive line (at 5.08 0 180) (length 2.032)
          (name "~" (effects (font (size 1.27 1.27))))
          (number "2" (effects (font (size 1.27 1.27))))
        )
      )
    )
	(symbol "data-center-rdimm-ddr4-tester:C_100n_0201_39" (pin_numbers hide) (pin_names hide) (in_bom yes) (on_board yes)
      (property "Reference" "C" (at 20.32 -5.08 0)
        (effects (font (size 1.27 1.27) (thickness 0.15)) (justify left bottom))
      )
      (property "Value" "C_100n_0201_39" (at 20.32 -10.16 0)
        (effects (font (size 1.27 1.27) (thickness 0.15)) (justify left bottom) hide)
      )
      (property "Footprint" "data-center-rdimm-ddr4-tester-footprints:C_0201" (at 20.32 -12.7 0)
        (effects (font (size 1.27 1.27) (thickness 0.15)) (justify left bottom) hide)
      )
      (property "Datasheet" " " (at 20.32 -15.24 0)
        (effects (font (size 1.27 1.27) (thickness 0.15)) (justify left bottom) hide)
      )
      (property "MPN" "CC0201KRX6S5BB104" (at 20.32 -17.78 0)
        (effects (font (size 1.27 1.27) (thickness 0.15)) (justify left bottom) hide)
      )
      (property "Manufacturer" "Yaego" (at 20.32 -20.32 0)
        (effects (font (size 1.27 1.27) (thickness 0.15)) (justify left bottom) hide)
      )
      (property "License" "Apache-2.0" (at 20.32 -22.86 0)
        (effects (font (size 1.27 1.27) (thickness 0.15)) (justify left bottom) hide)
      )
      (property "Author" "Antmicro" (at 20.32 -25.4 0)
        (effects (font (size 1.27 1.27) (thickness 0.15)) (justify left bottom) hide)
      )
      (property "Val" "100n" (at 20.32 -7.62 0)
        (effects (font (size 1.27 1.27) (thickness 0.15)) (justify left bottom))
      )
      (property "Voltage" "" (at 20.32 -27.94 0)
        (effects (font (size 1.27 1.27)) (justify left bottom) hide)
      )
      (property "Dielectric" "" (at 20.32 -30.48 0)
        (effects (font (size 1.27 1.27)) (justify left bottom) hide)
      )
      (property "ki_description" " " (at 0 0 0)
        (effects (font (size 1.27 1.27)) hide)
      )
      (symbol "C_100n_0201_39_0_1"
        (polyline
          (pts
            (xy 2.032 -1.524)
            (xy 2.032 1.524)
          )
          (stroke (width 0.3048) (type default))
          (fill (type none))
        )
        (polyline
          (pts
            (xy 3.048 -1.524)
            (xy 3.048 1.524)
          )
          (stroke (width 0.3302) (type default))
          (fill (type none))
        )
      )
      (symbol "C_100n_0201_39_1_1"
        (pin passive line (at 0 0 0) (length 2.032)
          (name "~" (effects (font (size 1.27 1.27))))
          (number "1" (effects (font (size 1.27 1.27))))
        )
        (pin passive line (at 5.08 0 180) (length 2.032)
          (name "~" (effects (font (size 1.27 1.27))))
          (number "2" (effects (font (size 1.27 1.27))))
        )
      )
    )
	(symbol "data-center-rdimm-ddr4-tester:C_100n_0201_40" (pin_numbers hide) (pin_names hide) (in_bom yes) (on_board yes)
      (property "Reference" "C" (at 20.32 -5.08 0)
        (effects (font (size 1.27 1.27) (thickness 0.15)) (justify left bottom))
      )
      (property "Value" "C_100n_0201_40" (at 20.32 -10.16 0)
        (effects (font (size 1.27 1.27) (thickness 0.15)) (justify left bottom) hide)
      )
      (property "Footprint" "data-center-rdimm-ddr4-tester-footprints:C_0201" (at 20.32 -12.7 0)
        (effects (font (size 1.27 1.27) (thickness 0.15)) (justify left bottom) hide)
      )
      (property "Datasheet" " " (at 20.32 -15.24 0)
        (effects (font (size 1.27 1.27) (thickness 0.15)) (justify left bottom) hide)
      )
      (property "MPN" "CC0201KRX6S5BB104" (at 20.32 -17.78 0)
        (effects (font (size 1.27 1.27) (thickness 0.15)) (justify left bottom) hide)
      )
      (property "Manufacturer" "Yaego" (at 20.32 -20.32 0)
        (effects (font (size 1.27 1.27) (thickness 0.15)) (justify left bottom) hide)
      )
      (property "License" "Apache-2.0" (at 20.32 -22.86 0)
        (effects (font (size 1.27 1.27) (thickness 0.15)) (justify left bottom) hide)
      )
      (property "Author" "Antmicro" (at 20.32 -25.4 0)
        (effects (font (size 1.27 1.27) (thickness 0.15)) (justify left bottom) hide)
      )
      (property "Val" "100n" (at 20.32 -7.62 0)
        (effects (font (size 1.27 1.27) (thickness 0.15)) (justify left bottom))
      )
      (property "Voltage" "" (at 20.32 -27.94 0)
        (effects (font (size 1.27 1.27)) (justify left bottom) hide)
      )
      (property "Dielectric" "" (at 20.32 -30.48 0)
        (effects (font (size 1.27 1.27)) (justify left bottom) hide)
      )
      (property "ki_description" " " (at 0 0 0)
        (effects (font (size 1.27 1.27)) hide)
      )
      (symbol "C_100n_0201_40_0_1"
        (polyline
          (pts
            (xy 2.032 -1.524)
            (xy 2.032 1.524)
          )
          (stroke (width 0.3048) (type default))
          (fill (type none))
        )
        (polyline
          (pts
            (xy 3.048 -1.524)
            (xy 3.048 1.524)
          )
          (stroke (width 0.3302) (type default))
          (fill (type none))
        )
      )
      (symbol "C_100n_0201_40_1_1"
        (pin passive line (at 0 0 0) (length 2.032)
          (name "~" (effects (font (size 1.27 1.27))))
          (number "1" (effects (font (size 1.27 1.27))))
        )
        (pin passive line (at 5.08 0 180) (length 2.032)
          (name "~" (effects (font (size 1.27 1.27))))
          (number "2" (effects (font (size 1.27 1.27))))
        )
      )
    )
	(symbol "data-center-rdimm-ddr4-tester:C_100n_0201_41" (pin_numbers hide) (pin_names hide) (in_bom yes) (on_board yes)
      (property "Reference" "C" (at 20.32 -5.08 0)
        (effects (font (size 1.27 1.27) (thickness 0.15)) (justify left bottom))
      )
      (property "Value" "C_100n_0201_41" (at 20.32 -10.16 0)
        (effects (font (size 1.27 1.27) (thickness 0.15)) (justify left bottom) hide)
      )
      (property "Footprint" "data-center-rdimm-ddr4-tester-footprints:C_0201" (at 20.32 -12.7 0)
        (effects (font (size 1.27 1.27) (thickness 0.15)) (justify left bottom) hide)
      )
      (property "Datasheet" " " (at 20.32 -15.24 0)
        (effects (font (size 1.27 1.27) (thickness 0.15)) (justify left bottom) hide)
      )
      (property "MPN" "CC0201KRX6S5BB104" (at 20.32 -17.78 0)
        (effects (font (size 1.27 1.27) (thickness 0.15)) (justify left bottom) hide)
      )
      (property "Manufacturer" "Yaego" (at 20.32 -20.32 0)
        (effects (font (size 1.27 1.27) (thickness 0.15)) (justify left bottom) hide)
      )
      (property "License" "Apache-2.0" (at 20.32 -22.86 0)
        (effects (font (size 1.27 1.27) (thickness 0.15)) (justify left bottom) hide)
      )
      (property "Author" "Antmicro" (at 20.32 -25.4 0)
        (effects (font (size 1.27 1.27) (thickness 0.15)) (justify left bottom) hide)
      )
      (property "Val" "100n" (at 20.32 -7.62 0)
        (effects (font (size 1.27 1.27) (thickness 0.15)) (justify left bottom))
      )
      (property "Voltage" "" (at 20.32 -27.94 0)
        (effects (font (size 1.27 1.27)) (justify left bottom) hide)
      )
      (property "Dielectric" "" (at 20.32 -30.48 0)
        (effects (font (size 1.27 1.27)) (justify left bottom) hide)
      )
      (property "ki_description" " " (at 0 0 0)
        (effects (font (size 1.27 1.27)) hide)
      )
      (symbol "C_100n_0201_41_0_1"
        (polyline
          (pts
            (xy 2.032 -1.524)
            (xy 2.032 1.524)
          )
          (stroke (width 0.3048) (type default))
          (fill (type none))
        )
        (polyline
          (pts
            (xy 3.048 -1.524)
            (xy 3.048 1.524)
          )
          (stroke (width 0.3302) (type default))
          (fill (type none))
        )
      )
      (symbol "C_100n_0201_41_1_1"
        (pin passive line (at 0 0 0) (length 2.032)
          (name "~" (effects (font (size 1.27 1.27))))
          (number "1" (effects (font (size 1.27 1.27))))
        )
        (pin passive line (at 5.08 0 180) (length 2.032)
          (name "~" (effects (font (size 1.27 1.27))))
          (number "2" (effects (font (size 1.27 1.27))))
        )
      )
    )
	(symbol "data-center-rdimm-ddr4-tester:C_100n_0201_42" (pin_numbers hide) (pin_names hide) (in_bom yes) (on_board yes)
      (property "Reference" "C" (at 20.32 -5.08 0)
        (effects (font (size 1.27 1.27) (thickness 0.15)) (justify left bottom))
      )
      (property "Value" "C_100n_0201_42" (at 20.32 -10.16 0)
        (effects (font (size 1.27 1.27) (thickness 0.15)) (justify left bottom) hide)
      )
      (property "Footprint" "data-center-rdimm-ddr4-tester-footprints:C_0201" (at 20.32 -12.7 0)
        (effects (font (size 1.27 1.27) (thickness 0.15)) (justify left bottom) hide)
      )
      (property "Datasheet" " " (at 20.32 -15.24 0)
        (effects (font (size 1.27 1.27) (thickness 0.15)) (justify left bottom) hide)
      )
      (property "MPN" "CC0201KRX6S5BB104" (at 20.32 -17.78 0)
        (effects (font (size 1.27 1.27) (thickness 0.15)) (justify left bottom) hide)
      )
      (property "Manufacturer" "Yaego" (at 20.32 -20.32 0)
        (effects (font (size 1.27 1.27) (thickness 0.15)) (justify left bottom) hide)
      )
      (property "License" "Apache-2.0" (at 20.32 -22.86 0)
        (effects (font (size 1.27 1.27) (thickness 0.15)) (justify left bottom) hide)
      )
      (property "Author" "Antmicro" (at 20.32 -25.4 0)
        (effects (font (size 1.27 1.27) (thickness 0.15)) (justify left bottom) hide)
      )
      (property "Val" "100n" (at 20.32 -7.62 0)
        (effects (font (size 1.27 1.27) (thickness 0.15)) (justify left bottom))
      )
      (property "Voltage" "" (at 20.32 -27.94 0)
        (effects (font (size 1.27 1.27)) (justify left bottom) hide)
      )
      (property "Dielectric" "" (at 20.32 -30.48 0)
        (effects (font (size 1.27 1.27)) (justify left bottom) hide)
      )
      (property "ki_description" " " (at 0 0 0)
        (effects (font (size 1.27 1.27)) hide)
      )
      (symbol "C_100n_0201_42_0_1"
        (polyline
          (pts
            (xy 2.032 -1.524)
            (xy 2.032 1.524)
          )
          (stroke (width 0.3048) (type default))
          (fill (type none))
        )
        (polyline
          (pts
            (xy 3.048 -1.524)
            (xy 3.048 1.524)
          )
          (stroke (width 0.3302) (type default))
          (fill (type none))
        )
      )
      (symbol "C_100n_0201_42_1_1"
        (pin passive line (at 0 0 0) (length 2.032)
          (name "~" (effects (font (size 1.27 1.27))))
          (number "1" (effects (font (size 1.27 1.27))))
        )
        (pin passive line (at 5.08 0 180) (length 2.032)
          (name "~" (effects (font (size 1.27 1.27))))
          (number "2" (effects (font (size 1.27 1.27))))
        )
      )
    )
	(symbol "data-center-rdimm-ddr4-tester:C_100n_0201_43" (pin_numbers hide) (pin_names hide) (in_bom yes) (on_board yes)
      (property "Reference" "C" (at 20.32 -5.08 0)
        (effects (font (size 1.27 1.27) (thickness 0.15)) (justify left bottom))
      )
      (property "Value" "C_100n_0201_43" (at 20.32 -10.16 0)
        (effects (font (size 1.27 1.27) (thickness 0.15)) (justify left bottom) hide)
      )
      (property "Footprint" "data-center-rdimm-ddr4-tester-footprints:C_0201" (at 20.32 -12.7 0)
        (effects (font (size 1.27 1.27) (thickness 0.15)) (justify left bottom) hide)
      )
      (property "Datasheet" " " (at 20.32 -15.24 0)
        (effects (font (size 1.27 1.27) (thickness 0.15)) (justify left bottom) hide)
      )
      (property "MPN" "CC0201KRX6S5BB104" (at 20.32 -17.78 0)
        (effects (font (size 1.27 1.27) (thickness 0.15)) (justify left bottom) hide)
      )
      (property "Manufacturer" "Yaego" (at 20.32 -20.32 0)
        (effects (font (size 1.27 1.27) (thickness 0.15)) (justify left bottom) hide)
      )
      (property "License" "Apache-2.0" (at 20.32 -22.86 0)
        (effects (font (size 1.27 1.27) (thickness 0.15)) (justify left bottom) hide)
      )
      (property "Author" "Antmicro" (at 20.32 -25.4 0)
        (effects (font (size 1.27 1.27) (thickness 0.15)) (justify left bottom) hide)
      )
      (property "Val" "100n" (at 20.32 -7.62 0)
        (effects (font (size 1.27 1.27) (thickness 0.15)) (justify left bottom))
      )
      (property "Voltage" "" (at 20.32 -27.94 0)
        (effects (font (size 1.27 1.27)) (justify left bottom) hide)
      )
      (property "Dielectric" "" (at 20.32 -30.48 0)
        (effects (font (size 1.27 1.27)) (justify left bottom) hide)
      )
      (property "ki_description" " " (at 0 0 0)
        (effects (font (size 1.27 1.27)) hide)
      )
      (symbol "C_100n_0201_43_0_1"
        (polyline
          (pts
            (xy 2.032 -1.524)
            (xy 2.032 1.524)
          )
          (stroke (width 0.3048) (type default))
          (fill (type none))
        )
        (polyline
          (pts
            (xy 3.048 -1.524)
            (xy 3.048 1.524)
          )
          (stroke (width 0.3302) (type default))
          (fill (type none))
        )
      )
      (symbol "C_100n_0201_43_1_1"
        (pin passive line (at 0 0 0) (length 2.032)
          (name "~" (effects (font (size 1.27 1.27))))
          (number "1" (effects (font (size 1.27 1.27))))
        )
        (pin passive line (at 5.08 0 180) (length 2.032)
          (name "~" (effects (font (size 1.27 1.27))))
          (number "2" (effects (font (size 1.27 1.27))))
        )
      )
    )
	(symbol "data-center-rdimm-ddr4-tester:C_100n_0201_44" (pin_numbers hide) (pin_names hide) (in_bom yes) (on_board yes)
      (property "Reference" "C" (at 20.32 -5.08 0)
        (effects (font (size 1.27 1.27) (thickness 0.15)) (justify left bottom))
      )
      (property "Value" "C_100n_0201_44" (at 20.32 -10.16 0)
        (effects (font (size 1.27 1.27) (thickness 0.15)) (justify left bottom) hide)
      )
      (property "Footprint" "data-center-rdimm-ddr4-tester-footprints:C_0201" (at 20.32 -12.7 0)
        (effects (font (size 1.27 1.27) (thickness 0.15)) (justify left bottom) hide)
      )
      (property "Datasheet" " " (at 20.32 -15.24 0)
        (effects (font (size 1.27 1.27) (thickness 0.15)) (justify left bottom) hide)
      )
      (property "MPN" "CC0201KRX6S5BB104" (at 20.32 -17.78 0)
        (effects (font (size 1.27 1.27) (thickness 0.15)) (justify left bottom) hide)
      )
      (property "Manufacturer" "Yaego" (at 20.32 -20.32 0)
        (effects (font (size 1.27 1.27) (thickness 0.15)) (justify left bottom) hide)
      )
      (property "License" "Apache-2.0" (at 20.32 -22.86 0)
        (effects (font (size 1.27 1.27) (thickness 0.15)) (justify left bottom) hide)
      )
      (property "Author" "Antmicro" (at 20.32 -25.4 0)
        (effects (font (size 1.27 1.27) (thickness 0.15)) (justify left bottom) hide)
      )
      (property "Val" "100n" (at 20.32 -7.62 0)
        (effects (font (size 1.27 1.27) (thickness 0.15)) (justify left bottom))
      )
      (property "Voltage" "" (at 20.32 -27.94 0)
        (effects (font (size 1.27 1.27)) (justify left bottom) hide)
      )
      (property "Dielectric" "" (at 20.32 -30.48 0)
        (effects (font (size 1.27 1.27)) (justify left bottom) hide)
      )
      (property "ki_description" " " (at 0 0 0)
        (effects (font (size 1.27 1.27)) hide)
      )
      (symbol "C_100n_0201_44_0_1"
        (polyline
          (pts
            (xy 2.032 -1.524)
            (xy 2.032 1.524)
          )
          (stroke (width 0.3048) (type default))
          (fill (type none))
        )
        (polyline
          (pts
            (xy 3.048 -1.524)
            (xy 3.048 1.524)
          )
          (stroke (width 0.3302) (type default))
          (fill (type none))
        )
      )
      (symbol "C_100n_0201_44_1_1"
        (pin passive line (at 0 0 0) (length 2.032)
          (name "~" (effects (font (size 1.27 1.27))))
          (number "1" (effects (font (size 1.27 1.27))))
        )
        (pin passive line (at 5.08 0 180) (length 2.032)
          (name "~" (effects (font (size 1.27 1.27))))
          (number "2" (effects (font (size 1.27 1.27))))
        )
      )
    )
	(symbol "data-center-rdimm-ddr4-tester:C_100n_0201_45" (pin_numbers hide) (pin_names hide) (in_bom yes) (on_board yes)
      (property "Reference" "C" (at 20.32 -5.08 0)
        (effects (font (size 1.27 1.27) (thickness 0.15)) (justify left bottom))
      )
      (property "Value" "C_100n_0201_45" (at 20.32 -10.16 0)
        (effects (font (size 1.27 1.27) (thickness 0.15)) (justify left bottom) hide)
      )
      (property "Footprint" "data-center-rdimm-ddr4-tester-footprints:C_0201" (at 20.32 -12.7 0)
        (effects (font (size 1.27 1.27) (thickness 0.15)) (justify left bottom) hide)
      )
      (property "Datasheet" " " (at 20.32 -15.24 0)
        (effects (font (size 1.27 1.27) (thickness 0.15)) (justify left bottom) hide)
      )
      (property "MPN" "CC0201KRX6S5BB104" (at 20.32 -17.78 0)
        (effects (font (size 1.27 1.27) (thickness 0.15)) (justify left bottom) hide)
      )
      (property "Manufacturer" "Yaego" (at 20.32 -20.32 0)
        (effects (font (size 1.27 1.27) (thickness 0.15)) (justify left bottom) hide)
      )
      (property "License" "Apache-2.0" (at 20.32 -22.86 0)
        (effects (font (size 1.27 1.27) (thickness 0.15)) (justify left bottom) hide)
      )
      (property "Author" "Antmicro" (at 20.32 -25.4 0)
        (effects (font (size 1.27 1.27) (thickness 0.15)) (justify left bottom) hide)
      )
      (property "Val" "100n" (at 20.32 -7.62 0)
        (effects (font (size 1.27 1.27) (thickness 0.15)) (justify left bottom))
      )
      (property "Voltage" "" (at 20.32 -27.94 0)
        (effects (font (size 1.27 1.27)) (justify left bottom) hide)
      )
      (property "Dielectric" "" (at 20.32 -30.48 0)
        (effects (font (size 1.27 1.27)) (justify left bottom) hide)
      )
      (property "ki_description" " " (at 0 0 0)
        (effects (font (size 1.27 1.27)) hide)
      )
      (symbol "C_100n_0201_45_0_1"
        (polyline
          (pts
            (xy 2.032 -1.524)
            (xy 2.032 1.524)
          )
          (stroke (width 0.3048) (type default))
          (fill (type none))
        )
        (polyline
          (pts
            (xy 3.048 -1.524)
            (xy 3.048 1.524)
          )
          (stroke (width 0.3302) (type default))
          (fill (type none))
        )
      )
      (symbol "C_100n_0201_45_1_1"
        (pin passive line (at 0 0 0) (length 2.032)
          (name "~" (effects (font (size 1.27 1.27))))
          (number "1" (effects (font (size 1.27 1.27))))
        )
        (pin passive line (at 5.08 0 180) (length 2.032)
          (name "~" (effects (font (size 1.27 1.27))))
          (number "2" (effects (font (size 1.27 1.27))))
        )
      )
    )
	(symbol "data-center-rdimm-ddr4-tester:C_100n_0201_46" (pin_numbers hide) (pin_names hide) (in_bom yes) (on_board yes)
      (property "Reference" "C" (at 20.32 -5.08 0)
        (effects (font (size 1.27 1.27) (thickness 0.15)) (justify left bottom))
      )
      (property "Value" "C_100n_0201_46" (at 20.32 -10.16 0)
        (effects (font (size 1.27 1.27) (thickness 0.15)) (justify left bottom) hide)
      )
      (property "Footprint" "data-center-rdimm-ddr4-tester-footprints:C_0201" (at 20.32 -12.7 0)
        (effects (font (size 1.27 1.27) (thickness 0.15)) (justify left bottom) hide)
      )
      (property "Datasheet" " " (at 20.32 -15.24 0)
        (effects (font (size 1.27 1.27) (thickness 0.15)) (justify left bottom) hide)
      )
      (property "MPN" "CC0201KRX6S5BB104" (at 20.32 -17.78 0)
        (effects (font (size 1.27 1.27) (thickness 0.15)) (justify left bottom) hide)
      )
      (property "Manufacturer" "Yaego" (at 20.32 -20.32 0)
        (effects (font (size 1.27 1.27) (thickness 0.15)) (justify left bottom) hide)
      )
      (property "License" "Apache-2.0" (at 20.32 -22.86 0)
        (effects (font (size 1.27 1.27) (thickness 0.15)) (justify left bottom) hide)
      )
      (property "Author" "Antmicro" (at 20.32 -25.4 0)
        (effects (font (size 1.27 1.27) (thickness 0.15)) (justify left bottom) hide)
      )
      (property "Val" "100n" (at 20.32 -7.62 0)
        (effects (font (size 1.27 1.27) (thickness 0.15)) (justify left bottom))
      )
      (property "Voltage" "" (at 20.32 -27.94 0)
        (effects (font (size 1.27 1.27)) (justify left bottom) hide)
      )
      (property "Dielectric" "" (at 20.32 -30.48 0)
        (effects (font (size 1.27 1.27)) (justify left bottom) hide)
      )
      (property "ki_description" " " (at 0 0 0)
        (effects (font (size 1.27 1.27)) hide)
      )
      (symbol "C_100n_0201_46_0_1"
        (polyline
          (pts
            (xy 2.032 -1.524)
            (xy 2.032 1.524)
          )
          (stroke (width 0.3048) (type default))
          (fill (type none))
        )
        (polyline
          (pts
            (xy 3.048 -1.524)
            (xy 3.048 1.524)
          )
          (stroke (width 0.3302) (type default))
          (fill (type none))
        )
      )
      (symbol "C_100n_0201_46_1_1"
        (pin passive line (at 0 0 0) (length 2.032)
          (name "~" (effects (font (size 1.27 1.27))))
          (number "1" (effects (font (size 1.27 1.27))))
        )
        (pin passive line (at 5.08 0 180) (length 2.032)
          (name "~" (effects (font (size 1.27 1.27))))
          (number "2" (effects (font (size 1.27 1.27))))
        )
      )
    )
	(symbol "data-center-rdimm-ddr4-tester:C_100n_0201_47" (pin_numbers hide) (pin_names hide) (in_bom yes) (on_board yes)
      (property "Reference" "C" (at 20.32 -5.08 0)
        (effects (font (size 1.27 1.27) (thickness 0.15)) (justify left bottom))
      )
      (property "Value" "C_100n_0201_47" (at 20.32 -10.16 0)
        (effects (font (size 1.27 1.27) (thickness 0.15)) (justify left bottom) hide)
      )
      (property "Footprint" "data-center-rdimm-ddr4-tester-footprints:C_0201" (at 20.32 -12.7 0)
        (effects (font (size 1.27 1.27) (thickness 0.15)) (justify left bottom) hide)
      )
      (property "Datasheet" " " (at 20.32 -15.24 0)
        (effects (font (size 1.27 1.27) (thickness 0.15)) (justify left bottom) hide)
      )
      (property "MPN" "CC0201KRX6S5BB104" (at 20.32 -17.78 0)
        (effects (font (size 1.27 1.27) (thickness 0.15)) (justify left bottom) hide)
      )
      (property "Manufacturer" "Yaego" (at 20.32 -20.32 0)
        (effects (font (size 1.27 1.27) (thickness 0.15)) (justify left bottom) hide)
      )
      (property "License" "Apache-2.0" (at 20.32 -22.86 0)
        (effects (font (size 1.27 1.27) (thickness 0.15)) (justify left bottom) hide)
      )
      (property "Author" "Antmicro" (at 20.32 -25.4 0)
        (effects (font (size 1.27 1.27) (thickness 0.15)) (justify left bottom) hide)
      )
      (property "Val" "100n" (at 20.32 -7.62 0)
        (effects (font (size 1.27 1.27) (thickness 0.15)) (justify left bottom))
      )
      (property "Voltage" "" (at 20.32 -27.94 0)
        (effects (font (size 1.27 1.27)) (justify left bottom) hide)
      )
      (property "Dielectric" "" (at 20.32 -30.48 0)
        (effects (font (size 1.27 1.27)) (justify left bottom) hide)
      )
      (property "ki_description" " " (at 0 0 0)
        (effects (font (size 1.27 1.27)) hide)
      )
      (symbol "C_100n_0201_47_0_1"
        (polyline
          (pts
            (xy 2.032 -1.524)
            (xy 2.032 1.524)
          )
          (stroke (width 0.3048) (type default))
          (fill (type none))
        )
        (polyline
          (pts
            (xy 3.048 -1.524)
            (xy 3.048 1.524)
          )
          (stroke (width 0.3302) (type default))
          (fill (type none))
        )
      )
      (symbol "C_100n_0201_47_1_1"
        (pin passive line (at 0 0 0) (length 2.032)
          (name "~" (effects (font (size 1.27 1.27))))
          (number "1" (effects (font (size 1.27 1.27))))
        )
        (pin passive line (at 5.08 0 180) (length 2.032)
          (name "~" (effects (font (size 1.27 1.27))))
          (number "2" (effects (font (size 1.27 1.27))))
        )
      )
    )
	(symbol "data-center-rdimm-ddr4-tester:C_100n_0201_48" (pin_numbers hide) (pin_names hide) (in_bom yes) (on_board yes)
      (property "Reference" "C" (at 20.32 -5.08 0)
        (effects (font (size 1.27 1.27) (thickness 0.15)) (justify left bottom))
      )
      (property "Value" "C_100n_0201_48" (at 20.32 -10.16 0)
        (effects (font (size 1.27 1.27) (thickness 0.15)) (justify left bottom) hide)
      )
      (property "Footprint" "data-center-rdimm-ddr4-tester-footprints:C_0201" (at 20.32 -12.7 0)
        (effects (font (size 1.27 1.27) (thickness 0.15)) (justify left bottom) hide)
      )
      (property "Datasheet" " " (at 20.32 -15.24 0)
        (effects (font (size 1.27 1.27) (thickness 0.15)) (justify left bottom) hide)
      )
      (property "MPN" "CC0201KRX6S5BB104" (at 20.32 -17.78 0)
        (effects (font (size 1.27 1.27) (thickness 0.15)) (justify left bottom) hide)
      )
      (property "Manufacturer" "Yaego" (at 20.32 -20.32 0)
        (effects (font (size 1.27 1.27) (thickness 0.15)) (justify left bottom) hide)
      )
      (property "License" "Apache-2.0" (at 20.32 -22.86 0)
        (effects (font (size 1.27 1.27) (thickness 0.15)) (justify left bottom) hide)
      )
      (property "Author" "Antmicro" (at 20.32 -25.4 0)
        (effects (font (size 1.27 1.27) (thickness 0.15)) (justify left bottom) hide)
      )
      (property "Val" "100n" (at 20.32 -7.62 0)
        (effects (font (size 1.27 1.27) (thickness 0.15)) (justify left bottom))
      )
      (property "Voltage" "" (at 20.32 -27.94 0)
        (effects (font (size 1.27 1.27)) (justify left bottom) hide)
      )
      (property "Dielectric" "" (at 20.32 -30.48 0)
        (effects (font (size 1.27 1.27)) (justify left bottom) hide)
      )
      (property "ki_description" " " (at 0 0 0)
        (effects (font (size 1.27 1.27)) hide)
      )
      (symbol "C_100n_0201_48_0_1"
        (polyline
          (pts
            (xy 2.032 -1.524)
            (xy 2.032 1.524)
          )
          (stroke (width 0.3048) (type default))
          (fill (type none))
        )
        (polyline
          (pts
            (xy 3.048 -1.524)
            (xy 3.048 1.524)
          )
          (stroke (width 0.3302) (type default))
          (fill (type none))
        )
      )
      (symbol "C_100n_0201_48_1_1"
        (pin passive line (at 0 0 0) (length 2.032)
          (name "~" (effects (font (size 1.27 1.27))))
          (number "1" (effects (font (size 1.27 1.27))))
        )
        (pin passive line (at 5.08 0 180) (length 2.032)
          (name "~" (effects (font (size 1.27 1.27))))
          (number "2" (effects (font (size 1.27 1.27))))
        )
      )
    )
	(symbol "data-center-rdimm-ddr4-tester:C_100n_0201_49" (pin_numbers hide) (pin_names hide) (in_bom yes) (on_board yes)
      (property "Reference" "C" (at 20.32 -5.08 0)
        (effects (font (size 1.27 1.27) (thickness 0.15)) (justify left bottom))
      )
      (property "Value" "C_100n_0201_49" (at 20.32 -10.16 0)
        (effects (font (size 1.27 1.27) (thickness 0.15)) (justify left bottom) hide)
      )
      (property "Footprint" "data-center-rdimm-ddr4-tester-footprints:C_0201" (at 20.32 -12.7 0)
        (effects (font (size 1.27 1.27) (thickness 0.15)) (justify left bottom) hide)
      )
      (property "Datasheet" " " (at 20.32 -15.24 0)
        (effects (font (size 1.27 1.27) (thickness 0.15)) (justify left bottom) hide)
      )
      (property "MPN" "CC0201KRX6S5BB104" (at 20.32 -17.78 0)
        (effects (font (size 1.27 1.27) (thickness 0.15)) (justify left bottom) hide)
      )
      (property "Manufacturer" "Yaego" (at 20.32 -20.32 0)
        (effects (font (size 1.27 1.27) (thickness 0.15)) (justify left bottom) hide)
      )
      (property "License" "Apache-2.0" (at 20.32 -22.86 0)
        (effects (font (size 1.27 1.27) (thickness 0.15)) (justify left bottom) hide)
      )
      (property "Author" "Antmicro" (at 20.32 -25.4 0)
        (effects (font (size 1.27 1.27) (thickness 0.15)) (justify left bottom) hide)
      )
      (property "Val" "100n" (at 20.32 -7.62 0)
        (effects (font (size 1.27 1.27) (thickness 0.15)) (justify left bottom))
      )
      (property "Voltage" "" (at 20.32 -27.94 0)
        (effects (font (size 1.27 1.27)) (justify left bottom) hide)
      )
      (property "Dielectric" "" (at 20.32 -30.48 0)
        (effects (font (size 1.27 1.27)) (justify left bottom) hide)
      )
      (property "ki_description" " " (at 0 0 0)
        (effects (font (size 1.27 1.27)) hide)
      )
      (symbol "C_100n_0201_49_0_1"
        (polyline
          (pts
            (xy 2.032 -1.524)
            (xy 2.032 1.524)
          )
          (stroke (width 0.3048) (type default))
          (fill (type none))
        )
        (polyline
          (pts
            (xy 3.048 -1.524)
            (xy 3.048 1.524)
          )
          (stroke (width 0.3302) (type default))
          (fill (type none))
        )
      )
      (symbol "C_100n_0201_49_1_1"
        (pin passive line (at 0 0 0) (length 2.032)
          (name "~" (effects (font (size 1.27 1.27))))
          (number "1" (effects (font (size 1.27 1.27))))
        )
        (pin passive line (at 5.08 0 180) (length 2.032)
          (name "~" (effects (font (size 1.27 1.27))))
          (number "2" (effects (font (size 1.27 1.27))))
        )
      )
    )
	(symbol "data-center-rdimm-ddr4-tester:C_100n_0201_50" (pin_numbers hide) (pin_names hide) (in_bom yes) (on_board yes)
      (property "Reference" "C" (at 20.32 -5.08 0)
        (effects (font (size 1.27 1.27) (thickness 0.15)) (justify left bottom))
      )
      (property "Value" "C_100n_0201_50" (at 20.32 -10.16 0)
        (effects (font (size 1.27 1.27) (thickness 0.15)) (justify left bottom) hide)
      )
      (property "Footprint" "data-center-rdimm-ddr4-tester-footprints:C_0201" (at 20.32 -12.7 0)
        (effects (font (size 1.27 1.27) (thickness 0.15)) (justify left bottom) hide)
      )
      (property "Datasheet" " " (at 20.32 -15.24 0)
        (effects (font (size 1.27 1.27) (thickness 0.15)) (justify left bottom) hide)
      )
      (property "MPN" "CC0201KRX6S5BB104" (at 20.32 -17.78 0)
        (effects (font (size 1.27 1.27) (thickness 0.15)) (justify left bottom) hide)
      )
      (property "Manufacturer" "Yaego" (at 20.32 -20.32 0)
        (effects (font (size 1.27 1.27) (thickness 0.15)) (justify left bottom) hide)
      )
      (property "License" "Apache-2.0" (at 20.32 -22.86 0)
        (effects (font (size 1.27 1.27) (thickness 0.15)) (justify left bottom) hide)
      )
      (property "Author" "Antmicro" (at 20.32 -25.4 0)
        (effects (font (size 1.27 1.27) (thickness 0.15)) (justify left bottom) hide)
      )
      (property "Val" "100n" (at 20.32 -7.62 0)
        (effects (font (size 1.27 1.27) (thickness 0.15)) (justify left bottom))
      )
      (property "Voltage" "" (at 20.32 -27.94 0)
        (effects (font (size 1.27 1.27)) (justify left bottom) hide)
      )
      (property "Dielectric" "" (at 20.32 -30.48 0)
        (effects (font (size 1.27 1.27)) (justify left bottom) hide)
      )
      (property "ki_description" " " (at 0 0 0)
        (effects (font (size 1.27 1.27)) hide)
      )
      (symbol "C_100n_0201_50_0_1"
        (polyline
          (pts
            (xy 2.032 -1.524)
            (xy 2.032 1.524)
          )
          (stroke (width 0.3048) (type default))
          (fill (type none))
        )
        (polyline
          (pts
            (xy 3.048 -1.524)
            (xy 3.048 1.524)
          )
          (stroke (width 0.3302) (type default))
          (fill (type none))
        )
      )
      (symbol "C_100n_0201_50_1_1"
        (pin passive line (at 0 0 0) (length 2.032)
          (name "~" (effects (font (size 1.27 1.27))))
          (number "1" (effects (font (size 1.27 1.27))))
        )
        (pin passive line (at 5.08 0 180) (length 2.032)
          (name "~" (effects (font (size 1.27 1.27))))
          (number "2" (effects (font (size 1.27 1.27))))
        )
      )
    )
	(symbol "data-center-rdimm-ddr4-tester:C_100n_0201_51" (pin_numbers hide) (pin_names hide) (in_bom yes) (on_board yes)
      (property "Reference" "C" (at 20.32 -5.08 0)
        (effects (font (size 1.27 1.27) (thickness 0.15)) (justify left bottom))
      )
      (property "Value" "C_100n_0201_51" (at 20.32 -10.16 0)
        (effects (font (size 1.27 1.27) (thickness 0.15)) (justify left bottom) hide)
      )
      (property "Footprint" "data-center-rdimm-ddr4-tester-footprints:C_0201" (at 20.32 -12.7 0)
        (effects (font (size 1.27 1.27) (thickness 0.15)) (justify left bottom) hide)
      )
      (property "Datasheet" " " (at 20.32 -15.24 0)
        (effects (font (size 1.27 1.27) (thickness 0.15)) (justify left bottom) hide)
      )
      (property "MPN" "CC0201KRX6S5BB104" (at 20.32 -17.78 0)
        (effects (font (size 1.27 1.27) (thickness 0.15)) (justify left bottom) hide)
      )
      (property "Manufacturer" "Yaego" (at 20.32 -20.32 0)
        (effects (font (size 1.27 1.27) (thickness 0.15)) (justify left bottom) hide)
      )
      (property "License" "Apache-2.0" (at 20.32 -22.86 0)
        (effects (font (size 1.27 1.27) (thickness 0.15)) (justify left bottom) hide)
      )
      (property "Author" "Antmicro" (at 20.32 -25.4 0)
        (effects (font (size 1.27 1.27) (thickness 0.15)) (justify left bottom) hide)
      )
      (property "Val" "100n" (at 20.32 -7.62 0)
        (effects (font (size 1.27 1.27) (thickness 0.15)) (justify left bottom))
      )
      (property "Voltage" "" (at 20.32 -27.94 0)
        (effects (font (size 1.27 1.27)) (justify left bottom) hide)
      )
      (property "Dielectric" "" (at 20.32 -30.48 0)
        (effects (font (size 1.27 1.27)) (justify left bottom) hide)
      )
      (property "ki_description" " " (at 0 0 0)
        (effects (font (size 1.27 1.27)) hide)
      )
      (symbol "C_100n_0201_51_0_1"
        (polyline
          (pts
            (xy 2.032 -1.524)
            (xy 2.032 1.524)
          )
          (stroke (width 0.3048) (type default))
          (fill (type none))
        )
        (polyline
          (pts
            (xy 3.048 -1.524)
            (xy 3.048 1.524)
          )
          (stroke (width 0.3302) (type default))
          (fill (type none))
        )
      )
      (symbol "C_100n_0201_51_1_1"
        (pin passive line (at 0 0 0) (length 2.032)
          (name "~" (effects (font (size 1.27 1.27))))
          (number "1" (effects (font (size 1.27 1.27))))
        )
        (pin passive line (at 5.08 0 180) (length 2.032)
          (name "~" (effects (font (size 1.27 1.27))))
          (number "2" (effects (font (size 1.27 1.27))))
        )
      )
    )
	(symbol "data-center-rdimm-ddr4-tester:C_100n_0201_52" (pin_numbers hide) (pin_names hide) (in_bom yes) (on_board yes)
      (property "Reference" "C" (at 20.32 -5.08 0)
        (effects (font (size 1.27 1.27) (thickness 0.15)) (justify left bottom))
      )
      (property "Value" "C_100n_0201_52" (at 20.32 -10.16 0)
        (effects (font (size 1.27 1.27) (thickness 0.15)) (justify left bottom) hide)
      )
      (property "Footprint" "data-center-rdimm-ddr4-tester-footprints:C_0201" (at 20.32 -12.7 0)
        (effects (font (size 1.27 1.27) (thickness 0.15)) (justify left bottom) hide)
      )
      (property "Datasheet" " " (at 20.32 -15.24 0)
        (effects (font (size 1.27 1.27) (thickness 0.15)) (justify left bottom) hide)
      )
      (property "MPN" "CC0201KRX6S5BB104" (at 20.32 -17.78 0)
        (effects (font (size 1.27 1.27) (thickness 0.15)) (justify left bottom) hide)
      )
      (property "Manufacturer" "Yaego" (at 20.32 -20.32 0)
        (effects (font (size 1.27 1.27) (thickness 0.15)) (justify left bottom) hide)
      )
      (property "License" "Apache-2.0" (at 20.32 -22.86 0)
        (effects (font (size 1.27 1.27) (thickness 0.15)) (justify left bottom) hide)
      )
      (property "Author" "Antmicro" (at 20.32 -25.4 0)
        (effects (font (size 1.27 1.27) (thickness 0.15)) (justify left bottom) hide)
      )
      (property "Val" "100n" (at 20.32 -7.62 0)
        (effects (font (size 1.27 1.27) (thickness 0.15)) (justify left bottom))
      )
      (property "Voltage" "" (at 20.32 -27.94 0)
        (effects (font (size 1.27 1.27)) (justify left bottom) hide)
      )
      (property "Dielectric" "" (at 20.32 -30.48 0)
        (effects (font (size 1.27 1.27)) (justify left bottom) hide)
      )
      (property "ki_description" " " (at 0 0 0)
        (effects (font (size 1.27 1.27)) hide)
      )
      (symbol "C_100n_0201_52_0_1"
        (polyline
          (pts
            (xy 2.032 -1.524)
            (xy 2.032 1.524)
          )
          (stroke (width 0.3048) (type default))
          (fill (type none))
        )
        (polyline
          (pts
            (xy 3.048 -1.524)
            (xy 3.048 1.524)
          )
          (stroke (width 0.3302) (type default))
          (fill (type none))
        )
      )
      (symbol "C_100n_0201_52_1_1"
        (pin passive line (at 0 0 0) (length 2.032)
          (name "~" (effects (font (size 1.27 1.27))))
          (number "1" (effects (font (size 1.27 1.27))))
        )
        (pin passive line (at 5.08 0 180) (length 2.032)
          (name "~" (effects (font (size 1.27 1.27))))
          (number "2" (effects (font (size 1.27 1.27))))
        )
      )
    )
	(symbol "data-center-rdimm-ddr4-tester:C_100n_0201_53" (pin_numbers hide) (pin_names hide) (in_bom yes) (on_board yes)
      (property "Reference" "C" (at 20.32 -5.08 0)
        (effects (font (size 1.27 1.27) (thickness 0.15)) (justify left bottom))
      )
      (property "Value" "C_100n_0201_53" (at 20.32 -10.16 0)
        (effects (font (size 1.27 1.27) (thickness 0.15)) (justify left bottom) hide)
      )
      (property "Footprint" "data-center-rdimm-ddr4-tester-footprints:C_0201" (at 20.32 -12.7 0)
        (effects (font (size 1.27 1.27) (thickness 0.15)) (justify left bottom) hide)
      )
      (property "Datasheet" " " (at 20.32 -15.24 0)
        (effects (font (size 1.27 1.27) (thickness 0.15)) (justify left bottom) hide)
      )
      (property "MPN" "CC0201KRX6S5BB104" (at 20.32 -17.78 0)
        (effects (font (size 1.27 1.27) (thickness 0.15)) (justify left bottom) hide)
      )
      (property "Manufacturer" "Yaego" (at 20.32 -20.32 0)
        (effects (font (size 1.27 1.27) (thickness 0.15)) (justify left bottom) hide)
      )
      (property "License" "Apache-2.0" (at 20.32 -22.86 0)
        (effects (font (size 1.27 1.27) (thickness 0.15)) (justify left bottom) hide)
      )
      (property "Author" "Antmicro" (at 20.32 -25.4 0)
        (effects (font (size 1.27 1.27) (thickness 0.15)) (justify left bottom) hide)
      )
      (property "Val" "100n" (at 20.32 -7.62 0)
        (effects (font (size 1.27 1.27) (thickness 0.15)) (justify left bottom))
      )
      (property "Voltage" "" (at 20.32 -27.94 0)
        (effects (font (size 1.27 1.27)) (justify left bottom) hide)
      )
      (property "Dielectric" "" (at 20.32 -30.48 0)
        (effects (font (size 1.27 1.27)) (justify left bottom) hide)
      )
      (property "ki_description" " " (at 0 0 0)
        (effects (font (size 1.27 1.27)) hide)
      )
      (symbol "C_100n_0201_53_0_1"
        (polyline
          (pts
            (xy 2.032 -1.524)
            (xy 2.032 1.524)
          )
          (stroke (width 0.3048) (type default))
          (fill (type none))
        )
        (polyline
          (pts
            (xy 3.048 -1.524)
            (xy 3.048 1.524)
          )
          (stroke (width 0.3302) (type default))
          (fill (type none))
        )
      )
      (symbol "C_100n_0201_53_1_1"
        (pin passive line (at 0 0 0) (length 2.032)
          (name "~" (effects (font (size 1.27 1.27))))
          (number "1" (effects (font (size 1.27 1.27))))
        )
        (pin passive line (at 5.08 0 180) (length 2.032)
          (name "~" (effects (font (size 1.27 1.27))))
          (number "2" (effects (font (size 1.27 1.27))))
        )
      )
    )
	(symbol "data-center-rdimm-ddr4-tester:C_100n_0201_54" (pin_numbers hide) (pin_names hide) (in_bom yes) (on_board yes)
      (property "Reference" "C" (at 20.32 -5.08 0)
        (effects (font (size 1.27 1.27) (thickness 0.15)) (justify left bottom))
      )
      (property "Value" "C_100n_0201_54" (at 20.32 -10.16 0)
        (effects (font (size 1.27 1.27) (thickness 0.15)) (justify left bottom) hide)
      )
      (property "Footprint" "data-center-rdimm-ddr4-tester-footprints:C_0201" (at 20.32 -12.7 0)
        (effects (font (size 1.27 1.27) (thickness 0.15)) (justify left bottom) hide)
      )
      (property "Datasheet" " " (at 20.32 -15.24 0)
        (effects (font (size 1.27 1.27) (thickness 0.15)) (justify left bottom) hide)
      )
      (property "MPN" "CC0201KRX6S5BB104" (at 20.32 -17.78 0)
        (effects (font (size 1.27 1.27) (thickness 0.15)) (justify left bottom) hide)
      )
      (property "Manufacturer" "Yaego" (at 20.32 -20.32 0)
        (effects (font (size 1.27 1.27) (thickness 0.15)) (justify left bottom) hide)
      )
      (property "License" "Apache-2.0" (at 20.32 -22.86 0)
        (effects (font (size 1.27 1.27) (thickness 0.15)) (justify left bottom) hide)
      )
      (property "Author" "Antmicro" (at 20.32 -25.4 0)
        (effects (font (size 1.27 1.27) (thickness 0.15)) (justify left bottom) hide)
      )
      (property "Val" "100n" (at 20.32 -7.62 0)
        (effects (font (size 1.27 1.27) (thickness 0.15)) (justify left bottom))
      )
      (property "Voltage" "" (at 20.32 -27.94 0)
        (effects (font (size 1.27 1.27)) (justify left bottom) hide)
      )
      (property "Dielectric" "" (at 20.32 -30.48 0)
        (effects (font (size 1.27 1.27)) (justify left bottom) hide)
      )
      (property "ki_description" " " (at 0 0 0)
        (effects (font (size 1.27 1.27)) hide)
      )
      (symbol "C_100n_0201_54_0_1"
        (polyline
          (pts
            (xy 2.032 -1.524)
            (xy 2.032 1.524)
          )
          (stroke (width 0.3048) (type default))
          (fill (type none))
        )
        (polyline
          (pts
            (xy 3.048 -1.524)
            (xy 3.048 1.524)
          )
          (stroke (width 0.3302) (type default))
          (fill (type none))
        )
      )
      (symbol "C_100n_0201_54_1_1"
        (pin passive line (at 0 0 0) (length 2.032)
          (name "~" (effects (font (size 1.27 1.27))))
          (number "1" (effects (font (size 1.27 1.27))))
        )
        (pin passive line (at 5.08 0 180) (length 2.032)
          (name "~" (effects (font (size 1.27 1.27))))
          (number "2" (effects (font (size 1.27 1.27))))
        )
      )
    )
	(symbol "data-center-rdimm-ddr4-tester:C_100n_0201_55" (pin_numbers hide) (pin_names hide) (in_bom yes) (on_board yes)
      (property "Reference" "C" (at 20.32 -5.08 0)
        (effects (font (size 1.27 1.27) (thickness 0.15)) (justify left bottom))
      )
      (property "Value" "C_100n_0201_55" (at 20.32 -10.16 0)
        (effects (font (size 1.27 1.27) (thickness 0.15)) (justify left bottom) hide)
      )
      (property "Footprint" "data-center-rdimm-ddr4-tester-footprints:C_0201" (at 20.32 -12.7 0)
        (effects (font (size 1.27 1.27) (thickness 0.15)) (justify left bottom) hide)
      )
      (property "Datasheet" " " (at 20.32 -15.24 0)
        (effects (font (size 1.27 1.27) (thickness 0.15)) (justify left bottom) hide)
      )
      (property "MPN" "CC0201KRX6S5BB104" (at 20.32 -17.78 0)
        (effects (font (size 1.27 1.27) (thickness 0.15)) (justify left bottom) hide)
      )
      (property "Manufacturer" "Yaego" (at 20.32 -20.32 0)
        (effects (font (size 1.27 1.27) (thickness 0.15)) (justify left bottom) hide)
      )
      (property "License" "Apache-2.0" (at 20.32 -22.86 0)
        (effects (font (size 1.27 1.27) (thickness 0.15)) (justify left bottom) hide)
      )
      (property "Author" "Antmicro" (at 20.32 -25.4 0)
        (effects (font (size 1.27 1.27) (thickness 0.15)) (justify left bottom) hide)
      )
      (property "Val" "100n" (at 20.32 -7.62 0)
        (effects (font (size 1.27 1.27) (thickness 0.15)) (justify left bottom))
      )
      (property "Voltage" "" (at 20.32 -27.94 0)
        (effects (font (size 1.27 1.27)) (justify left bottom) hide)
      )
      (property "Dielectric" "" (at 20.32 -30.48 0)
        (effects (font (size 1.27 1.27)) (justify left bottom) hide)
      )
      (property "ki_description" " " (at 0 0 0)
        (effects (font (size 1.27 1.27)) hide)
      )
      (symbol "C_100n_0201_55_0_1"
        (polyline
          (pts
            (xy 2.032 -1.524)
            (xy 2.032 1.524)
          )
          (stroke (width 0.3048) (type default))
          (fill (type none))
        )
        (polyline
          (pts
            (xy 3.048 -1.524)
            (xy 3.048 1.524)
          )
          (stroke (width 0.3302) (type default))
          (fill (type none))
        )
      )
      (symbol "C_100n_0201_55_1_1"
        (pin passive line (at 0 0 0) (length 2.032)
          (name "~" (effects (font (size 1.27 1.27))))
          (number "1" (effects (font (size 1.27 1.27))))
        )
        (pin passive line (at 5.08 0 180) (length 2.032)
          (name "~" (effects (font (size 1.27 1.27))))
          (number "2" (effects (font (size 1.27 1.27))))
        )
      )
    )
	(symbol "data-center-rdimm-ddr4-tester:C_100n_0201_56" (pin_numbers hide) (pin_names hide) (in_bom yes) (on_board yes)
      (property "Reference" "C" (at 20.32 -5.08 0)
        (effects (font (size 1.27 1.27) (thickness 0.15)) (justify left bottom))
      )
      (property "Value" "C_100n_0201_56" (at 20.32 -10.16 0)
        (effects (font (size 1.27 1.27) (thickness 0.15)) (justify left bottom) hide)
      )
      (property "Footprint" "data-center-rdimm-ddr4-tester-footprints:C_0201" (at 20.32 -12.7 0)
        (effects (font (size 1.27 1.27) (thickness 0.15)) (justify left bottom) hide)
      )
      (property "Datasheet" " " (at 20.32 -15.24 0)
        (effects (font (size 1.27 1.27) (thickness 0.15)) (justify left bottom) hide)
      )
      (property "MPN" "CC0201KRX6S5BB104" (at 20.32 -17.78 0)
        (effects (font (size 1.27 1.27) (thickness 0.15)) (justify left bottom) hide)
      )
      (property "Manufacturer" "Yaego" (at 20.32 -20.32 0)
        (effects (font (size 1.27 1.27) (thickness 0.15)) (justify left bottom) hide)
      )
      (property "License" "Apache-2.0" (at 20.32 -22.86 0)
        (effects (font (size 1.27 1.27) (thickness 0.15)) (justify left bottom) hide)
      )
      (property "Author" "Antmicro" (at 20.32 -25.4 0)
        (effects (font (size 1.27 1.27) (thickness 0.15)) (justify left bottom) hide)
      )
      (property "Val" "100n" (at 20.32 -7.62 0)
        (effects (font (size 1.27 1.27) (thickness 0.15)) (justify left bottom))
      )
      (property "Voltage" "" (at 20.32 -27.94 0)
        (effects (font (size 1.27 1.27)) (justify left bottom) hide)
      )
      (property "Dielectric" "" (at 20.32 -30.48 0)
        (effects (font (size 1.27 1.27)) (justify left bottom) hide)
      )
      (property "ki_description" " " (at 0 0 0)
        (effects (font (size 1.27 1.27)) hide)
      )
      (symbol "C_100n_0201_56_0_1"
        (polyline
          (pts
            (xy 2.032 -1.524)
            (xy 2.032 1.524)
          )
          (stroke (width 0.3048) (type default))
          (fill (type none))
        )
        (polyline
          (pts
            (xy 3.048 -1.524)
            (xy 3.048 1.524)
          )
          (stroke (width 0.3302) (type default))
          (fill (type none))
        )
      )
      (symbol "C_100n_0201_56_1_1"
        (pin passive line (at 0 0 0) (length 2.032)
          (name "~" (effects (font (size 1.27 1.27))))
          (number "1" (effects (font (size 1.27 1.27))))
        )
        (pin passive line (at 5.08 0 180) (length 2.032)
          (name "~" (effects (font (size 1.27 1.27))))
          (number "2" (effects (font (size 1.27 1.27))))
        )
      )
    )
	(symbol "data-center-rdimm-ddr4-tester:C_100n_0201_57" (pin_numbers hide) (pin_names hide) (in_bom yes) (on_board yes)
      (property "Reference" "C" (at 20.32 -5.08 0)
        (effects (font (size 1.27 1.27) (thickness 0.15)) (justify left bottom))
      )
      (property "Value" "C_100n_0201_57" (at 20.32 -10.16 0)
        (effects (font (size 1.27 1.27) (thickness 0.15)) (justify left bottom) hide)
      )
      (property "Footprint" "data-center-rdimm-ddr4-tester-footprints:C_0201" (at 20.32 -12.7 0)
        (effects (font (size 1.27 1.27) (thickness 0.15)) (justify left bottom) hide)
      )
      (property "Datasheet" " " (at 20.32 -15.24 0)
        (effects (font (size 1.27 1.27) (thickness 0.15)) (justify left bottom) hide)
      )
      (property "MPN" "CC0201KRX6S5BB104" (at 20.32 -17.78 0)
        (effects (font (size 1.27 1.27) (thickness 0.15)) (justify left bottom) hide)
      )
      (property "Manufacturer" "Yaego" (at 20.32 -20.32 0)
        (effects (font (size 1.27 1.27) (thickness 0.15)) (justify left bottom) hide)
      )
      (property "License" "Apache-2.0" (at 20.32 -22.86 0)
        (effects (font (size 1.27 1.27) (thickness 0.15)) (justify left bottom) hide)
      )
      (property "Author" "Antmicro" (at 20.32 -25.4 0)
        (effects (font (size 1.27 1.27) (thickness 0.15)) (justify left bottom) hide)
      )
      (property "Val" "100n" (at 20.32 -7.62 0)
        (effects (font (size 1.27 1.27) (thickness 0.15)) (justify left bottom))
      )
      (property "Voltage" "" (at 20.32 -27.94 0)
        (effects (font (size 1.27 1.27)) (justify left bottom) hide)
      )
      (property "Dielectric" "" (at 20.32 -30.48 0)
        (effects (font (size 1.27 1.27)) (justify left bottom) hide)
      )
      (property "ki_description" " " (at 0 0 0)
        (effects (font (size 1.27 1.27)) hide)
      )
      (symbol "C_100n_0201_57_0_1"
        (polyline
          (pts
            (xy 2.032 -1.524)
            (xy 2.032 1.524)
          )
          (stroke (width 0.3048) (type default))
          (fill (type none))
        )
        (polyline
          (pts
            (xy 3.048 -1.524)
            (xy 3.048 1.524)
          )
          (stroke (width 0.3302) (type default))
          (fill (type none))
        )
      )
      (symbol "C_100n_0201_57_1_1"
        (pin passive line (at 0 0 0) (length 2.032)
          (name "~" (effects (font (size 1.27 1.27))))
          (number "1" (effects (font (size 1.27 1.27))))
        )
        (pin passive line (at 5.08 0 180) (length 2.032)
          (name "~" (effects (font (size 1.27 1.27))))
          (number "2" (effects (font (size 1.27 1.27))))
        )
      )
    )
	(symbol "data-center-rdimm-ddr4-tester:C_100n_0201_58" (pin_numbers hide) (pin_names hide) (in_bom yes) (on_board yes)
      (property "Reference" "C" (at 20.32 -5.08 0)
        (effects (font (size 1.27 1.27) (thickness 0.15)) (justify left bottom))
      )
      (property "Value" "C_100n_0201_58" (at 20.32 -10.16 0)
        (effects (font (size 1.27 1.27) (thickness 0.15)) (justify left bottom) hide)
      )
      (property "Footprint" "data-center-rdimm-ddr4-tester-footprints:C_0201" (at 20.32 -12.7 0)
        (effects (font (size 1.27 1.27) (thickness 0.15)) (justify left bottom) hide)
      )
      (property "Datasheet" " " (at 20.32 -15.24 0)
        (effects (font (size 1.27 1.27) (thickness 0.15)) (justify left bottom) hide)
      )
      (property "MPN" "CC0201KRX6S5BB104" (at 20.32 -17.78 0)
        (effects (font (size 1.27 1.27) (thickness 0.15)) (justify left bottom) hide)
      )
      (property "Manufacturer" "Yaego" (at 20.32 -20.32 0)
        (effects (font (size 1.27 1.27) (thickness 0.15)) (justify left bottom) hide)
      )
      (property "License" "Apache-2.0" (at 20.32 -22.86 0)
        (effects (font (size 1.27 1.27) (thickness 0.15)) (justify left bottom) hide)
      )
      (property "Author" "Antmicro" (at 20.32 -25.4 0)
        (effects (font (size 1.27 1.27) (thickness 0.15)) (justify left bottom) hide)
      )
      (property "Val" "100n" (at 20.32 -7.62 0)
        (effects (font (size 1.27 1.27) (thickness 0.15)) (justify left bottom))
      )
      (property "Voltage" "" (at 20.32 -27.94 0)
        (effects (font (size 1.27 1.27)) (justify left bottom) hide)
      )
      (property "Dielectric" "" (at 20.32 -30.48 0)
        (effects (font (size 1.27 1.27)) (justify left bottom) hide)
      )
      (property "ki_description" " " (at 0 0 0)
        (effects (font (size 1.27 1.27)) hide)
      )
      (symbol "C_100n_0201_58_0_1"
        (polyline
          (pts
            (xy 2.032 -1.524)
            (xy 2.032 1.524)
          )
          (stroke (width 0.3048) (type default))
          (fill (type none))
        )
        (polyline
          (pts
            (xy 3.048 -1.524)
            (xy 3.048 1.524)
          )
          (stroke (width 0.3302) (type default))
          (fill (type none))
        )
      )
      (symbol "C_100n_0201_58_1_1"
        (pin passive line (at 0 0 0) (length 2.032)
          (name "~" (effects (font (size 1.27 1.27))))
          (number "1" (effects (font (size 1.27 1.27))))
        )
        (pin passive line (at 5.08 0 180) (length 2.032)
          (name "~" (effects (font (size 1.27 1.27))))
          (number "2" (effects (font (size 1.27 1.27))))
        )
      )
    )
	(symbol "data-center-rdimm-ddr4-tester:C_100n_0201_59" (pin_numbers hide) (pin_names hide) (in_bom yes) (on_board yes)
      (property "Reference" "C" (at 20.32 -5.08 0)
        (effects (font (size 1.27 1.27) (thickness 0.15)) (justify left bottom))
      )
      (property "Value" "C_100n_0201_59" (at 20.32 -10.16 0)
        (effects (font (size 1.27 1.27) (thickness 0.15)) (justify left bottom) hide)
      )
      (property "Footprint" "data-center-rdimm-ddr4-tester-footprints:C_0201" (at 20.32 -12.7 0)
        (effects (font (size 1.27 1.27) (thickness 0.15)) (justify left bottom) hide)
      )
      (property "Datasheet" " " (at 20.32 -15.24 0)
        (effects (font (size 1.27 1.27) (thickness 0.15)) (justify left bottom) hide)
      )
      (property "MPN" "CC0201KRX6S5BB104" (at 20.32 -17.78 0)
        (effects (font (size 1.27 1.27) (thickness 0.15)) (justify left bottom) hide)
      )
      (property "Manufacturer" "Yaego" (at 20.32 -20.32 0)
        (effects (font (size 1.27 1.27) (thickness 0.15)) (justify left bottom) hide)
      )
      (property "License" "Apache-2.0" (at 20.32 -22.86 0)
        (effects (font (size 1.27 1.27) (thickness 0.15)) (justify left bottom) hide)
      )
      (property "Author" "Antmicro" (at 20.32 -25.4 0)
        (effects (font (size 1.27 1.27) (thickness 0.15)) (justify left bottom) hide)
      )
      (property "Val" "100n" (at 20.32 -7.62 0)
        (effects (font (size 1.27 1.27) (thickness 0.15)) (justify left bottom))
      )
      (property "Voltage" "" (at 20.32 -27.94 0)
        (effects (font (size 1.27 1.27)) (justify left bottom) hide)
      )
      (property "Dielectric" "" (at 20.32 -30.48 0)
        (effects (font (size 1.27 1.27)) (justify left bottom) hide)
      )
      (property "ki_description" " " (at 0 0 0)
        (effects (font (size 1.27 1.27)) hide)
      )
      (symbol "C_100n_0201_59_0_1"
        (polyline
          (pts
            (xy 2.032 -1.524)
            (xy 2.032 1.524)
          )
          (stroke (width 0.3048) (type default))
          (fill (type none))
        )
        (polyline
          (pts
            (xy 3.048 -1.524)
            (xy 3.048 1.524)
          )
          (stroke (width 0.3302) (type default))
          (fill (type none))
        )
      )
      (symbol "C_100n_0201_59_1_1"
        (pin passive line (at 0 0 0) (length 2.032)
          (name "~" (effects (font (size 1.27 1.27))))
          (number "1" (effects (font (size 1.27 1.27))))
        )
        (pin passive line (at 5.08 0 180) (length 2.032)
          (name "~" (effects (font (size 1.27 1.27))))
          (number "2" (effects (font (size 1.27 1.27))))
        )
      )
    )
	(symbol "data-center-rdimm-ddr4-tester:C_100n_0201_60" (pin_numbers hide) (pin_names hide) (in_bom yes) (on_board yes)
      (property "Reference" "C" (at 20.32 -5.08 0)
        (effects (font (size 1.27 1.27) (thickness 0.15)) (justify left bottom))
      )
      (property "Value" "C_100n_0201_60" (at 20.32 -10.16 0)
        (effects (font (size 1.27 1.27) (thickness 0.15)) (justify left bottom) hide)
      )
      (property "Footprint" "data-center-rdimm-ddr4-tester-footprints:C_0201" (at 20.32 -12.7 0)
        (effects (font (size 1.27 1.27) (thickness 0.15)) (justify left bottom) hide)
      )
      (property "Datasheet" " " (at 20.32 -15.24 0)
        (effects (font (size 1.27 1.27) (thickness 0.15)) (justify left bottom) hide)
      )
      (property "MPN" "CC0201KRX6S5BB104" (at 20.32 -17.78 0)
        (effects (font (size 1.27 1.27) (thickness 0.15)) (justify left bottom) hide)
      )
      (property "Manufacturer" "Yaego" (at 20.32 -20.32 0)
        (effects (font (size 1.27 1.27) (thickness 0.15)) (justify left bottom) hide)
      )
      (property "License" "Apache-2.0" (at 20.32 -22.86 0)
        (effects (font (size 1.27 1.27) (thickness 0.15)) (justify left bottom) hide)
      )
      (property "Author" "Antmicro" (at 20.32 -25.4 0)
        (effects (font (size 1.27 1.27) (thickness 0.15)) (justify left bottom) hide)
      )
      (property "Val" "100n" (at 20.32 -7.62 0)
        (effects (font (size 1.27 1.27) (thickness 0.15)) (justify left bottom))
      )
      (property "Voltage" "" (at 20.32 -27.94 0)
        (effects (font (size 1.27 1.27)) (justify left bottom) hide)
      )
      (property "Dielectric" "" (at 20.32 -30.48 0)
        (effects (font (size 1.27 1.27)) (justify left bottom) hide)
      )
      (property "ki_description" " " (at 0 0 0)
        (effects (font (size 1.27 1.27)) hide)
      )
      (symbol "C_100n_0201_60_0_1"
        (polyline
          (pts
            (xy 2.032 -1.524)
            (xy 2.032 1.524)
          )
          (stroke (width 0.3048) (type default))
          (fill (type none))
        )
        (polyline
          (pts
            (xy 3.048 -1.524)
            (xy 3.048 1.524)
          )
          (stroke (width 0.3302) (type default))
          (fill (type none))
        )
      )
      (symbol "C_100n_0201_60_1_1"
        (pin passive line (at 0 0 0) (length 2.032)
          (name "~" (effects (font (size 1.27 1.27))))
          (number "1" (effects (font (size 1.27 1.27))))
        )
        (pin passive line (at 5.08 0 180) (length 2.032)
          (name "~" (effects (font (size 1.27 1.27))))
          (number "2" (effects (font (size 1.27 1.27))))
        )
      )
    )
	(symbol "data-center-rdimm-ddr4-tester:C_100n_0201_61" (pin_numbers hide) (pin_names hide) (in_bom yes) (on_board yes)
      (property "Reference" "C" (at 20.32 -5.08 0)
        (effects (font (size 1.27 1.27) (thickness 0.15)) (justify left bottom))
      )
      (property "Value" "C_100n_0201_61" (at 20.32 -10.16 0)
        (effects (font (size 1.27 1.27) (thickness 0.15)) (justify left bottom) hide)
      )
      (property "Footprint" "data-center-rdimm-ddr4-tester-footprints:C_0201" (at 20.32 -12.7 0)
        (effects (font (size 1.27 1.27) (thickness 0.15)) (justify left bottom) hide)
      )
      (property "Datasheet" " " (at 20.32 -15.24 0)
        (effects (font (size 1.27 1.27) (thickness 0.15)) (justify left bottom) hide)
      )
      (property "MPN" "CC0201KRX6S5BB104" (at 20.32 -17.78 0)
        (effects (font (size 1.27 1.27) (thickness 0.15)) (justify left bottom) hide)
      )
      (property "Manufacturer" "Yaego" (at 20.32 -20.32 0)
        (effects (font (size 1.27 1.27) (thickness 0.15)) (justify left bottom) hide)
      )
      (property "License" "Apache-2.0" (at 20.32 -22.86 0)
        (effects (font (size 1.27 1.27) (thickness 0.15)) (justify left bottom) hide)
      )
      (property "Author" "Antmicro" (at 20.32 -25.4 0)
        (effects (font (size 1.27 1.27) (thickness 0.15)) (justify left bottom) hide)
      )
      (property "Val" "100n" (at 20.32 -7.62 0)
        (effects (font (size 1.27 1.27) (thickness 0.15)) (justify left bottom))
      )
      (property "Voltage" "" (at 20.32 -27.94 0)
        (effects (font (size 1.27 1.27)) (justify left bottom) hide)
      )
      (property "Dielectric" "" (at 20.32 -30.48 0)
        (effects (font (size 1.27 1.27)) (justify left bottom) hide)
      )
      (property "ki_description" " " (at 0 0 0)
        (effects (font (size 1.27 1.27)) hide)
      )
      (symbol "C_100n_0201_61_0_1"
        (polyline
          (pts
            (xy 2.032 -1.524)
            (xy 2.032 1.524)
          )
          (stroke (width 0.3048) (type default))
          (fill (type none))
        )
        (polyline
          (pts
            (xy 3.048 -1.524)
            (xy 3.048 1.524)
          )
          (stroke (width 0.3302) (type default))
          (fill (type none))
        )
      )
      (symbol "C_100n_0201_61_1_1"
        (pin passive line (at 0 0 0) (length 2.032)
          (name "~" (effects (font (size 1.27 1.27))))
          (number "1" (effects (font (size 1.27 1.27))))
        )
        (pin passive line (at 5.08 0 180) (length 2.032)
          (name "~" (effects (font (size 1.27 1.27))))
          (number "2" (effects (font (size 1.27 1.27))))
        )
      )
    )
	(symbol "data-center-rdimm-ddr4-tester:C_100n_0201_62" (pin_numbers hide) (pin_names hide) (in_bom yes) (on_board yes)
      (property "Reference" "C" (at 20.32 -5.08 0)
        (effects (font (size 1.27 1.27) (thickness 0.15)) (justify left bottom))
      )
      (property "Value" "C_100n_0201_62" (at 20.32 -10.16 0)
        (effects (font (size 1.27 1.27) (thickness 0.15)) (justify left bottom) hide)
      )
      (property "Footprint" "data-center-rdimm-ddr4-tester-footprints:C_0201" (at 20.32 -12.7 0)
        (effects (font (size 1.27 1.27) (thickness 0.15)) (justify left bottom) hide)
      )
      (property "Datasheet" " " (at 20.32 -15.24 0)
        (effects (font (size 1.27 1.27) (thickness 0.15)) (justify left bottom) hide)
      )
      (property "MPN" "CC0201KRX6S5BB104" (at 20.32 -17.78 0)
        (effects (font (size 1.27 1.27) (thickness 0.15)) (justify left bottom) hide)
      )
      (property "Manufacturer" "Yaego" (at 20.32 -20.32 0)
        (effects (font (size 1.27 1.27) (thickness 0.15)) (justify left bottom) hide)
      )
      (property "License" "Apache-2.0" (at 20.32 -22.86 0)
        (effects (font (size 1.27 1.27) (thickness 0.15)) (justify left bottom) hide)
      )
      (property "Author" "Antmicro" (at 20.32 -25.4 0)
        (effects (font (size 1.27 1.27) (thickness 0.15)) (justify left bottom) hide)
      )
      (property "Val" "100n" (at 20.32 -7.62 0)
        (effects (font (size 1.27 1.27) (thickness 0.15)) (justify left bottom))
      )
      (property "Voltage" "" (at 20.32 -27.94 0)
        (effects (font (size 1.27 1.27)) (justify left bottom) hide)
      )
      (property "Dielectric" "" (at 20.32 -30.48 0)
        (effects (font (size 1.27 1.27)) (justify left bottom) hide)
      )
      (property "ki_description" " " (at 0 0 0)
        (effects (font (size 1.27 1.27)) hide)
      )
      (symbol "C_100n_0201_62_0_1"
        (polyline
          (pts
            (xy 2.032 -1.524)
            (xy 2.032 1.524)
          )
          (stroke (width 0.3048) (type default))
          (fill (type none))
        )
        (polyline
          (pts
            (xy 3.048 -1.524)
            (xy 3.048 1.524)
          )
          (stroke (width 0.3302) (type default))
          (fill (type none))
        )
      )
      (symbol "C_100n_0201_62_1_1"
        (pin passive line (at 0 0 0) (length 2.032)
          (name "~" (effects (font (size 1.27 1.27))))
          (number "1" (effects (font (size 1.27 1.27))))
        )
        (pin passive line (at 5.08 0 180) (length 2.032)
          (name "~" (effects (font (size 1.27 1.27))))
          (number "2" (effects (font (size 1.27 1.27))))
        )
      )
    )
	(symbol "data-center-rdimm-ddr4-tester:C_100n_0201_63" (pin_numbers hide) (pin_names hide) (in_bom yes) (on_board yes)
      (property "Reference" "C" (at 20.32 -5.08 0)
        (effects (font (size 1.27 1.27) (thickness 0.15)) (justify left bottom))
      )
      (property "Value" "C_100n_0201_63" (at 20.32 -10.16 0)
        (effects (font (size 1.27 1.27) (thickness 0.15)) (justify left bottom) hide)
      )
      (property "Footprint" "data-center-rdimm-ddr4-tester-footprints:C_0201" (at 20.32 -12.7 0)
        (effects (font (size 1.27 1.27) (thickness 0.15)) (justify left bottom) hide)
      )
      (property "Datasheet" " " (at 20.32 -15.24 0)
        (effects (font (size 1.27 1.27) (thickness 0.15)) (justify left bottom) hide)
      )
      (property "MPN" "CC0201KRX6S5BB104" (at 20.32 -17.78 0)
        (effects (font (size 1.27 1.27) (thickness 0.15)) (justify left bottom) hide)
      )
      (property "Manufacturer" "Yaego" (at 20.32 -20.32 0)
        (effects (font (size 1.27 1.27) (thickness 0.15)) (justify left bottom) hide)
      )
      (property "License" "Apache-2.0" (at 20.32 -22.86 0)
        (effects (font (size 1.27 1.27) (thickness 0.15)) (justify left bottom) hide)
      )
      (property "Author" "Antmicro" (at 20.32 -25.4 0)
        (effects (font (size 1.27 1.27) (thickness 0.15)) (justify left bottom) hide)
      )
      (property "Val" "100n" (at 20.32 -7.62 0)
        (effects (font (size 1.27 1.27) (thickness 0.15)) (justify left bottom))
      )
      (property "Voltage" "" (at 20.32 -27.94 0)
        (effects (font (size 1.27 1.27)) (justify left bottom) hide)
      )
      (property "Dielectric" "" (at 20.32 -30.48 0)
        (effects (font (size 1.27 1.27)) (justify left bottom) hide)
      )
      (property "ki_description" " " (at 0 0 0)
        (effects (font (size 1.27 1.27)) hide)
      )
      (symbol "C_100n_0201_63_0_1"
        (polyline
          (pts
            (xy 2.032 -1.524)
            (xy 2.032 1.524)
          )
          (stroke (width 0.3048) (type default))
          (fill (type none))
        )
        (polyline
          (pts
            (xy 3.048 -1.524)
            (xy 3.048 1.524)
          )
          (stroke (width 0.3302) (type default))
          (fill (type none))
        )
      )
      (symbol "C_100n_0201_63_1_1"
        (pin passive line (at 0 0 0) (length 2.032)
          (name "~" (effects (font (size 1.27 1.27))))
          (number "1" (effects (font (size 1.27 1.27))))
        )
        (pin passive line (at 5.08 0 180) (length 2.032)
          (name "~" (effects (font (size 1.27 1.27))))
          (number "2" (effects (font (size 1.27 1.27))))
        )
      )
    )
	(symbol "data-center-rdimm-ddr4-tester:C_100n_0201_64" (pin_numbers hide) (pin_names hide) (in_bom yes) (on_board yes)
      (property "Reference" "C" (at 20.32 -5.08 0)
        (effects (font (size 1.27 1.27) (thickness 0.15)) (justify left bottom))
      )
      (property "Value" "C_100n_0201_64" (at 20.32 -10.16 0)
        (effects (font (size 1.27 1.27) (thickness 0.15)) (justify left bottom) hide)
      )
      (property "Footprint" "data-center-rdimm-ddr4-tester-footprints:C_0201" (at 20.32 -12.7 0)
        (effects (font (size 1.27 1.27) (thickness 0.15)) (justify left bottom) hide)
      )
      (property "Datasheet" " " (at 20.32 -15.24 0)
        (effects (font (size 1.27 1.27) (thickness 0.15)) (justify left bottom) hide)
      )
      (property "MPN" "CC0201KRX6S5BB104" (at 20.32 -17.78 0)
        (effects (font (size 1.27 1.27) (thickness 0.15)) (justify left bottom) hide)
      )
      (property "Manufacturer" "Yaego" (at 20.32 -20.32 0)
        (effects (font (size 1.27 1.27) (thickness 0.15)) (justify left bottom) hide)
      )
      (property "License" "Apache-2.0" (at 20.32 -22.86 0)
        (effects (font (size 1.27 1.27) (thickness 0.15)) (justify left bottom) hide)
      )
      (property "Author" "Antmicro" (at 20.32 -25.4 0)
        (effects (font (size 1.27 1.27) (thickness 0.15)) (justify left bottom) hide)
      )
      (property "Val" "100n" (at 20.32 -7.62 0)
        (effects (font (size 1.27 1.27) (thickness 0.15)) (justify left bottom))
      )
      (property "Voltage" "" (at 20.32 -27.94 0)
        (effects (font (size 1.27 1.27)) (justify left bottom) hide)
      )
      (property "Dielectric" "" (at 20.32 -30.48 0)
        (effects (font (size 1.27 1.27)) (justify left bottom) hide)
      )
      (property "ki_description" " " (at 0 0 0)
        (effects (font (size 1.27 1.27)) hide)
      )
      (symbol "C_100n_0201_64_0_1"
        (polyline
          (pts
            (xy 2.032 -1.524)
            (xy 2.032 1.524)
          )
          (stroke (width 0.3048) (type default))
          (fill (type none))
        )
        (polyline
          (pts
            (xy 3.048 -1.524)
            (xy 3.048 1.524)
          )
          (stroke (width 0.3302) (type default))
          (fill (type none))
        )
      )
      (symbol "C_100n_0201_64_1_1"
        (pin passive line (at 0 0 0) (length 2.032)
          (name "~" (effects (font (size 1.27 1.27))))
          (number "1" (effects (font (size 1.27 1.27))))
        )
        (pin passive line (at 5.08 0 180) (length 2.032)
          (name "~" (effects (font (size 1.27 1.27))))
          (number "2" (effects (font (size 1.27 1.27))))
        )
      )
    )
	(symbol "data-center-rdimm-ddr4-tester:C_100n_0201_65" (pin_numbers hide) (pin_names hide) (in_bom yes) (on_board yes)
      (property "Reference" "C" (at 20.32 -5.08 0)
        (effects (font (size 1.27 1.27) (thickness 0.15)) (justify left bottom))
      )
      (property "Value" "C_100n_0201_65" (at 20.32 -10.16 0)
        (effects (font (size 1.27 1.27) (thickness 0.15)) (justify left bottom) hide)
      )
      (property "Footprint" "data-center-rdimm-ddr4-tester-footprints:C_0201" (at 20.32 -12.7 0)
        (effects (font (size 1.27 1.27) (thickness 0.15)) (justify left bottom) hide)
      )
      (property "Datasheet" " " (at 20.32 -15.24 0)
        (effects (font (size 1.27 1.27) (thickness 0.15)) (justify left bottom) hide)
      )
      (property "MPN" "CC0201KRX6S5BB104" (at 20.32 -17.78 0)
        (effects (font (size 1.27 1.27) (thickness 0.15)) (justify left bottom) hide)
      )
      (property "Manufacturer" "Yaego" (at 20.32 -20.32 0)
        (effects (font (size 1.27 1.27) (thickness 0.15)) (justify left bottom) hide)
      )
      (property "License" "Apache-2.0" (at 20.32 -22.86 0)
        (effects (font (size 1.27 1.27) (thickness 0.15)) (justify left bottom) hide)
      )
      (property "Author" "Antmicro" (at 20.32 -25.4 0)
        (effects (font (size 1.27 1.27) (thickness 0.15)) (justify left bottom) hide)
      )
      (property "Val" "100n" (at 20.32 -7.62 0)
        (effects (font (size 1.27 1.27) (thickness 0.15)) (justify left bottom))
      )
      (property "Voltage" "" (at 20.32 -27.94 0)
        (effects (font (size 1.27 1.27)) (justify left bottom) hide)
      )
      (property "Dielectric" "" (at 20.32 -30.48 0)
        (effects (font (size 1.27 1.27)) (justify left bottom) hide)
      )
      (property "ki_description" " " (at 0 0 0)
        (effects (font (size 1.27 1.27)) hide)
      )
      (symbol "C_100n_0201_65_0_1"
        (polyline
          (pts
            (xy 2.032 -1.524)
            (xy 2.032 1.524)
          )
          (stroke (width 0.3048) (type default))
          (fill (type none))
        )
        (polyline
          (pts
            (xy 3.048 -1.524)
            (xy 3.048 1.524)
          )
          (stroke (width 0.3302) (type default))
          (fill (type none))
        )
      )
      (symbol "C_100n_0201_65_1_1"
        (pin passive line (at 0 0 0) (length 2.032)
          (name "~" (effects (font (size 1.27 1.27))))
          (number "1" (effects (font (size 1.27 1.27))))
        )
        (pin passive line (at 5.08 0 180) (length 2.032)
          (name "~" (effects (font (size 1.27 1.27))))
          (number "2" (effects (font (size 1.27 1.27))))
        )
      )
    )
	(symbol "data-center-rdimm-ddr4-tester:C_100n_0201_66" (pin_numbers hide) (pin_names hide) (in_bom yes) (on_board yes)
      (property "Reference" "C" (at 20.32 -5.08 0)
        (effects (font (size 1.27 1.27) (thickness 0.15)) (justify left bottom))
      )
      (property "Value" "C_100n_0201_66" (at 20.32 -10.16 0)
        (effects (font (size 1.27 1.27) (thickness 0.15)) (justify left bottom) hide)
      )
      (property "Footprint" "data-center-rdimm-ddr4-tester-footprints:C_0201" (at 20.32 -12.7 0)
        (effects (font (size 1.27 1.27) (thickness 0.15)) (justify left bottom) hide)
      )
      (property "Datasheet" " " (at 20.32 -15.24 0)
        (effects (font (size 1.27 1.27) (thickness 0.15)) (justify left bottom) hide)
      )
      (property "MPN" "CC0201KRX6S5BB104" (at 20.32 -17.78 0)
        (effects (font (size 1.27 1.27) (thickness 0.15)) (justify left bottom) hide)
      )
      (property "Manufacturer" "Yaego" (at 20.32 -20.32 0)
        (effects (font (size 1.27 1.27) (thickness 0.15)) (justify left bottom) hide)
      )
      (property "License" "Apache-2.0" (at 20.32 -22.86 0)
        (effects (font (size 1.27 1.27) (thickness 0.15)) (justify left bottom) hide)
      )
      (property "Author" "Antmicro" (at 20.32 -25.4 0)
        (effects (font (size 1.27 1.27) (thickness 0.15)) (justify left bottom) hide)
      )
      (property "Val" "100n" (at 20.32 -7.62 0)
        (effects (font (size 1.27 1.27) (thickness 0.15)) (justify left bottom))
      )
      (property "Voltage" "" (at 20.32 -27.94 0)
        (effects (font (size 1.27 1.27)) (justify left bottom) hide)
      )
      (property "Dielectric" "" (at 20.32 -30.48 0)
        (effects (font (size 1.27 1.27)) (justify left bottom) hide)
      )
      (property "ki_description" " " (at 0 0 0)
        (effects (font (size 1.27 1.27)) hide)
      )
      (symbol "C_100n_0201_66_0_1"
        (polyline
          (pts
            (xy 2.032 -1.524)
            (xy 2.032 1.524)
          )
          (stroke (width 0.3048) (type default))
          (fill (type none))
        )
        (polyline
          (pts
            (xy 3.048 -1.524)
            (xy 3.048 1.524)
          )
          (stroke (width 0.3302) (type default))
          (fill (type none))
        )
      )
      (symbol "C_100n_0201_66_1_1"
        (pin passive line (at 0 0 0) (length 2.032)
          (name "~" (effects (font (size 1.27 1.27))))
          (number "1" (effects (font (size 1.27 1.27))))
        )
        (pin passive line (at 5.08 0 180) (length 2.032)
          (name "~" (effects (font (size 1.27 1.27))))
          (number "2" (effects (font (size 1.27 1.27))))
        )
      )
    )
	(symbol "data-center-rdimm-ddr4-tester:C_100n_0201_67" (pin_numbers hide) (pin_names hide) (in_bom yes) (on_board yes)
      (property "Reference" "C" (at 20.32 -5.08 0)
        (effects (font (size 1.27 1.27) (thickness 0.15)) (justify left bottom))
      )
      (property "Value" "C_100n_0201_67" (at 20.32 -10.16 0)
        (effects (font (size 1.27 1.27) (thickness 0.15)) (justify left bottom) hide)
      )
      (property "Footprint" "data-center-rdimm-ddr4-tester-footprints:C_0201" (at 20.32 -12.7 0)
        (effects (font (size 1.27 1.27) (thickness 0.15)) (justify left bottom) hide)
      )
      (property "Datasheet" " " (at 20.32 -15.24 0)
        (effects (font (size 1.27 1.27) (thickness 0.15)) (justify left bottom) hide)
      )
      (property "MPN" "CC0201KRX6S5BB104" (at 20.32 -17.78 0)
        (effects (font (size 1.27 1.27) (thickness 0.15)) (justify left bottom) hide)
      )
      (property "Manufacturer" "Yaego" (at 20.32 -20.32 0)
        (effects (font (size 1.27 1.27) (thickness 0.15)) (justify left bottom) hide)
      )
      (property "License" "Apache-2.0" (at 20.32 -22.86 0)
        (effects (font (size 1.27 1.27) (thickness 0.15)) (justify left bottom) hide)
      )
      (property "Author" "Antmicro" (at 20.32 -25.4 0)
        (effects (font (size 1.27 1.27) (thickness 0.15)) (justify left bottom) hide)
      )
      (property "Val" "100n" (at 20.32 -7.62 0)
        (effects (font (size 1.27 1.27) (thickness 0.15)) (justify left bottom))
      )
      (property "Voltage" "" (at 20.32 -27.94 0)
        (effects (font (size 1.27 1.27)) (justify left bottom) hide)
      )
      (property "Dielectric" "" (at 20.32 -30.48 0)
        (effects (font (size 1.27 1.27)) (justify left bottom) hide)
      )
      (property "ki_description" " " (at 0 0 0)
        (effects (font (size 1.27 1.27)) hide)
      )
      (symbol "C_100n_0201_67_0_1"
        (polyline
          (pts
            (xy 2.032 -1.524)
            (xy 2.032 1.524)
          )
          (stroke (width 0.3048) (type default))
          (fill (type none))
        )
        (polyline
          (pts
            (xy 3.048 -1.524)
            (xy 3.048 1.524)
          )
          (stroke (width 0.3302) (type default))
          (fill (type none))
        )
      )
      (symbol "C_100n_0201_67_1_1"
        (pin passive line (at 0 0 0) (length 2.032)
          (name "~" (effects (font (size 1.27 1.27))))
          (number "1" (effects (font (size 1.27 1.27))))
        )
        (pin passive line (at 5.08 0 180) (length 2.032)
          (name "~" (effects (font (size 1.27 1.27))))
          (number "2" (effects (font (size 1.27 1.27))))
        )
      )
    )
	(symbol "data-center-rdimm-ddr4-tester:C_100n_0201_68" (pin_numbers hide) (pin_names hide) (in_bom yes) (on_board yes)
      (property "Reference" "C" (at 20.32 -5.08 0)
        (effects (font (size 1.27 1.27) (thickness 0.15)) (justify left bottom))
      )
      (property "Value" "C_100n_0201_68" (at 20.32 -10.16 0)
        (effects (font (size 1.27 1.27) (thickness 0.15)) (justify left bottom) hide)
      )
      (property "Footprint" "data-center-rdimm-ddr4-tester-footprints:C_0201" (at 20.32 -12.7 0)
        (effects (font (size 1.27 1.27) (thickness 0.15)) (justify left bottom) hide)
      )
      (property "Datasheet" " " (at 20.32 -15.24 0)
        (effects (font (size 1.27 1.27) (thickness 0.15)) (justify left bottom) hide)
      )
      (property "MPN" "CC0201KRX6S5BB104" (at 20.32 -17.78 0)
        (effects (font (size 1.27 1.27) (thickness 0.15)) (justify left bottom) hide)
      )
      (property "Manufacturer" "Yaego" (at 20.32 -20.32 0)
        (effects (font (size 1.27 1.27) (thickness 0.15)) (justify left bottom) hide)
      )
      (property "License" "Apache-2.0" (at 20.32 -22.86 0)
        (effects (font (size 1.27 1.27) (thickness 0.15)) (justify left bottom) hide)
      )
      (property "Author" "Antmicro" (at 20.32 -25.4 0)
        (effects (font (size 1.27 1.27) (thickness 0.15)) (justify left bottom) hide)
      )
      (property "Val" "100n" (at 20.32 -7.62 0)
        (effects (font (size 1.27 1.27) (thickness 0.15)) (justify left bottom))
      )
      (property "Voltage" "" (at 20.32 -27.94 0)
        (effects (font (size 1.27 1.27)) (justify left bottom) hide)
      )
      (property "Dielectric" "" (at 20.32 -30.48 0)
        (effects (font (size 1.27 1.27)) (justify left bottom) hide)
      )
      (property "ki_description" " " (at 0 0 0)
        (effects (font (size 1.27 1.27)) hide)
      )
      (symbol "C_100n_0201_68_0_1"
        (polyline
          (pts
            (xy 2.032 -1.524)
            (xy 2.032 1.524)
          )
          (stroke (width 0.3048) (type default))
          (fill (type none))
        )
        (polyline
          (pts
            (xy 3.048 -1.524)
            (xy 3.048 1.524)
          )
          (stroke (width 0.3302) (type default))
          (fill (type none))
        )
      )
      (symbol "C_100n_0201_68_1_1"
        (pin passive line (at 0 0 0) (length 2.032)
          (name "~" (effects (font (size 1.27 1.27))))
          (number "1" (effects (font (size 1.27 1.27))))
        )
        (pin passive line (at 5.08 0 180) (length 2.032)
          (name "~" (effects (font (size 1.27 1.27))))
          (number "2" (effects (font (size 1.27 1.27))))
        )
      )
    )
	(symbol "data-center-rdimm-ddr4-tester:C_100n_0201_69" (pin_numbers hide) (pin_names hide) (in_bom yes) (on_board yes)
      (property "Reference" "C" (at 20.32 -5.08 0)
        (effects (font (size 1.27 1.27) (thickness 0.15)) (justify left bottom))
      )
      (property "Value" "C_100n_0201_69" (at 20.32 -10.16 0)
        (effects (font (size 1.27 1.27) (thickness 0.15)) (justify left bottom) hide)
      )
      (property "Footprint" "data-center-rdimm-ddr4-tester-footprints:C_0201" (at 20.32 -12.7 0)
        (effects (font (size 1.27 1.27) (thickness 0.15)) (justify left bottom) hide)
      )
      (property "Datasheet" " " (at 20.32 -15.24 0)
        (effects (font (size 1.27 1.27) (thickness 0.15)) (justify left bottom) hide)
      )
      (property "MPN" "CC0201KRX6S5BB104" (at 20.32 -17.78 0)
        (effects (font (size 1.27 1.27) (thickness 0.15)) (justify left bottom) hide)
      )
      (property "Manufacturer" "Yaego" (at 20.32 -20.32 0)
        (effects (font (size 1.27 1.27) (thickness 0.15)) (justify left bottom) hide)
      )
      (property "License" "Apache-2.0" (at 20.32 -22.86 0)
        (effects (font (size 1.27 1.27) (thickness 0.15)) (justify left bottom) hide)
      )
      (property "Author" "Antmicro" (at 20.32 -25.4 0)
        (effects (font (size 1.27 1.27) (thickness 0.15)) (justify left bottom) hide)
      )
      (property "Val" "100n" (at 20.32 -7.62 0)
        (effects (font (size 1.27 1.27) (thickness 0.15)) (justify left bottom))
      )
      (property "Voltage" "" (at 20.32 -27.94 0)
        (effects (font (size 1.27 1.27)) (justify left bottom) hide)
      )
      (property "Dielectric" "" (at 20.32 -30.48 0)
        (effects (font (size 1.27 1.27)) (justify left bottom) hide)
      )
      (property "ki_description" " " (at 0 0 0)
        (effects (font (size 1.27 1.27)) hide)
      )
      (symbol "C_100n_0201_69_0_1"
        (polyline
          (pts
            (xy 2.032 -1.524)
            (xy 2.032 1.524)
          )
          (stroke (width 0.3048) (type default))
          (fill (type none))
        )
        (polyline
          (pts
            (xy 3.048 -1.524)
            (xy 3.048 1.524)
          )
          (stroke (width 0.3302) (type default))
          (fill (type none))
        )
      )
      (symbol "C_100n_0201_69_1_1"
        (pin passive line (at 0 0 0) (length 2.032)
          (name "~" (effects (font (size 1.27 1.27))))
          (number "1" (effects (font (size 1.27 1.27))))
        )
        (pin passive line (at 5.08 0 180) (length 2.032)
          (name "~" (effects (font (size 1.27 1.27))))
          (number "2" (effects (font (size 1.27 1.27))))
        )
      )
    )
	(symbol "data-center-rdimm-ddr4-tester:C_100n_0201_70" (pin_numbers hide) (pin_names hide) (in_bom yes) (on_board yes)
      (property "Reference" "C" (at 20.32 -5.08 0)
        (effects (font (size 1.27 1.27) (thickness 0.15)) (justify left bottom))
      )
      (property "Value" "C_100n_0201_70" (at 20.32 -10.16 0)
        (effects (font (size 1.27 1.27) (thickness 0.15)) (justify left bottom) hide)
      )
      (property "Footprint" "data-center-rdimm-ddr4-tester-footprints:C_0201" (at 20.32 -12.7 0)
        (effects (font (size 1.27 1.27) (thickness 0.15)) (justify left bottom) hide)
      )
      (property "Datasheet" " " (at 20.32 -15.24 0)
        (effects (font (size 1.27 1.27) (thickness 0.15)) (justify left bottom) hide)
      )
      (property "MPN" "CC0201KRX6S5BB104" (at 20.32 -17.78 0)
        (effects (font (size 1.27 1.27) (thickness 0.15)) (justify left bottom) hide)
      )
      (property "Manufacturer" "Yaego" (at 20.32 -20.32 0)
        (effects (font (size 1.27 1.27) (thickness 0.15)) (justify left bottom) hide)
      )
      (property "License" "Apache-2.0" (at 20.32 -22.86 0)
        (effects (font (size 1.27 1.27) (thickness 0.15)) (justify left bottom) hide)
      )
      (property "Author" "Antmicro" (at 20.32 -25.4 0)
        (effects (font (size 1.27 1.27) (thickness 0.15)) (justify left bottom) hide)
      )
      (property "Val" "100n" (at 20.32 -7.62 0)
        (effects (font (size 1.27 1.27) (thickness 0.15)) (justify left bottom))
      )
      (property "Voltage" "" (at 20.32 -27.94 0)
        (effects (font (size 1.27 1.27)) (justify left bottom) hide)
      )
      (property "Dielectric" "" (at 20.32 -30.48 0)
        (effects (font (size 1.27 1.27)) (justify left bottom) hide)
      )
      (property "ki_description" " " (at 0 0 0)
        (effects (font (size 1.27 1.27)) hide)
      )
      (symbol "C_100n_0201_70_0_1"
        (polyline
          (pts
            (xy 2.032 -1.524)
            (xy 2.032 1.524)
          )
          (stroke (width 0.3048) (type default))
          (fill (type none))
        )
        (polyline
          (pts
            (xy 3.048 -1.524)
            (xy 3.048 1.524)
          )
          (stroke (width 0.3302) (type default))
          (fill (type none))
        )
      )
      (symbol "C_100n_0201_70_1_1"
        (pin passive line (at 0 0 0) (length 2.032)
          (name "~" (effects (font (size 1.27 1.27))))
          (number "1" (effects (font (size 1.27 1.27))))
        )
        (pin passive line (at 5.08 0 180) (length 2.032)
          (name "~" (effects (font (size 1.27 1.27))))
          (number "2" (effects (font (size 1.27 1.27))))
        )
      )
    )
	(symbol "data-center-rdimm-ddr4-tester:C_100n_0201_71" (pin_numbers hide) (pin_names hide) (in_bom yes) (on_board yes)
      (property "Reference" "C" (at 20.32 -5.08 0)
        (effects (font (size 1.27 1.27) (thickness 0.15)) (justify left bottom))
      )
      (property "Value" "C_100n_0201_71" (at 20.32 -10.16 0)
        (effects (font (size 1.27 1.27) (thickness 0.15)) (justify left bottom) hide)
      )
      (property "Footprint" "data-center-rdimm-ddr4-tester-footprints:C_0201" (at 20.32 -12.7 0)
        (effects (font (size 1.27 1.27) (thickness 0.15)) (justify left bottom) hide)
      )
      (property "Datasheet" " " (at 20.32 -15.24 0)
        (effects (font (size 1.27 1.27) (thickness 0.15)) (justify left bottom) hide)
      )
      (property "MPN" "CC0201KRX6S5BB104" (at 20.32 -17.78 0)
        (effects (font (size 1.27 1.27) (thickness 0.15)) (justify left bottom) hide)
      )
      (property "Manufacturer" "Yaego" (at 20.32 -20.32 0)
        (effects (font (size 1.27 1.27) (thickness 0.15)) (justify left bottom) hide)
      )
      (property "License" "Apache-2.0" (at 20.32 -22.86 0)
        (effects (font (size 1.27 1.27) (thickness 0.15)) (justify left bottom) hide)
      )
      (property "Author" "Antmicro" (at 20.32 -25.4 0)
        (effects (font (size 1.27 1.27) (thickness 0.15)) (justify left bottom) hide)
      )
      (property "Val" "100n" (at 20.32 -7.62 0)
        (effects (font (size 1.27 1.27) (thickness 0.15)) (justify left bottom))
      )
      (property "Voltage" "" (at 20.32 -27.94 0)
        (effects (font (size 1.27 1.27)) (justify left bottom) hide)
      )
      (property "Dielectric" "" (at 20.32 -30.48 0)
        (effects (font (size 1.27 1.27)) (justify left bottom) hide)
      )
      (property "ki_description" " " (at 0 0 0)
        (effects (font (size 1.27 1.27)) hide)
      )
      (symbol "C_100n_0201_71_0_1"
        (polyline
          (pts
            (xy 2.032 -1.524)
            (xy 2.032 1.524)
          )
          (stroke (width 0.3048) (type default))
          (fill (type none))
        )
        (polyline
          (pts
            (xy 3.048 -1.524)
            (xy 3.048 1.524)
          )
          (stroke (width 0.3302) (type default))
          (fill (type none))
        )
      )
      (symbol "C_100n_0201_71_1_1"
        (pin passive line (at 0 0 0) (length 2.032)
          (name "~" (effects (font (size 1.27 1.27))))
          (number "1" (effects (font (size 1.27 1.27))))
        )
        (pin passive line (at 5.08 0 180) (length 2.032)
          (name "~" (effects (font (size 1.27 1.27))))
          (number "2" (effects (font (size 1.27 1.27))))
        )
      )
    )
	(symbol "data-center-rdimm-ddr4-tester:C_100n_0201_72" (pin_numbers hide) (pin_names hide) (in_bom yes) (on_board yes)
      (property "Reference" "C" (at 20.32 -5.08 0)
        (effects (font (size 1.27 1.27) (thickness 0.15)) (justify left bottom))
      )
      (property "Value" "C_100n_0201_72" (at 20.32 -10.16 0)
        (effects (font (size 1.27 1.27) (thickness 0.15)) (justify left bottom) hide)
      )
      (property "Footprint" "data-center-rdimm-ddr4-tester-footprints:C_0201" (at 20.32 -12.7 0)
        (effects (font (size 1.27 1.27) (thickness 0.15)) (justify left bottom) hide)
      )
      (property "Datasheet" " " (at 20.32 -15.24 0)
        (effects (font (size 1.27 1.27) (thickness 0.15)) (justify left bottom) hide)
      )
      (property "MPN" "CC0201KRX6S5BB104" (at 20.32 -17.78 0)
        (effects (font (size 1.27 1.27) (thickness 0.15)) (justify left bottom) hide)
      )
      (property "Manufacturer" "Yaego" (at 20.32 -20.32 0)
        (effects (font (size 1.27 1.27) (thickness 0.15)) (justify left bottom) hide)
      )
      (property "License" "Apache-2.0" (at 20.32 -22.86 0)
        (effects (font (size 1.27 1.27) (thickness 0.15)) (justify left bottom) hide)
      )
      (property "Author" "Antmicro" (at 20.32 -25.4 0)
        (effects (font (size 1.27 1.27) (thickness 0.15)) (justify left bottom) hide)
      )
      (property "Val" "100n" (at 20.32 -7.62 0)
        (effects (font (size 1.27 1.27) (thickness 0.15)) (justify left bottom))
      )
      (property "Voltage" "" (at 20.32 -27.94 0)
        (effects (font (size 1.27 1.27)) (justify left bottom) hide)
      )
      (property "Dielectric" "" (at 20.32 -30.48 0)
        (effects (font (size 1.27 1.27)) (justify left bottom) hide)
      )
      (property "ki_description" " " (at 0 0 0)
        (effects (font (size 1.27 1.27)) hide)
      )
      (symbol "C_100n_0201_72_0_1"
        (polyline
          (pts
            (xy 2.032 -1.524)
            (xy 2.032 1.524)
          )
          (stroke (width 0.3048) (type default))
          (fill (type none))
        )
        (polyline
          (pts
            (xy 3.048 -1.524)
            (xy 3.048 1.524)
          )
          (stroke (width 0.3302) (type default))
          (fill (type none))
        )
      )
      (symbol "C_100n_0201_72_1_1"
        (pin passive line (at 0 0 0) (length 2.032)
          (name "~" (effects (font (size 1.27 1.27))))
          (number "1" (effects (font (size 1.27 1.27))))
        )
        (pin passive line (at 5.08 0 180) (length 2.032)
          (name "~" (effects (font (size 1.27 1.27))))
          (number "2" (effects (font (size 1.27 1.27))))
        )
      )
    )
	(symbol "data-center-rdimm-ddr4-tester:C_100n_0201_73" (pin_numbers hide) (pin_names hide) (in_bom yes) (on_board yes)
      (property "Reference" "C" (at 20.32 -5.08 0)
        (effects (font (size 1.27 1.27) (thickness 0.15)) (justify left bottom))
      )
      (property "Value" "C_100n_0201_73" (at 20.32 -10.16 0)
        (effects (font (size 1.27 1.27) (thickness 0.15)) (justify left bottom) hide)
      )
      (property "Footprint" "data-center-rdimm-ddr4-tester-footprints:C_0201" (at 20.32 -12.7 0)
        (effects (font (size 1.27 1.27) (thickness 0.15)) (justify left bottom) hide)
      )
      (property "Datasheet" " " (at 20.32 -15.24 0)
        (effects (font (size 1.27 1.27) (thickness 0.15)) (justify left bottom) hide)
      )
      (property "MPN" "CC0201KRX6S5BB104" (at 20.32 -17.78 0)
        (effects (font (size 1.27 1.27) (thickness 0.15)) (justify left bottom) hide)
      )
      (property "Manufacturer" "Yaego" (at 20.32 -20.32 0)
        (effects (font (size 1.27 1.27) (thickness 0.15)) (justify left bottom) hide)
      )
      (property "License" "Apache-2.0" (at 20.32 -22.86 0)
        (effects (font (size 1.27 1.27) (thickness 0.15)) (justify left bottom) hide)
      )
      (property "Author" "Antmicro" (at 20.32 -25.4 0)
        (effects (font (size 1.27 1.27) (thickness 0.15)) (justify left bottom) hide)
      )
      (property "Val" "100n" (at 20.32 -7.62 0)
        (effects (font (size 1.27 1.27) (thickness 0.15)) (justify left bottom))
      )
      (property "Voltage" "" (at 20.32 -27.94 0)
        (effects (font (size 1.27 1.27)) (justify left bottom) hide)
      )
      (property "Dielectric" "" (at 20.32 -30.48 0)
        (effects (font (size 1.27 1.27)) (justify left bottom) hide)
      )
      (property "ki_description" " " (at 0 0 0)
        (effects (font (size 1.27 1.27)) hide)
      )
      (symbol "C_100n_0201_73_0_1"
        (polyline
          (pts
            (xy 2.032 -1.524)
            (xy 2.032 1.524)
          )
          (stroke (width 0.3048) (type default))
          (fill (type none))
        )
        (polyline
          (pts
            (xy 3.048 -1.524)
            (xy 3.048 1.524)
          )
          (stroke (width 0.3302) (type default))
          (fill (type none))
        )
      )
      (symbol "C_100n_0201_73_1_1"
        (pin passive line (at 0 0 0) (length 2.032)
          (name "~" (effects (font (size 1.27 1.27))))
          (number "1" (effects (font (size 1.27 1.27))))
        )
        (pin passive line (at 5.08 0 180) (length 2.032)
          (name "~" (effects (font (size 1.27 1.27))))
          (number "2" (effects (font (size 1.27 1.27))))
        )
      )
    )
	(symbol "data-center-rdimm-ddr4-tester:C_100n_0201_74" (pin_numbers hide) (pin_names hide) (in_bom yes) (on_board yes)
      (property "Reference" "C" (at 20.32 -5.08 0)
        (effects (font (size 1.27 1.27) (thickness 0.15)) (justify left bottom))
      )
      (property "Value" "C_100n_0201_74" (at 20.32 -10.16 0)
        (effects (font (size 1.27 1.27) (thickness 0.15)) (justify left bottom) hide)
      )
      (property "Footprint" "data-center-rdimm-ddr4-tester-footprints:C_0201" (at 20.32 -12.7 0)
        (effects (font (size 1.27 1.27) (thickness 0.15)) (justify left bottom) hide)
      )
      (property "Datasheet" " " (at 20.32 -15.24 0)
        (effects (font (size 1.27 1.27) (thickness 0.15)) (justify left bottom) hide)
      )
      (property "MPN" "CC0201KRX6S5BB104" (at 20.32 -17.78 0)
        (effects (font (size 1.27 1.27) (thickness 0.15)) (justify left bottom) hide)
      )
      (property "Manufacturer" "Yaego" (at 20.32 -20.32 0)
        (effects (font (size 1.27 1.27) (thickness 0.15)) (justify left bottom) hide)
      )
      (property "License" "Apache-2.0" (at 20.32 -22.86 0)
        (effects (font (size 1.27 1.27) (thickness 0.15)) (justify left bottom) hide)
      )
      (property "Author" "Antmicro" (at 20.32 -25.4 0)
        (effects (font (size 1.27 1.27) (thickness 0.15)) (justify left bottom) hide)
      )
      (property "Val" "100n" (at 20.32 -7.62 0)
        (effects (font (size 1.27 1.27) (thickness 0.15)) (justify left bottom))
      )
      (property "Voltage" "" (at 20.32 -27.94 0)
        (effects (font (size 1.27 1.27)) (justify left bottom) hide)
      )
      (property "Dielectric" "" (at 20.32 -30.48 0)
        (effects (font (size 1.27 1.27)) (justify left bottom) hide)
      )
      (property "ki_description" " " (at 0 0 0)
        (effects (font (size 1.27 1.27)) hide)
      )
      (symbol "C_100n_0201_74_0_1"
        (polyline
          (pts
            (xy 2.032 -1.524)
            (xy 2.032 1.524)
          )
          (stroke (width 0.3048) (type default))
          (fill (type none))
        )
        (polyline
          (pts
            (xy 3.048 -1.524)
            (xy 3.048 1.524)
          )
          (stroke (width 0.3302) (type default))
          (fill (type none))
        )
      )
      (symbol "C_100n_0201_74_1_1"
        (pin passive line (at 0 0 0) (length 2.032)
          (name "~" (effects (font (size 1.27 1.27))))
          (number "1" (effects (font (size 1.27 1.27))))
        )
        (pin passive line (at 5.08 0 180) (length 2.032)
          (name "~" (effects (font (size 1.27 1.27))))
          (number "2" (effects (font (size 1.27 1.27))))
        )
      )
    )
	(symbol "data-center-rdimm-ddr4-tester:C_100n_0201_75" (pin_numbers hide) (pin_names hide) (in_bom yes) (on_board yes)
      (property "Reference" "C" (at 20.32 -5.08 0)
        (effects (font (size 1.27 1.27) (thickness 0.15)) (justify left bottom))
      )
      (property "Value" "C_100n_0201_75" (at 20.32 -10.16 0)
        (effects (font (size 1.27 1.27) (thickness 0.15)) (justify left bottom) hide)
      )
      (property "Footprint" "data-center-rdimm-ddr4-tester-footprints:C_0201" (at 20.32 -12.7 0)
        (effects (font (size 1.27 1.27) (thickness 0.15)) (justify left bottom) hide)
      )
      (property "Datasheet" " " (at 20.32 -15.24 0)
        (effects (font (size 1.27 1.27) (thickness 0.15)) (justify left bottom) hide)
      )
      (property "MPN" "CC0201KRX6S5BB104" (at 20.32 -17.78 0)
        (effects (font (size 1.27 1.27) (thickness 0.15)) (justify left bottom) hide)
      )
      (property "Manufacturer" "Yaego" (at 20.32 -20.32 0)
        (effects (font (size 1.27 1.27) (thickness 0.15)) (justify left bottom) hide)
      )
      (property "License" "Apache-2.0" (at 20.32 -22.86 0)
        (effects (font (size 1.27 1.27) (thickness 0.15)) (justify left bottom) hide)
      )
      (property "Author" "Antmicro" (at 20.32 -25.4 0)
        (effects (font (size 1.27 1.27) (thickness 0.15)) (justify left bottom) hide)
      )
      (property "Val" "100n" (at 20.32 -7.62 0)
        (effects (font (size 1.27 1.27) (thickness 0.15)) (justify left bottom))
      )
      (property "Voltage" "" (at 20.32 -27.94 0)
        (effects (font (size 1.27 1.27)) (justify left bottom) hide)
      )
      (property "Dielectric" "" (at 20.32 -30.48 0)
        (effects (font (size 1.27 1.27)) (justify left bottom) hide)
      )
      (property "ki_description" " " (at 0 0 0)
        (effects (font (size 1.27 1.27)) hide)
      )
      (symbol "C_100n_0201_75_0_1"
        (polyline
          (pts
            (xy 2.032 -1.524)
            (xy 2.032 1.524)
          )
          (stroke (width 0.3048) (type default))
          (fill (type none))
        )
        (polyline
          (pts
            (xy 3.048 -1.524)
            (xy 3.048 1.524)
          )
          (stroke (width 0.3302) (type default))
          (fill (type none))
        )
      )
      (symbol "C_100n_0201_75_1_1"
        (pin passive line (at 0 0 0) (length 2.032)
          (name "~" (effects (font (size 1.27 1.27))))
          (number "1" (effects (font (size 1.27 1.27))))
        )
        (pin passive line (at 5.08 0 180) (length 2.032)
          (name "~" (effects (font (size 1.27 1.27))))
          (number "2" (effects (font (size 1.27 1.27))))
        )
      )
    )
	(symbol "data-center-rdimm-ddr4-tester:C_100n_0201_76" (pin_numbers hide) (pin_names hide) (in_bom yes) (on_board yes)
      (property "Reference" "C" (at 20.32 -5.08 0)
        (effects (font (size 1.27 1.27) (thickness 0.15)) (justify left bottom))
      )
      (property "Value" "C_100n_0201_76" (at 20.32 -10.16 0)
        (effects (font (size 1.27 1.27) (thickness 0.15)) (justify left bottom) hide)
      )
      (property "Footprint" "data-center-rdimm-ddr4-tester-footprints:C_0201" (at 20.32 -12.7 0)
        (effects (font (size 1.27 1.27) (thickness 0.15)) (justify left bottom) hide)
      )
      (property "Datasheet" " " (at 20.32 -15.24 0)
        (effects (font (size 1.27 1.27) (thickness 0.15)) (justify left bottom) hide)
      )
      (property "MPN" "CC0201KRX6S5BB104" (at 20.32 -17.78 0)
        (effects (font (size 1.27 1.27) (thickness 0.15)) (justify left bottom) hide)
      )
      (property "Manufacturer" "Yaego" (at 20.32 -20.32 0)
        (effects (font (size 1.27 1.27) (thickness 0.15)) (justify left bottom) hide)
      )
      (property "License" "Apache-2.0" (at 20.32 -22.86 0)
        (effects (font (size 1.27 1.27) (thickness 0.15)) (justify left bottom) hide)
      )
      (property "Author" "Antmicro" (at 20.32 -25.4 0)
        (effects (font (size 1.27 1.27) (thickness 0.15)) (justify left bottom) hide)
      )
      (property "Val" "100n" (at 20.32 -7.62 0)
        (effects (font (size 1.27 1.27) (thickness 0.15)) (justify left bottom))
      )
      (property "Voltage" "" (at 20.32 -27.94 0)
        (effects (font (size 1.27 1.27)) (justify left bottom) hide)
      )
      (property "Dielectric" "" (at 20.32 -30.48 0)
        (effects (font (size 1.27 1.27)) (justify left bottom) hide)
      )
      (property "ki_description" " " (at 0 0 0)
        (effects (font (size 1.27 1.27)) hide)
      )
      (symbol "C_100n_0201_76_0_1"
        (polyline
          (pts
            (xy 2.032 -1.524)
            (xy 2.032 1.524)
          )
          (stroke (width 0.3048) (type default))
          (fill (type none))
        )
        (polyline
          (pts
            (xy 3.048 -1.524)
            (xy 3.048 1.524)
          )
          (stroke (width 0.3302) (type default))
          (fill (type none))
        )
      )
      (symbol "C_100n_0201_76_1_1"
        (pin passive line (at 0 0 0) (length 2.032)
          (name "~" (effects (font (size 1.27 1.27))))
          (number "1" (effects (font (size 1.27 1.27))))
        )
        (pin passive line (at 5.08 0 180) (length 2.032)
          (name "~" (effects (font (size 1.27 1.27))))
          (number "2" (effects (font (size 1.27 1.27))))
        )
      )
    )
	(symbol "data-center-rdimm-ddr4-tester:C_100n_0402_10" (pin_numbers hide) (pin_names hide) (in_bom yes) (on_board yes)
      (property "Reference" "C" (at 20.32 -5.08 0)
        (effects (font (size 1.27 1.27) (thickness 0.15)) (justify left bottom))
      )
      (property "Value" "C_100n_0402_10" (at 20.32 -10.16 0)
        (effects (font (size 1.27 1.27) (thickness 0.15)) (justify left bottom) hide)
      )
      (property "Footprint" "data-center-rdimm-ddr4-tester-footprints:C_0402_1005Metric" (at 20.32 -12.7 0)
        (effects (font (size 1.27 1.27) (thickness 0.15)) (justify left bottom) hide)
      )
      (property "Datasheet" "https://search.murata.co.jp/Ceramy/image/img/A01X/G101/ENG/GRM155R61H104KE14-01.pdf" (at 20.32 -15.24 0)
        (effects (font (size 1.27 1.27) (thickness 0.15)) (justify left bottom) hide)
      )
      (property "MPN" "GRM155R61H104KE14D" (at 20.32 -17.78 0)
        (effects (font (size 1.27 1.27) (thickness 0.15)) (justify left bottom) hide)
      )
      (property "Manufacturer" "Murata" (at 20.32 -20.32 0)
        (effects (font (size 1.27 1.27) (thickness 0.15)) (justify left bottom) hide)
      )
      (property "License" "Apache-2.0" (at 20.32 -22.86 0)
        (effects (font (size 1.27 1.27) (thickness 0.15)) (justify left bottom) hide)
      )
      (property "Author" "Antmicro" (at 20.32 -25.4 0)
        (effects (font (size 1.27 1.27) (thickness 0.15)) (justify left bottom) hide)
      )
      (property "Val" "100n" (at 20.32 -7.62 0)
        (effects (font (size 1.27 1.27) (thickness 0.15)) (justify left bottom))
      )
      (property "Voltage" "50V" (at 20.32 -27.94 0)
        (effects (font (size 1.27 1.27)) (justify left bottom) hide)
      )
      (property "Dielectric" "X5R" (at 20.32 -30.48 0)
        (effects (font (size 1.27 1.27)) (justify left bottom) hide)
      )
      (property "ki_description" " " (at 0 0 0)
        (effects (font (size 1.27 1.27)) hide)
      )
      (symbol "C_100n_0402_10_0_1"
        (polyline
          (pts
            (xy 2.032 -1.524)
            (xy 2.032 1.524)
          )
          (stroke (width 0.3048) (type default))
          (fill (type none))
        )
        (polyline
          (pts
            (xy 3.048 -1.524)
            (xy 3.048 1.524)
          )
          (stroke (width 0.3302) (type default))
          (fill (type none))
        )
      )
      (symbol "C_100n_0402_10_1_1"
        (pin passive line (at 0 0 0) (length 2.032)
          (name "~" (effects (font (size 1.27 1.27))))
          (number "1" (effects (font (size 1.27 1.27))))
        )
        (pin passive line (at 5.08 0 180) (length 2.032)
          (name "~" (effects (font (size 1.27 1.27))))
          (number "2" (effects (font (size 1.27 1.27))))
        )
      )
    )
	(symbol "data-center-rdimm-ddr4-tester:C_100n_0402_11" (pin_numbers hide) (pin_names hide) (in_bom yes) (on_board yes)
      (property "Reference" "C" (at 20.32 -5.08 0)
        (effects (font (size 1.27 1.27) (thickness 0.15)) (justify left bottom))
      )
      (property "Value" "C_100n_0402_11" (at 20.32 -10.16 0)
        (effects (font (size 1.27 1.27) (thickness 0.15)) (justify left bottom) hide)
      )
      (property "Footprint" "data-center-rdimm-ddr4-tester-footprints:C_0402_1005Metric" (at 20.32 -12.7 0)
        (effects (font (size 1.27 1.27) (thickness 0.15)) (justify left bottom) hide)
      )
      (property "Datasheet" "https://search.murata.co.jp/Ceramy/image/img/A01X/G101/ENG/GRM155R61H104KE14-01.pdf" (at 20.32 -15.24 0)
        (effects (font (size 1.27 1.27) (thickness 0.15)) (justify left bottom) hide)
      )
      (property "MPN" "GRM155R61H104KE14D" (at 20.32 -17.78 0)
        (effects (font (size 1.27 1.27) (thickness 0.15)) (justify left bottom) hide)
      )
      (property "Manufacturer" "Murata" (at 20.32 -20.32 0)
        (effects (font (size 1.27 1.27) (thickness 0.15)) (justify left bottom) hide)
      )
      (property "License" "Apache-2.0" (at 20.32 -22.86 0)
        (effects (font (size 1.27 1.27) (thickness 0.15)) (justify left bottom) hide)
      )
      (property "Author" "Antmicro" (at 20.32 -25.4 0)
        (effects (font (size 1.27 1.27) (thickness 0.15)) (justify left bottom) hide)
      )
      (property "Val" "100n" (at 20.32 -7.62 0)
        (effects (font (size 1.27 1.27) (thickness 0.15)) (justify left bottom))
      )
      (property "Voltage" "50V" (at 20.32 -27.94 0)
        (effects (font (size 1.27 1.27)) (justify left bottom) hide)
      )
      (property "Dielectric" "X5R" (at 20.32 -30.48 0)
        (effects (font (size 1.27 1.27)) (justify left bottom) hide)
      )
      (property "ki_description" " " (at 0 0 0)
        (effects (font (size 1.27 1.27)) hide)
      )
      (symbol "C_100n_0402_11_0_1"
        (polyline
          (pts
            (xy 2.032 -1.524)
            (xy 2.032 1.524)
          )
          (stroke (width 0.3048) (type default))
          (fill (type none))
        )
        (polyline
          (pts
            (xy 3.048 -1.524)
            (xy 3.048 1.524)
          )
          (stroke (width 0.3302) (type default))
          (fill (type none))
        )
      )
      (symbol "C_100n_0402_11_1_1"
        (pin passive line (at 0 0 0) (length 2.032)
          (name "~" (effects (font (size 1.27 1.27))))
          (number "1" (effects (font (size 1.27 1.27))))
        )
        (pin passive line (at 5.08 0 180) (length 2.032)
          (name "~" (effects (font (size 1.27 1.27))))
          (number "2" (effects (font (size 1.27 1.27))))
        )
      )
    )
	(symbol "data-center-rdimm-ddr4-tester:C_100n_0402_12" (pin_numbers hide) (pin_names hide) (in_bom yes) (on_board yes)
      (property "Reference" "C" (at 20.32 -5.08 0)
        (effects (font (size 1.27 1.27) (thickness 0.15)) (justify left bottom))
      )
      (property "Value" "C_100n_0402_12" (at 20.32 -10.16 0)
        (effects (font (size 1.27 1.27) (thickness 0.15)) (justify left bottom) hide)
      )
      (property "Footprint" "data-center-rdimm-ddr4-tester-footprints:C_0402_1005Metric" (at 20.32 -12.7 0)
        (effects (font (size 1.27 1.27) (thickness 0.15)) (justify left bottom) hide)
      )
      (property "Datasheet" "https://search.murata.co.jp/Ceramy/image/img/A01X/G101/ENG/GRM155R61H104KE14-01.pdf" (at 20.32 -15.24 0)
        (effects (font (size 1.27 1.27) (thickness 0.15)) (justify left bottom) hide)
      )
      (property "MPN" "GRM155R61H104KE14D" (at 20.32 -17.78 0)
        (effects (font (size 1.27 1.27) (thickness 0.15)) (justify left bottom) hide)
      )
      (property "Manufacturer" "Murata" (at 20.32 -20.32 0)
        (effects (font (size 1.27 1.27) (thickness 0.15)) (justify left bottom) hide)
      )
      (property "License" "Apache-2.0" (at 20.32 -22.86 0)
        (effects (font (size 1.27 1.27) (thickness 0.15)) (justify left bottom) hide)
      )
      (property "Author" "Antmicro" (at 20.32 -25.4 0)
        (effects (font (size 1.27 1.27) (thickness 0.15)) (justify left bottom) hide)
      )
      (property "Val" "100n" (at 20.32 -7.62 0)
        (effects (font (size 1.27 1.27) (thickness 0.15)) (justify left bottom))
      )
      (property "Voltage" "50V" (at 20.32 -27.94 0)
        (effects (font (size 1.27 1.27)) (justify left bottom) hide)
      )
      (property "Dielectric" "X5R" (at 20.32 -30.48 0)
        (effects (font (size 1.27 1.27)) (justify left bottom) hide)
      )
      (property "ki_description" " " (at 0 0 0)
        (effects (font (size 1.27 1.27)) hide)
      )
      (symbol "C_100n_0402_12_0_1"
        (polyline
          (pts
            (xy 2.032 -1.524)
            (xy 2.032 1.524)
          )
          (stroke (width 0.3048) (type default))
          (fill (type none))
        )
        (polyline
          (pts
            (xy 3.048 -1.524)
            (xy 3.048 1.524)
          )
          (stroke (width 0.3302) (type default))
          (fill (type none))
        )
      )
      (symbol "C_100n_0402_12_1_1"
        (pin passive line (at 0 0 0) (length 2.032)
          (name "~" (effects (font (size 1.27 1.27))))
          (number "1" (effects (font (size 1.27 1.27))))
        )
        (pin passive line (at 5.08 0 180) (length 2.032)
          (name "~" (effects (font (size 1.27 1.27))))
          (number "2" (effects (font (size 1.27 1.27))))
        )
      )
    )
	(symbol "data-center-rdimm-ddr4-tester:C_100n_0402_13" (pin_numbers hide) (pin_names hide) (in_bom yes) (on_board yes)
      (property "Reference" "C" (at 20.32 -5.08 0)
        (effects (font (size 1.27 1.27) (thickness 0.15)) (justify left bottom))
      )
      (property "Value" "C_100n_0402_13" (at 20.32 -10.16 0)
        (effects (font (size 1.27 1.27) (thickness 0.15)) (justify left bottom) hide)
      )
      (property "Footprint" "data-center-rdimm-ddr4-tester-footprints:C_0402_1005Metric" (at 20.32 -12.7 0)
        (effects (font (size 1.27 1.27) (thickness 0.15)) (justify left bottom) hide)
      )
      (property "Datasheet" "https://search.murata.co.jp/Ceramy/image/img/A01X/G101/ENG/GRM155R61H104KE14-01.pdf" (at 20.32 -15.24 0)
        (effects (font (size 1.27 1.27) (thickness 0.15)) (justify left bottom) hide)
      )
      (property "MPN" "GRM155R61H104KE14D" (at 20.32 -17.78 0)
        (effects (font (size 1.27 1.27) (thickness 0.15)) (justify left bottom) hide)
      )
      (property "Manufacturer" "Murata" (at 20.32 -20.32 0)
        (effects (font (size 1.27 1.27) (thickness 0.15)) (justify left bottom) hide)
      )
      (property "License" "Apache-2.0" (at 20.32 -22.86 0)
        (effects (font (size 1.27 1.27) (thickness 0.15)) (justify left bottom) hide)
      )
      (property "Author" "Antmicro" (at 20.32 -25.4 0)
        (effects (font (size 1.27 1.27) (thickness 0.15)) (justify left bottom) hide)
      )
      (property "Val" "100n" (at 20.32 -7.62 0)
        (effects (font (size 1.27 1.27) (thickness 0.15)) (justify left bottom))
      )
      (property "Voltage" "50V" (at 20.32 -27.94 0)
        (effects (font (size 1.27 1.27)) (justify left bottom) hide)
      )
      (property "Dielectric" "X5R" (at 20.32 -30.48 0)
        (effects (font (size 1.27 1.27)) (justify left bottom) hide)
      )
      (property "ki_description" " " (at 0 0 0)
        (effects (font (size 1.27 1.27)) hide)
      )
      (symbol "C_100n_0402_13_0_1"
        (polyline
          (pts
            (xy 2.032 -1.524)
            (xy 2.032 1.524)
          )
          (stroke (width 0.3048) (type default))
          (fill (type none))
        )
        (polyline
          (pts
            (xy 3.048 -1.524)
            (xy 3.048 1.524)
          )
          (stroke (width 0.3302) (type default))
          (fill (type none))
        )
      )
      (symbol "C_100n_0402_13_1_1"
        (pin passive line (at 0 0 0) (length 2.032)
          (name "~" (effects (font (size 1.27 1.27))))
          (number "1" (effects (font (size 1.27 1.27))))
        )
        (pin passive line (at 5.08 0 180) (length 2.032)
          (name "~" (effects (font (size 1.27 1.27))))
          (number "2" (effects (font (size 1.27 1.27))))
        )
      )
    )
	(symbol "data-center-rdimm-ddr4-tester:C_100n_0402_14" (pin_numbers hide) (pin_names hide) (in_bom yes) (on_board yes)
      (property "Reference" "C" (at 20.32 -5.08 0)
        (effects (font (size 1.27 1.27) (thickness 0.15)) (justify left bottom))
      )
      (property "Value" "C_100n_0402_14" (at 20.32 -10.16 0)
        (effects (font (size 1.27 1.27) (thickness 0.15)) (justify left bottom) hide)
      )
      (property "Footprint" "data-center-rdimm-ddr4-tester-footprints:C_0402_1005Metric" (at 20.32 -12.7 0)
        (effects (font (size 1.27 1.27) (thickness 0.15)) (justify left bottom) hide)
      )
      (property "Datasheet" "https://search.murata.co.jp/Ceramy/image/img/A01X/G101/ENG/GRM155R61H104KE14-01.pdf" (at 20.32 -15.24 0)
        (effects (font (size 1.27 1.27) (thickness 0.15)) (justify left bottom) hide)
      )
      (property "MPN" "GRM155R61H104KE14D" (at 20.32 -17.78 0)
        (effects (font (size 1.27 1.27) (thickness 0.15)) (justify left bottom) hide)
      )
      (property "Manufacturer" "Murata" (at 20.32 -20.32 0)
        (effects (font (size 1.27 1.27) (thickness 0.15)) (justify left bottom) hide)
      )
      (property "License" "Apache-2.0" (at 20.32 -22.86 0)
        (effects (font (size 1.27 1.27) (thickness 0.15)) (justify left bottom) hide)
      )
      (property "Author" "Antmicro" (at 20.32 -25.4 0)
        (effects (font (size 1.27 1.27) (thickness 0.15)) (justify left bottom) hide)
      )
      (property "Val" "100n" (at 20.32 -7.62 0)
        (effects (font (size 1.27 1.27) (thickness 0.15)) (justify left bottom))
      )
      (property "Voltage" "50V" (at 20.32 -27.94 0)
        (effects (font (size 1.27 1.27)) (justify left bottom) hide)
      )
      (property "Dielectric" "X5R" (at 20.32 -30.48 0)
        (effects (font (size 1.27 1.27)) (justify left bottom) hide)
      )
      (property "ki_description" " " (at 0 0 0)
        (effects (font (size 1.27 1.27)) hide)
      )
      (symbol "C_100n_0402_14_0_1"
        (polyline
          (pts
            (xy 2.032 -1.524)
            (xy 2.032 1.524)
          )
          (stroke (width 0.3048) (type default))
          (fill (type none))
        )
        (polyline
          (pts
            (xy 3.048 -1.524)
            (xy 3.048 1.524)
          )
          (stroke (width 0.3302) (type default))
          (fill (type none))
        )
      )
      (symbol "C_100n_0402_14_1_1"
        (pin passive line (at 0 0 0) (length 2.032)
          (name "~" (effects (font (size 1.27 1.27))))
          (number "1" (effects (font (size 1.27 1.27))))
        )
        (pin passive line (at 5.08 0 180) (length 2.032)
          (name "~" (effects (font (size 1.27 1.27))))
          (number "2" (effects (font (size 1.27 1.27))))
        )
      )
    )
	(symbol "data-center-rdimm-ddr4-tester:C_100n_0402_15" (pin_numbers hide) (pin_names hide) (in_bom yes) (on_board yes)
      (property "Reference" "C" (at 20.32 -5.08 0)
        (effects (font (size 1.27 1.27) (thickness 0.15)) (justify left bottom))
      )
      (property "Value" "C_100n_0402_15" (at 20.32 -10.16 0)
        (effects (font (size 1.27 1.27) (thickness 0.15)) (justify left bottom) hide)
      )
      (property "Footprint" "data-center-rdimm-ddr4-tester-footprints:C_0402_1005Metric" (at 20.32 -12.7 0)
        (effects (font (size 1.27 1.27) (thickness 0.15)) (justify left bottom) hide)
      )
      (property "Datasheet" "https://search.murata.co.jp/Ceramy/image/img/A01X/G101/ENG/GRM155R61H104KE14-01.pdf" (at 20.32 -15.24 0)
        (effects (font (size 1.27 1.27) (thickness 0.15)) (justify left bottom) hide)
      )
      (property "MPN" "GRM155R61H104KE14D" (at 20.32 -17.78 0)
        (effects (font (size 1.27 1.27) (thickness 0.15)) (justify left bottom) hide)
      )
      (property "Manufacturer" "Murata" (at 20.32 -20.32 0)
        (effects (font (size 1.27 1.27) (thickness 0.15)) (justify left bottom) hide)
      )
      (property "License" "Apache-2.0" (at 20.32 -22.86 0)
        (effects (font (size 1.27 1.27) (thickness 0.15)) (justify left bottom) hide)
      )
      (property "Author" "Antmicro" (at 20.32 -25.4 0)
        (effects (font (size 1.27 1.27) (thickness 0.15)) (justify left bottom) hide)
      )
      (property "Val" "100n" (at 20.32 -7.62 0)
        (effects (font (size 1.27 1.27) (thickness 0.15)) (justify left bottom))
      )
      (property "Voltage" "50V" (at 20.32 -27.94 0)
        (effects (font (size 1.27 1.27)) (justify left bottom) hide)
      )
      (property "Dielectric" "X5R" (at 20.32 -30.48 0)
        (effects (font (size 1.27 1.27)) (justify left bottom) hide)
      )
      (property "ki_description" " " (at 0 0 0)
        (effects (font (size 1.27 1.27)) hide)
      )
      (symbol "C_100n_0402_15_0_1"
        (polyline
          (pts
            (xy 2.032 -1.524)
            (xy 2.032 1.524)
          )
          (stroke (width 0.3048) (type default))
          (fill (type none))
        )
        (polyline
          (pts
            (xy 3.048 -1.524)
            (xy 3.048 1.524)
          )
          (stroke (width 0.3302) (type default))
          (fill (type none))
        )
      )
      (symbol "C_100n_0402_15_1_1"
        (pin passive line (at 0 0 0) (length 2.032)
          (name "~" (effects (font (size 1.27 1.27))))
          (number "1" (effects (font (size 1.27 1.27))))
        )
        (pin passive line (at 5.08 0 180) (length 2.032)
          (name "~" (effects (font (size 1.27 1.27))))
          (number "2" (effects (font (size 1.27 1.27))))
        )
      )
    )
	(symbol "data-center-rdimm-ddr4-tester:C_100n_0402_16" (pin_numbers hide) (pin_names hide) (in_bom yes) (on_board yes)
      (property "Reference" "C" (at 20.32 -5.08 0)
        (effects (font (size 1.27 1.27) (thickness 0.15)) (justify left bottom))
      )
      (property "Value" "C_100n_0402_16" (at 20.32 -10.16 0)
        (effects (font (size 1.27 1.27) (thickness 0.15)) (justify left bottom) hide)
      )
      (property "Footprint" "data-center-rdimm-ddr4-tester-footprints:C_0402_1005Metric" (at 20.32 -12.7 0)
        (effects (font (size 1.27 1.27) (thickness 0.15)) (justify left bottom) hide)
      )
      (property "Datasheet" "https://search.murata.co.jp/Ceramy/image/img/A01X/G101/ENG/GRM155R61H104KE14-01.pdf" (at 20.32 -15.24 0)
        (effects (font (size 1.27 1.27) (thickness 0.15)) (justify left bottom) hide)
      )
      (property "MPN" "GRM155R61H104KE14D" (at 20.32 -17.78 0)
        (effects (font (size 1.27 1.27) (thickness 0.15)) (justify left bottom) hide)
      )
      (property "Manufacturer" "Murata" (at 20.32 -20.32 0)
        (effects (font (size 1.27 1.27) (thickness 0.15)) (justify left bottom) hide)
      )
      (property "License" "Apache-2.0" (at 20.32 -22.86 0)
        (effects (font (size 1.27 1.27) (thickness 0.15)) (justify left bottom) hide)
      )
      (property "Author" "Antmicro" (at 20.32 -25.4 0)
        (effects (font (size 1.27 1.27) (thickness 0.15)) (justify left bottom) hide)
      )
      (property "Val" "100n" (at 20.32 -7.62 0)
        (effects (font (size 1.27 1.27) (thickness 0.15)) (justify left bottom))
      )
      (property "Voltage" "50V" (at 20.32 -27.94 0)
        (effects (font (size 1.27 1.27)) (justify left bottom) hide)
      )
      (property "Dielectric" "X5R" (at 20.32 -30.48 0)
        (effects (font (size 1.27 1.27)) (justify left bottom) hide)
      )
      (property "ki_description" " " (at 0 0 0)
        (effects (font (size 1.27 1.27)) hide)
      )
      (symbol "C_100n_0402_16_0_1"
        (polyline
          (pts
            (xy 2.032 -1.524)
            (xy 2.032 1.524)
          )
          (stroke (width 0.3048) (type default))
          (fill (type none))
        )
        (polyline
          (pts
            (xy 3.048 -1.524)
            (xy 3.048 1.524)
          )
          (stroke (width 0.3302) (type default))
          (fill (type none))
        )
      )
      (symbol "C_100n_0402_16_1_1"
        (pin passive line (at 0 0 0) (length 2.032)
          (name "~" (effects (font (size 1.27 1.27))))
          (number "1" (effects (font (size 1.27 1.27))))
        )
        (pin passive line (at 5.08 0 180) (length 2.032)
          (name "~" (effects (font (size 1.27 1.27))))
          (number "2" (effects (font (size 1.27 1.27))))
        )
      )
    )
	(symbol "data-center-rdimm-ddr4-tester:C_100n_0402_17" (pin_numbers hide) (pin_names hide) (in_bom yes) (on_board yes)
      (property "Reference" "C" (at 20.32 -5.08 0)
        (effects (font (size 1.27 1.27) (thickness 0.15)) (justify left bottom))
      )
      (property "Value" "C_100n_0402_17" (at 20.32 -10.16 0)
        (effects (font (size 1.27 1.27) (thickness 0.15)) (justify left bottom) hide)
      )
      (property "Footprint" "data-center-rdimm-ddr4-tester-footprints:C_0402_1005Metric" (at 20.32 -12.7 0)
        (effects (font (size 1.27 1.27) (thickness 0.15)) (justify left bottom) hide)
      )
      (property "Datasheet" "https://search.murata.co.jp/Ceramy/image/img/A01X/G101/ENG/GRM155R61H104KE14-01.pdf" (at 20.32 -15.24 0)
        (effects (font (size 1.27 1.27) (thickness 0.15)) (justify left bottom) hide)
      )
      (property "MPN" "GRM155R61H104KE14D" (at 20.32 -17.78 0)
        (effects (font (size 1.27 1.27) (thickness 0.15)) (justify left bottom) hide)
      )
      (property "Manufacturer" "Murata" (at 20.32 -20.32 0)
        (effects (font (size 1.27 1.27) (thickness 0.15)) (justify left bottom) hide)
      )
      (property "License" "Apache-2.0" (at 20.32 -22.86 0)
        (effects (font (size 1.27 1.27) (thickness 0.15)) (justify left bottom) hide)
      )
      (property "Author" "Antmicro" (at 20.32 -25.4 0)
        (effects (font (size 1.27 1.27) (thickness 0.15)) (justify left bottom) hide)
      )
      (property "Val" "100n" (at 20.32 -7.62 0)
        (effects (font (size 1.27 1.27) (thickness 0.15)) (justify left bottom))
      )
      (property "Voltage" "50V" (at 20.32 -27.94 0)
        (effects (font (size 1.27 1.27)) (justify left bottom) hide)
      )
      (property "Dielectric" "X5R" (at 20.32 -30.48 0)
        (effects (font (size 1.27 1.27)) (justify left bottom) hide)
      )
      (property "ki_description" " " (at 0 0 0)
        (effects (font (size 1.27 1.27)) hide)
      )
      (symbol "C_100n_0402_17_0_1"
        (polyline
          (pts
            (xy 2.032 -1.524)
            (xy 2.032 1.524)
          )
          (stroke (width 0.3048) (type default))
          (fill (type none))
        )
        (polyline
          (pts
            (xy 3.048 -1.524)
            (xy 3.048 1.524)
          )
          (stroke (width 0.3302) (type default))
          (fill (type none))
        )
      )
      (symbol "C_100n_0402_17_1_1"
        (pin passive line (at 0 0 0) (length 2.032)
          (name "~" (effects (font (size 1.27 1.27))))
          (number "1" (effects (font (size 1.27 1.27))))
        )
        (pin passive line (at 5.08 0 180) (length 2.032)
          (name "~" (effects (font (size 1.27 1.27))))
          (number "2" (effects (font (size 1.27 1.27))))
        )
      )
    )
	(symbol "data-center-rdimm-ddr4-tester:C_100n_0402_18" (pin_numbers hide) (pin_names hide) (in_bom yes) (on_board yes)
      (property "Reference" "C" (at 20.32 -5.08 0)
        (effects (font (size 1.27 1.27) (thickness 0.15)) (justify left bottom))
      )
      (property "Value" "C_100n_0402_18" (at 20.32 -10.16 0)
        (effects (font (size 1.27 1.27) (thickness 0.15)) (justify left bottom) hide)
      )
      (property "Footprint" "data-center-rdimm-ddr4-tester-footprints:C_0402_1005Metric" (at 20.32 -12.7 0)
        (effects (font (size 1.27 1.27) (thickness 0.15)) (justify left bottom) hide)
      )
      (property "Datasheet" "https://search.murata.co.jp/Ceramy/image/img/A01X/G101/ENG/GRM155R61H104KE14-01.pdf" (at 20.32 -15.24 0)
        (effects (font (size 1.27 1.27) (thickness 0.15)) (justify left bottom) hide)
      )
      (property "MPN" "GRM155R61H104KE14D" (at 20.32 -17.78 0)
        (effects (font (size 1.27 1.27) (thickness 0.15)) (justify left bottom) hide)
      )
      (property "Manufacturer" "Murata" (at 20.32 -20.32 0)
        (effects (font (size 1.27 1.27) (thickness 0.15)) (justify left bottom) hide)
      )
      (property "License" "Apache-2.0" (at 20.32 -22.86 0)
        (effects (font (size 1.27 1.27) (thickness 0.15)) (justify left bottom) hide)
      )
      (property "Author" "Antmicro" (at 20.32 -25.4 0)
        (effects (font (size 1.27 1.27) (thickness 0.15)) (justify left bottom) hide)
      )
      (property "Val" "100n" (at 20.32 -7.62 0)
        (effects (font (size 1.27 1.27) (thickness 0.15)) (justify left bottom))
      )
      (property "Voltage" "50V" (at 20.32 -27.94 0)
        (effects (font (size 1.27 1.27)) (justify left bottom) hide)
      )
      (property "Dielectric" "X5R" (at 20.32 -30.48 0)
        (effects (font (size 1.27 1.27)) (justify left bottom) hide)
      )
      (property "ki_description" " " (at 0 0 0)
        (effects (font (size 1.27 1.27)) hide)
      )
      (symbol "C_100n_0402_18_0_1"
        (polyline
          (pts
            (xy 2.032 -1.524)
            (xy 2.032 1.524)
          )
          (stroke (width 0.3048) (type default))
          (fill (type none))
        )
        (polyline
          (pts
            (xy 3.048 -1.524)
            (xy 3.048 1.524)
          )
          (stroke (width 0.3302) (type default))
          (fill (type none))
        )
      )
      (symbol "C_100n_0402_18_1_1"
        (pin passive line (at 0 0 0) (length 2.032)
          (name "~" (effects (font (size 1.27 1.27))))
          (number "1" (effects (font (size 1.27 1.27))))
        )
        (pin passive line (at 5.08 0 180) (length 2.032)
          (name "~" (effects (font (size 1.27 1.27))))
          (number "2" (effects (font (size 1.27 1.27))))
        )
      )
    )
	(symbol "data-center-rdimm-ddr4-tester:C_100n_0402_19" (pin_numbers hide) (pin_names hide) (in_bom yes) (on_board yes)
      (property "Reference" "C" (at 20.32 -5.08 0)
        (effects (font (size 1.27 1.27) (thickness 0.15)) (justify left bottom))
      )
      (property "Value" "C_100n_0402_19" (at 20.32 -10.16 0)
        (effects (font (size 1.27 1.27) (thickness 0.15)) (justify left bottom) hide)
      )
      (property "Footprint" "data-center-rdimm-ddr4-tester-footprints:C_0402_1005Metric" (at 20.32 -12.7 0)
        (effects (font (size 1.27 1.27) (thickness 0.15)) (justify left bottom) hide)
      )
      (property "Datasheet" "https://search.murata.co.jp/Ceramy/image/img/A01X/G101/ENG/GRM155R61H104KE14-01.pdf" (at 20.32 -15.24 0)
        (effects (font (size 1.27 1.27) (thickness 0.15)) (justify left bottom) hide)
      )
      (property "MPN" "GRM155R61H104KE14D" (at 20.32 -17.78 0)
        (effects (font (size 1.27 1.27) (thickness 0.15)) (justify left bottom) hide)
      )
      (property "Manufacturer" "Murata" (at 20.32 -20.32 0)
        (effects (font (size 1.27 1.27) (thickness 0.15)) (justify left bottom) hide)
      )
      (property "License" "Apache-2.0" (at 20.32 -22.86 0)
        (effects (font (size 1.27 1.27) (thickness 0.15)) (justify left bottom) hide)
      )
      (property "Author" "Antmicro" (at 20.32 -25.4 0)
        (effects (font (size 1.27 1.27) (thickness 0.15)) (justify left bottom) hide)
      )
      (property "Val" "100n" (at 20.32 -7.62 0)
        (effects (font (size 1.27 1.27) (thickness 0.15)) (justify left bottom))
      )
      (property "Voltage" "50V" (at 20.32 -27.94 0)
        (effects (font (size 1.27 1.27)) (justify left bottom) hide)
      )
      (property "Dielectric" "X5R" (at 20.32 -30.48 0)
        (effects (font (size 1.27 1.27)) (justify left bottom) hide)
      )
      (property "ki_description" " " (at 0 0 0)
        (effects (font (size 1.27 1.27)) hide)
      )
      (symbol "C_100n_0402_19_0_1"
        (polyline
          (pts
            (xy 2.032 -1.524)
            (xy 2.032 1.524)
          )
          (stroke (width 0.3048) (type default))
          (fill (type none))
        )
        (polyline
          (pts
            (xy 3.048 -1.524)
            (xy 3.048 1.524)
          )
          (stroke (width 0.3302) (type default))
          (fill (type none))
        )
      )
      (symbol "C_100n_0402_19_1_1"
        (pin passive line (at 0 0 0) (length 2.032)
          (name "~" (effects (font (size 1.27 1.27))))
          (number "1" (effects (font (size 1.27 1.27))))
        )
        (pin passive line (at 5.08 0 180) (length 2.032)
          (name "~" (effects (font (size 1.27 1.27))))
          (number "2" (effects (font (size 1.27 1.27))))
        )
      )
    )
	(symbol "data-center-rdimm-ddr4-tester:C_100n_0402_20" (pin_numbers hide) (pin_names hide) (in_bom yes) (on_board yes)
      (property "Reference" "C" (at 20.32 -5.08 0)
        (effects (font (size 1.27 1.27) (thickness 0.15)) (justify left bottom))
      )
      (property "Value" "C_100n_0402_20" (at 20.32 -10.16 0)
        (effects (font (size 1.27 1.27) (thickness 0.15)) (justify left bottom) hide)
      )
      (property "Footprint" "data-center-rdimm-ddr4-tester-footprints:C_0402_1005Metric" (at 20.32 -12.7 0)
        (effects (font (size 1.27 1.27) (thickness 0.15)) (justify left bottom) hide)
      )
      (property "Datasheet" "https://search.murata.co.jp/Ceramy/image/img/A01X/G101/ENG/GRM155R61H104KE14-01.pdf" (at 20.32 -15.24 0)
        (effects (font (size 1.27 1.27) (thickness 0.15)) (justify left bottom) hide)
      )
      (property "MPN" "GRM155R61H104KE14D" (at 20.32 -17.78 0)
        (effects (font (size 1.27 1.27) (thickness 0.15)) (justify left bottom) hide)
      )
      (property "Manufacturer" "Murata" (at 20.32 -20.32 0)
        (effects (font (size 1.27 1.27) (thickness 0.15)) (justify left bottom) hide)
      )
      (property "License" "Apache-2.0" (at 20.32 -22.86 0)
        (effects (font (size 1.27 1.27) (thickness 0.15)) (justify left bottom) hide)
      )
      (property "Author" "Antmicro" (at 20.32 -25.4 0)
        (effects (font (size 1.27 1.27) (thickness 0.15)) (justify left bottom) hide)
      )
      (property "Val" "100n" (at 20.32 -7.62 0)
        (effects (font (size 1.27 1.27) (thickness 0.15)) (justify left bottom))
      )
      (property "Voltage" "50V" (at 20.32 -27.94 0)
        (effects (font (size 1.27 1.27)) (justify left bottom) hide)
      )
      (property "Dielectric" "X5R" (at 20.32 -30.48 0)
        (effects (font (size 1.27 1.27)) (justify left bottom) hide)
      )
      (property "ki_description" " " (at 0 0 0)
        (effects (font (size 1.27 1.27)) hide)
      )
      (symbol "C_100n_0402_20_0_1"
        (polyline
          (pts
            (xy 2.032 -1.524)
            (xy 2.032 1.524)
          )
          (stroke (width 0.3048) (type default))
          (fill (type none))
        )
        (polyline
          (pts
            (xy 3.048 -1.524)
            (xy 3.048 1.524)
          )
          (stroke (width 0.3302) (type default))
          (fill (type none))
        )
      )
      (symbol "C_100n_0402_20_1_1"
        (pin passive line (at 0 0 0) (length 2.032)
          (name "~" (effects (font (size 1.27 1.27))))
          (number "1" (effects (font (size 1.27 1.27))))
        )
        (pin passive line (at 5.08 0 180) (length 2.032)
          (name "~" (effects (font (size 1.27 1.27))))
          (number "2" (effects (font (size 1.27 1.27))))
        )
      )
    )
	(symbol "data-center-rdimm-ddr4-tester:C_100n_0402_21" (pin_numbers hide) (pin_names hide) (in_bom yes) (on_board yes)
      (property "Reference" "C" (at 20.32 -5.08 0)
        (effects (font (size 1.27 1.27) (thickness 0.15)) (justify left bottom))
      )
      (property "Value" "C_100n_0402_21" (at 20.32 -10.16 0)
        (effects (font (size 1.27 1.27) (thickness 0.15)) (justify left bottom) hide)
      )
      (property "Footprint" "data-center-rdimm-ddr4-tester-footprints:C_0402_1005Metric" (at 20.32 -12.7 0)
        (effects (font (size 1.27 1.27) (thickness 0.15)) (justify left bottom) hide)
      )
      (property "Datasheet" "https://search.murata.co.jp/Ceramy/image/img/A01X/G101/ENG/GRM155R61H104KE14-01.pdf" (at 20.32 -15.24 0)
        (effects (font (size 1.27 1.27) (thickness 0.15)) (justify left bottom) hide)
      )
      (property "MPN" "GRM155R61H104KE14D" (at 20.32 -17.78 0)
        (effects (font (size 1.27 1.27) (thickness 0.15)) (justify left bottom) hide)
      )
      (property "Manufacturer" "Murata" (at 20.32 -20.32 0)
        (effects (font (size 1.27 1.27) (thickness 0.15)) (justify left bottom) hide)
      )
      (property "License" "Apache-2.0" (at 20.32 -22.86 0)
        (effects (font (size 1.27 1.27) (thickness 0.15)) (justify left bottom) hide)
      )
      (property "Author" "Antmicro" (at 20.32 -25.4 0)
        (effects (font (size 1.27 1.27) (thickness 0.15)) (justify left bottom) hide)
      )
      (property "Val" "100n" (at 20.32 -7.62 0)
        (effects (font (size 1.27 1.27) (thickness 0.15)) (justify left bottom))
      )
      (property "Voltage" "50V" (at 20.32 -27.94 0)
        (effects (font (size 1.27 1.27)) (justify left bottom) hide)
      )
      (property "Dielectric" "X5R" (at 20.32 -30.48 0)
        (effects (font (size 1.27 1.27)) (justify left bottom) hide)
      )
      (property "ki_description" " " (at 0 0 0)
        (effects (font (size 1.27 1.27)) hide)
      )
      (symbol "C_100n_0402_21_0_1"
        (polyline
          (pts
            (xy 2.032 -1.524)
            (xy 2.032 1.524)
          )
          (stroke (width 0.3048) (type default))
          (fill (type none))
        )
        (polyline
          (pts
            (xy 3.048 -1.524)
            (xy 3.048 1.524)
          )
          (stroke (width 0.3302) (type default))
          (fill (type none))
        )
      )
      (symbol "C_100n_0402_21_1_1"
        (pin passive line (at 0 0 0) (length 2.032)
          (name "~" (effects (font (size 1.27 1.27))))
          (number "1" (effects (font (size 1.27 1.27))))
        )
        (pin passive line (at 5.08 0 180) (length 2.032)
          (name "~" (effects (font (size 1.27 1.27))))
          (number "2" (effects (font (size 1.27 1.27))))
        )
      )
    )
	(symbol "data-center-rdimm-ddr4-tester:C_100n_0402_22" (pin_numbers hide) (pin_names hide) (in_bom yes) (on_board yes)
      (property "Reference" "C" (at 20.32 -5.08 0)
        (effects (font (size 1.27 1.27) (thickness 0.15)) (justify left bottom))
      )
      (property "Value" "C_100n_0402_22" (at 20.32 -10.16 0)
        (effects (font (size 1.27 1.27) (thickness 0.15)) (justify left bottom) hide)
      )
      (property "Footprint" "data-center-rdimm-ddr4-tester-footprints:C_0402_1005Metric" (at 20.32 -12.7 0)
        (effects (font (size 1.27 1.27) (thickness 0.15)) (justify left bottom) hide)
      )
      (property "Datasheet" "https://search.murata.co.jp/Ceramy/image/img/A01X/G101/ENG/GRM155R61H104KE14-01.pdf" (at 20.32 -15.24 0)
        (effects (font (size 1.27 1.27) (thickness 0.15)) (justify left bottom) hide)
      )
      (property "MPN" "GRM155R61H104KE14D" (at 20.32 -17.78 0)
        (effects (font (size 1.27 1.27) (thickness 0.15)) (justify left bottom) hide)
      )
      (property "Manufacturer" "Murata" (at 20.32 -20.32 0)
        (effects (font (size 1.27 1.27) (thickness 0.15)) (justify left bottom) hide)
      )
      (property "License" "Apache-2.0" (at 20.32 -22.86 0)
        (effects (font (size 1.27 1.27) (thickness 0.15)) (justify left bottom) hide)
      )
      (property "Author" "Antmicro" (at 20.32 -25.4 0)
        (effects (font (size 1.27 1.27) (thickness 0.15)) (justify left bottom) hide)
      )
      (property "Val" "100n" (at 20.32 -7.62 0)
        (effects (font (size 1.27 1.27) (thickness 0.15)) (justify left bottom))
      )
      (property "Voltage" "50V" (at 20.32 -27.94 0)
        (effects (font (size 1.27 1.27)) (justify left bottom) hide)
      )
      (property "Dielectric" "X5R" (at 20.32 -30.48 0)
        (effects (font (size 1.27 1.27)) (justify left bottom) hide)
      )
      (property "ki_description" " " (at 0 0 0)
        (effects (font (size 1.27 1.27)) hide)
      )
      (symbol "C_100n_0402_22_0_1"
        (polyline
          (pts
            (xy 2.032 -1.524)
            (xy 2.032 1.524)
          )
          (stroke (width 0.3048) (type default))
          (fill (type none))
        )
        (polyline
          (pts
            (xy 3.048 -1.524)
            (xy 3.048 1.524)
          )
          (stroke (width 0.3302) (type default))
          (fill (type none))
        )
      )
      (symbol "C_100n_0402_22_1_1"
        (pin passive line (at 0 0 0) (length 2.032)
          (name "~" (effects (font (size 1.27 1.27))))
          (number "1" (effects (font (size 1.27 1.27))))
        )
        (pin passive line (at 5.08 0 180) (length 2.032)
          (name "~" (effects (font (size 1.27 1.27))))
          (number "2" (effects (font (size 1.27 1.27))))
        )
      )
    )
	(symbol "data-center-rdimm-ddr4-tester:C_100n_0402_23" (pin_numbers hide) (pin_names hide) (in_bom yes) (on_board yes)
      (property "Reference" "C" (at 20.32 -5.08 0)
        (effects (font (size 1.27 1.27) (thickness 0.15)) (justify left bottom))
      )
      (property "Value" "C_100n_0402_23" (at 20.32 -10.16 0)
        (effects (font (size 1.27 1.27) (thickness 0.15)) (justify left bottom) hide)
      )
      (property "Footprint" "data-center-rdimm-ddr4-tester-footprints:C_0402_1005Metric" (at 20.32 -12.7 0)
        (effects (font (size 1.27 1.27) (thickness 0.15)) (justify left bottom) hide)
      )
      (property "Datasheet" "https://search.murata.co.jp/Ceramy/image/img/A01X/G101/ENG/GRM155R61H104KE14-01.pdf" (at 20.32 -15.24 0)
        (effects (font (size 1.27 1.27) (thickness 0.15)) (justify left bottom) hide)
      )
      (property "MPN" "GRM155R61H104KE14D" (at 20.32 -17.78 0)
        (effects (font (size 1.27 1.27) (thickness 0.15)) (justify left bottom) hide)
      )
      (property "Manufacturer" "Murata" (at 20.32 -20.32 0)
        (effects (font (size 1.27 1.27) (thickness 0.15)) (justify left bottom) hide)
      )
      (property "License" "Apache-2.0" (at 20.32 -22.86 0)
        (effects (font (size 1.27 1.27) (thickness 0.15)) (justify left bottom) hide)
      )
      (property "Author" "Antmicro" (at 20.32 -25.4 0)
        (effects (font (size 1.27 1.27) (thickness 0.15)) (justify left bottom) hide)
      )
      (property "Val" "100n" (at 20.32 -7.62 0)
        (effects (font (size 1.27 1.27) (thickness 0.15)) (justify left bottom))
      )
      (property "Voltage" "50V" (at 20.32 -27.94 0)
        (effects (font (size 1.27 1.27)) (justify left bottom) hide)
      )
      (property "Dielectric" "X5R" (at 20.32 -30.48 0)
        (effects (font (size 1.27 1.27)) (justify left bottom) hide)
      )
      (property "ki_description" " " (at 0 0 0)
        (effects (font (size 1.27 1.27)) hide)
      )
      (symbol "C_100n_0402_23_0_1"
        (polyline
          (pts
            (xy 2.032 -1.524)
            (xy 2.032 1.524)
          )
          (stroke (width 0.3048) (type default))
          (fill (type none))
        )
        (polyline
          (pts
            (xy 3.048 -1.524)
            (xy 3.048 1.524)
          )
          (stroke (width 0.3302) (type default))
          (fill (type none))
        )
      )
      (symbol "C_100n_0402_23_1_1"
        (pin passive line (at 0 0 0) (length 2.032)
          (name "~" (effects (font (size 1.27 1.27))))
          (number "1" (effects (font (size 1.27 1.27))))
        )
        (pin passive line (at 5.08 0 180) (length 2.032)
          (name "~" (effects (font (size 1.27 1.27))))
          (number "2" (effects (font (size 1.27 1.27))))
        )
      )
    )
	(symbol "data-center-rdimm-ddr4-tester:C_100n_0402_24" (pin_numbers hide) (pin_names hide) (in_bom yes) (on_board yes)
      (property "Reference" "C" (at 20.32 -5.08 0)
        (effects (font (size 1.27 1.27) (thickness 0.15)) (justify left bottom))
      )
      (property "Value" "C_100n_0402_24" (at 20.32 -10.16 0)
        (effects (font (size 1.27 1.27) (thickness 0.15)) (justify left bottom) hide)
      )
      (property "Footprint" "data-center-rdimm-ddr4-tester-footprints:C_0402_1005Metric" (at 20.32 -12.7 0)
        (effects (font (size 1.27 1.27) (thickness 0.15)) (justify left bottom) hide)
      )
      (property "Datasheet" "https://search.murata.co.jp/Ceramy/image/img/A01X/G101/ENG/GRM155R61H104KE14-01.pdf" (at 20.32 -15.24 0)
        (effects (font (size 1.27 1.27) (thickness 0.15)) (justify left bottom) hide)
      )
      (property "MPN" "GRM155R61H104KE14D" (at 20.32 -17.78 0)
        (effects (font (size 1.27 1.27) (thickness 0.15)) (justify left bottom) hide)
      )
      (property "Manufacturer" "Murata" (at 20.32 -20.32 0)
        (effects (font (size 1.27 1.27) (thickness 0.15)) (justify left bottom) hide)
      )
      (property "License" "Apache-2.0" (at 20.32 -22.86 0)
        (effects (font (size 1.27 1.27) (thickness 0.15)) (justify left bottom) hide)
      )
      (property "Author" "Antmicro" (at 20.32 -25.4 0)
        (effects (font (size 1.27 1.27) (thickness 0.15)) (justify left bottom) hide)
      )
      (property "Val" "100n" (at 20.32 -7.62 0)
        (effects (font (size 1.27 1.27) (thickness 0.15)) (justify left bottom))
      )
      (property "Voltage" "50V" (at 20.32 -27.94 0)
        (effects (font (size 1.27 1.27)) (justify left bottom) hide)
      )
      (property "Dielectric" "X5R" (at 20.32 -30.48 0)
        (effects (font (size 1.27 1.27)) (justify left bottom) hide)
      )
      (property "ki_description" " " (at 0 0 0)
        (effects (font (size 1.27 1.27)) hide)
      )
      (symbol "C_100n_0402_24_0_1"
        (polyline
          (pts
            (xy 2.032 -1.524)
            (xy 2.032 1.524)
          )
          (stroke (width 0.3048) (type default))
          (fill (type none))
        )
        (polyline
          (pts
            (xy 3.048 -1.524)
            (xy 3.048 1.524)
          )
          (stroke (width 0.3302) (type default))
          (fill (type none))
        )
      )
      (symbol "C_100n_0402_24_1_1"
        (pin passive line (at 0 0 0) (length 2.032)
          (name "~" (effects (font (size 1.27 1.27))))
          (number "1" (effects (font (size 1.27 1.27))))
        )
        (pin passive line (at 5.08 0 180) (length 2.032)
          (name "~" (effects (font (size 1.27 1.27))))
          (number "2" (effects (font (size 1.27 1.27))))
        )
      )
    )
	(symbol "data-center-rdimm-ddr4-tester:C_100n_0402_25" (pin_numbers hide) (pin_names hide) (in_bom yes) (on_board yes)
      (property "Reference" "C" (at 20.32 -5.08 0)
        (effects (font (size 1.27 1.27) (thickness 0.15)) (justify left bottom))
      )
      (property "Value" "C_100n_0402_25" (at 20.32 -10.16 0)
        (effects (font (size 1.27 1.27) (thickness 0.15)) (justify left bottom) hide)
      )
      (property "Footprint" "data-center-rdimm-ddr4-tester-footprints:C_0402_1005Metric" (at 20.32 -12.7 0)
        (effects (font (size 1.27 1.27) (thickness 0.15)) (justify left bottom) hide)
      )
      (property "Datasheet" "https://search.murata.co.jp/Ceramy/image/img/A01X/G101/ENG/GRM155R61H104KE14-01.pdf" (at 20.32 -15.24 0)
        (effects (font (size 1.27 1.27) (thickness 0.15)) (justify left bottom) hide)
      )
      (property "MPN" "GRM155R61H104KE14D" (at 20.32 -17.78 0)
        (effects (font (size 1.27 1.27) (thickness 0.15)) (justify left bottom) hide)
      )
      (property "Manufacturer" "Murata" (at 20.32 -20.32 0)
        (effects (font (size 1.27 1.27) (thickness 0.15)) (justify left bottom) hide)
      )
      (property "License" "Apache-2.0" (at 20.32 -22.86 0)
        (effects (font (size 1.27 1.27) (thickness 0.15)) (justify left bottom) hide)
      )
      (property "Author" "Antmicro" (at 20.32 -25.4 0)
        (effects (font (size 1.27 1.27) (thickness 0.15)) (justify left bottom) hide)
      )
      (property "Val" "100n" (at 20.32 -7.62 0)
        (effects (font (size 1.27 1.27) (thickness 0.15)) (justify left bottom))
      )
      (property "Voltage" "50V" (at 20.32 -27.94 0)
        (effects (font (size 1.27 1.27)) (justify left bottom) hide)
      )
      (property "Dielectric" "X5R" (at 20.32 -30.48 0)
        (effects (font (size 1.27 1.27)) (justify left bottom) hide)
      )
      (property "ki_description" " " (at 0 0 0)
        (effects (font (size 1.27 1.27)) hide)
      )
      (symbol "C_100n_0402_25_0_1"
        (polyline
          (pts
            (xy 2.032 -1.524)
            (xy 2.032 1.524)
          )
          (stroke (width 0.3048) (type default))
          (fill (type none))
        )
        (polyline
          (pts
            (xy 3.048 -1.524)
            (xy 3.048 1.524)
          )
          (stroke (width 0.3302) (type default))
          (fill (type none))
        )
      )
      (symbol "C_100n_0402_25_1_1"
        (pin passive line (at 0 0 0) (length 2.032)
          (name "~" (effects (font (size 1.27 1.27))))
          (number "1" (effects (font (size 1.27 1.27))))
        )
        (pin passive line (at 5.08 0 180) (length 2.032)
          (name "~" (effects (font (size 1.27 1.27))))
          (number "2" (effects (font (size 1.27 1.27))))
        )
      )
    )
	(symbol "data-center-rdimm-ddr4-tester:C_100n_0402_26" (pin_numbers hide) (pin_names hide) (in_bom yes) (on_board yes)
      (property "Reference" "C" (at 20.32 -5.08 0)
        (effects (font (size 1.27 1.27) (thickness 0.15)) (justify left bottom))
      )
      (property "Value" "C_100n_0402_26" (at 20.32 -10.16 0)
        (effects (font (size 1.27 1.27) (thickness 0.15)) (justify left bottom) hide)
      )
      (property "Footprint" "data-center-rdimm-ddr4-tester-footprints:C_0402_1005Metric" (at 20.32 -12.7 0)
        (effects (font (size 1.27 1.27) (thickness 0.15)) (justify left bottom) hide)
      )
      (property "Datasheet" "https://search.murata.co.jp/Ceramy/image/img/A01X/G101/ENG/GRM155R61H104KE14-01.pdf" (at 20.32 -15.24 0)
        (effects (font (size 1.27 1.27) (thickness 0.15)) (justify left bottom) hide)
      )
      (property "MPN" "GRM155R61H104KE14D" (at 20.32 -17.78 0)
        (effects (font (size 1.27 1.27) (thickness 0.15)) (justify left bottom) hide)
      )
      (property "Manufacturer" "Murata" (at 20.32 -20.32 0)
        (effects (font (size 1.27 1.27) (thickness 0.15)) (justify left bottom) hide)
      )
      (property "License" "Apache-2.0" (at 20.32 -22.86 0)
        (effects (font (size 1.27 1.27) (thickness 0.15)) (justify left bottom) hide)
      )
      (property "Author" "Antmicro" (at 20.32 -25.4 0)
        (effects (font (size 1.27 1.27) (thickness 0.15)) (justify left bottom) hide)
      )
      (property "Val" "100n" (at 20.32 -7.62 0)
        (effects (font (size 1.27 1.27) (thickness 0.15)) (justify left bottom))
      )
      (property "Voltage" "50V" (at 20.32 -27.94 0)
        (effects (font (size 1.27 1.27)) (justify left bottom) hide)
      )
      (property "Dielectric" "X5R" (at 20.32 -30.48 0)
        (effects (font (size 1.27 1.27)) (justify left bottom) hide)
      )
      (property "ki_description" " " (at 0 0 0)
        (effects (font (size 1.27 1.27)) hide)
      )
      (symbol "C_100n_0402_26_0_1"
        (polyline
          (pts
            (xy 2.032 -1.524)
            (xy 2.032 1.524)
          )
          (stroke (width 0.3048) (type default))
          (fill (type none))
        )
        (polyline
          (pts
            (xy 3.048 -1.524)
            (xy 3.048 1.524)
          )
          (stroke (width 0.3302) (type default))
          (fill (type none))
        )
      )
      (symbol "C_100n_0402_26_1_1"
        (pin passive line (at 0 0 0) (length 2.032)
          (name "~" (effects (font (size 1.27 1.27))))
          (number "1" (effects (font (size 1.27 1.27))))
        )
        (pin passive line (at 5.08 0 180) (length 2.032)
          (name "~" (effects (font (size 1.27 1.27))))
          (number "2" (effects (font (size 1.27 1.27))))
        )
      )
    )
	(symbol "data-center-rdimm-ddr4-tester:C_100n_0402_27" (pin_numbers hide) (pin_names hide) (in_bom yes) (on_board yes)
      (property "Reference" "C" (at 20.32 -5.08 0)
        (effects (font (size 1.27 1.27) (thickness 0.15)) (justify left bottom))
      )
      (property "Value" "C_100n_0402_27" (at 20.32 -10.16 0)
        (effects (font (size 1.27 1.27) (thickness 0.15)) (justify left bottom) hide)
      )
      (property "Footprint" "data-center-rdimm-ddr4-tester-footprints:C_0402_1005Metric" (at 20.32 -12.7 0)
        (effects (font (size 1.27 1.27) (thickness 0.15)) (justify left bottom) hide)
      )
      (property "Datasheet" "https://search.murata.co.jp/Ceramy/image/img/A01X/G101/ENG/GRM155R61H104KE14-01.pdf" (at 20.32 -15.24 0)
        (effects (font (size 1.27 1.27) (thickness 0.15)) (justify left bottom) hide)
      )
      (property "MPN" "GRM155R61H104KE14D" (at 20.32 -17.78 0)
        (effects (font (size 1.27 1.27) (thickness 0.15)) (justify left bottom) hide)
      )
      (property "Manufacturer" "Murata" (at 20.32 -20.32 0)
        (effects (font (size 1.27 1.27) (thickness 0.15)) (justify left bottom) hide)
      )
      (property "License" "Apache-2.0" (at 20.32 -22.86 0)
        (effects (font (size 1.27 1.27) (thickness 0.15)) (justify left bottom) hide)
      )
      (property "Author" "Antmicro" (at 20.32 -25.4 0)
        (effects (font (size 1.27 1.27) (thickness 0.15)) (justify left bottom) hide)
      )
      (property "Val" "100n" (at 20.32 -7.62 0)
        (effects (font (size 1.27 1.27) (thickness 0.15)) (justify left bottom))
      )
      (property "Voltage" "50V" (at 20.32 -27.94 0)
        (effects (font (size 1.27 1.27)) (justify left bottom) hide)
      )
      (property "Dielectric" "X5R" (at 20.32 -30.48 0)
        (effects (font (size 1.27 1.27)) (justify left bottom) hide)
      )
      (property "ki_description" " " (at 0 0 0)
        (effects (font (size 1.27 1.27)) hide)
      )
      (symbol "C_100n_0402_27_0_1"
        (polyline
          (pts
            (xy 2.032 -1.524)
            (xy 2.032 1.524)
          )
          (stroke (width 0.3048) (type default))
          (fill (type none))
        )
        (polyline
          (pts
            (xy 3.048 -1.524)
            (xy 3.048 1.524)
          )
          (stroke (width 0.3302) (type default))
          (fill (type none))
        )
      )
      (symbol "C_100n_0402_27_1_1"
        (pin passive line (at 0 0 0) (length 2.032)
          (name "~" (effects (font (size 1.27 1.27))))
          (number "1" (effects (font (size 1.27 1.27))))
        )
        (pin passive line (at 5.08 0 180) (length 2.032)
          (name "~" (effects (font (size 1.27 1.27))))
          (number "2" (effects (font (size 1.27 1.27))))
        )
      )
    )
	(symbol "data-center-rdimm-ddr4-tester:C_100n_0402_28" (pin_numbers hide) (pin_names hide) (in_bom yes) (on_board yes)
      (property "Reference" "C" (at 20.32 -5.08 0)
        (effects (font (size 1.27 1.27) (thickness 0.15)) (justify left bottom))
      )
      (property "Value" "C_100n_0402_28" (at 20.32 -10.16 0)
        (effects (font (size 1.27 1.27) (thickness 0.15)) (justify left bottom) hide)
      )
      (property "Footprint" "data-center-rdimm-ddr4-tester-footprints:C_0402_1005Metric" (at 20.32 -12.7 0)
        (effects (font (size 1.27 1.27) (thickness 0.15)) (justify left bottom) hide)
      )
      (property "Datasheet" "https://search.murata.co.jp/Ceramy/image/img/A01X/G101/ENG/GRM155R61H104KE14-01.pdf" (at 20.32 -15.24 0)
        (effects (font (size 1.27 1.27) (thickness 0.15)) (justify left bottom) hide)
      )
      (property "MPN" "GRM155R61H104KE14D" (at 20.32 -17.78 0)
        (effects (font (size 1.27 1.27) (thickness 0.15)) (justify left bottom) hide)
      )
      (property "Manufacturer" "Murata" (at 20.32 -20.32 0)
        (effects (font (size 1.27 1.27) (thickness 0.15)) (justify left bottom) hide)
      )
      (property "License" "Apache-2.0" (at 20.32 -22.86 0)
        (effects (font (size 1.27 1.27) (thickness 0.15)) (justify left bottom) hide)
      )
      (property "Author" "Antmicro" (at 20.32 -25.4 0)
        (effects (font (size 1.27 1.27) (thickness 0.15)) (justify left bottom) hide)
      )
      (property "Val" "100n" (at 20.32 -7.62 0)
        (effects (font (size 1.27 1.27) (thickness 0.15)) (justify left bottom))
      )
      (property "Voltage" "50V" (at 20.32 -27.94 0)
        (effects (font (size 1.27 1.27)) (justify left bottom) hide)
      )
      (property "Dielectric" "X5R" (at 20.32 -30.48 0)
        (effects (font (size 1.27 1.27)) (justify left bottom) hide)
      )
      (property "ki_description" " " (at 0 0 0)
        (effects (font (size 1.27 1.27)) hide)
      )
      (symbol "C_100n_0402_28_0_1"
        (polyline
          (pts
            (xy 2.032 -1.524)
            (xy 2.032 1.524)
          )
          (stroke (width 0.3048) (type default))
          (fill (type none))
        )
        (polyline
          (pts
            (xy 3.048 -1.524)
            (xy 3.048 1.524)
          )
          (stroke (width 0.3302) (type default))
          (fill (type none))
        )
      )
      (symbol "C_100n_0402_28_1_1"
        (pin passive line (at 0 0 0) (length 2.032)
          (name "~" (effects (font (size 1.27 1.27))))
          (number "1" (effects (font (size 1.27 1.27))))
        )
        (pin passive line (at 5.08 0 180) (length 2.032)
          (name "~" (effects (font (size 1.27 1.27))))
          (number "2" (effects (font (size 1.27 1.27))))
        )
      )
    )
	(symbol "data-center-rdimm-ddr4-tester:C_100n_0402_29" (pin_numbers hide) (pin_names hide) (in_bom yes) (on_board yes)
      (property "Reference" "C" (at 20.32 -5.08 0)
        (effects (font (size 1.27 1.27) (thickness 0.15)) (justify left bottom))
      )
      (property "Value" "C_100n_0402_29" (at 20.32 -10.16 0)
        (effects (font (size 1.27 1.27) (thickness 0.15)) (justify left bottom) hide)
      )
      (property "Footprint" "data-center-rdimm-ddr4-tester-footprints:C_0402_1005Metric" (at 20.32 -12.7 0)
        (effects (font (size 1.27 1.27) (thickness 0.15)) (justify left bottom) hide)
      )
      (property "Datasheet" "https://search.murata.co.jp/Ceramy/image/img/A01X/G101/ENG/GRM155R61H104KE14-01.pdf" (at 20.32 -15.24 0)
        (effects (font (size 1.27 1.27) (thickness 0.15)) (justify left bottom) hide)
      )
      (property "MPN" "GRM155R61H104KE14D" (at 20.32 -17.78 0)
        (effects (font (size 1.27 1.27) (thickness 0.15)) (justify left bottom) hide)
      )
      (property "Manufacturer" "Murata" (at 20.32 -20.32 0)
        (effects (font (size 1.27 1.27) (thickness 0.15)) (justify left bottom) hide)
      )
      (property "License" "Apache-2.0" (at 20.32 -22.86 0)
        (effects (font (size 1.27 1.27) (thickness 0.15)) (justify left bottom) hide)
      )
      (property "Author" "Antmicro" (at 20.32 -25.4 0)
        (effects (font (size 1.27 1.27) (thickness 0.15)) (justify left bottom) hide)
      )
      (property "Val" "100n" (at 20.32 -7.62 0)
        (effects (font (size 1.27 1.27) (thickness 0.15)) (justify left bottom))
      )
      (property "Voltage" "50V" (at 20.32 -27.94 0)
        (effects (font (size 1.27 1.27)) (justify left bottom) hide)
      )
      (property "Dielectric" "X5R" (at 20.32 -30.48 0)
        (effects (font (size 1.27 1.27)) (justify left bottom) hide)
      )
      (property "ki_description" " " (at 0 0 0)
        (effects (font (size 1.27 1.27)) hide)
      )
      (symbol "C_100n_0402_29_0_1"
        (polyline
          (pts
            (xy 2.032 -1.524)
            (xy 2.032 1.524)
          )
          (stroke (width 0.3048) (type default))
          (fill (type none))
        )
        (polyline
          (pts
            (xy 3.048 -1.524)
            (xy 3.048 1.524)
          )
          (stroke (width 0.3302) (type default))
          (fill (type none))
        )
      )
      (symbol "C_100n_0402_29_1_1"
        (pin passive line (at 0 0 0) (length 2.032)
          (name "~" (effects (font (size 1.27 1.27))))
          (number "1" (effects (font (size 1.27 1.27))))
        )
        (pin passive line (at 5.08 0 180) (length 2.032)
          (name "~" (effects (font (size 1.27 1.27))))
          (number "2" (effects (font (size 1.27 1.27))))
        )
      )
    )
	(symbol "data-center-rdimm-ddr4-tester:C_100n_0402_30" (pin_numbers hide) (pin_names hide) (in_bom yes) (on_board yes)
      (property "Reference" "C" (at 20.32 -5.08 0)
        (effects (font (size 1.27 1.27) (thickness 0.15)) (justify left bottom))
      )
      (property "Value" "C_100n_0402_30" (at 20.32 -10.16 0)
        (effects (font (size 1.27 1.27) (thickness 0.15)) (justify left bottom) hide)
      )
      (property "Footprint" "data-center-rdimm-ddr4-tester-footprints:C_0402_1005Metric" (at 20.32 -12.7 0)
        (effects (font (size 1.27 1.27) (thickness 0.15)) (justify left bottom) hide)
      )
      (property "Datasheet" "https://search.murata.co.jp/Ceramy/image/img/A01X/G101/ENG/GRM155R61H104KE14-01.pdf" (at 20.32 -15.24 0)
        (effects (font (size 1.27 1.27) (thickness 0.15)) (justify left bottom) hide)
      )
      (property "MPN" "GRM155R61H104KE14D" (at 20.32 -17.78 0)
        (effects (font (size 1.27 1.27) (thickness 0.15)) (justify left bottom) hide)
      )
      (property "Manufacturer" "Murata" (at 20.32 -20.32 0)
        (effects (font (size 1.27 1.27) (thickness 0.15)) (justify left bottom) hide)
      )
      (property "License" "Apache-2.0" (at 20.32 -22.86 0)
        (effects (font (size 1.27 1.27) (thickness 0.15)) (justify left bottom) hide)
      )
      (property "Author" "Antmicro" (at 20.32 -25.4 0)
        (effects (font (size 1.27 1.27) (thickness 0.15)) (justify left bottom) hide)
      )
      (property "Val" "100n" (at 20.32 -7.62 0)
        (effects (font (size 1.27 1.27) (thickness 0.15)) (justify left bottom))
      )
      (property "Voltage" "50V" (at 20.32 -27.94 0)
        (effects (font (size 1.27 1.27)) (justify left bottom) hide)
      )
      (property "Dielectric" "X5R" (at 20.32 -30.48 0)
        (effects (font (size 1.27 1.27)) (justify left bottom) hide)
      )
      (property "ki_description" " " (at 0 0 0)
        (effects (font (size 1.27 1.27)) hide)
      )
      (symbol "C_100n_0402_30_0_1"
        (polyline
          (pts
            (xy 2.032 -1.524)
            (xy 2.032 1.524)
          )
          (stroke (width 0.3048) (type default))
          (fill (type none))
        )
        (polyline
          (pts
            (xy 3.048 -1.524)
            (xy 3.048 1.524)
          )
          (stroke (width 0.3302) (type default))
          (fill (type none))
        )
      )
      (symbol "C_100n_0402_30_1_1"
        (pin passive line (at 0 0 0) (length 2.032)
          (name "~" (effects (font (size 1.27 1.27))))
          (number "1" (effects (font (size 1.27 1.27))))
        )
        (pin passive line (at 5.08 0 180) (length 2.032)
          (name "~" (effects (font (size 1.27 1.27))))
          (number "2" (effects (font (size 1.27 1.27))))
        )
      )
    )
	(symbol "data-center-rdimm-ddr4-tester:C_100n_0402_31" (pin_numbers hide) (pin_names hide) (in_bom yes) (on_board yes)
      (property "Reference" "C" (at 20.32 -5.08 0)
        (effects (font (size 1.27 1.27) (thickness 0.15)) (justify left bottom))
      )
      (property "Value" "C_100n_0402_31" (at 20.32 -10.16 0)
        (effects (font (size 1.27 1.27) (thickness 0.15)) (justify left bottom) hide)
      )
      (property "Footprint" "data-center-rdimm-ddr4-tester-footprints:C_0402_1005Metric" (at 20.32 -12.7 0)
        (effects (font (size 1.27 1.27) (thickness 0.15)) (justify left bottom) hide)
      )
      (property "Datasheet" "https://search.murata.co.jp/Ceramy/image/img/A01X/G101/ENG/GRM155R61H104KE14-01.pdf" (at 20.32 -15.24 0)
        (effects (font (size 1.27 1.27) (thickness 0.15)) (justify left bottom) hide)
      )
      (property "MPN" "GRM155R61H104KE14D" (at 20.32 -17.78 0)
        (effects (font (size 1.27 1.27) (thickness 0.15)) (justify left bottom) hide)
      )
      (property "Manufacturer" "Murata" (at 20.32 -20.32 0)
        (effects (font (size 1.27 1.27) (thickness 0.15)) (justify left bottom) hide)
      )
      (property "License" "Apache-2.0" (at 20.32 -22.86 0)
        (effects (font (size 1.27 1.27) (thickness 0.15)) (justify left bottom) hide)
      )
      (property "Author" "Antmicro" (at 20.32 -25.4 0)
        (effects (font (size 1.27 1.27) (thickness 0.15)) (justify left bottom) hide)
      )
      (property "Val" "100n" (at 20.32 -7.62 0)
        (effects (font (size 1.27 1.27) (thickness 0.15)) (justify left bottom))
      )
      (property "Voltage" "50V" (at 20.32 -27.94 0)
        (effects (font (size 1.27 1.27)) (justify left bottom) hide)
      )
      (property "Dielectric" "X5R" (at 20.32 -30.48 0)
        (effects (font (size 1.27 1.27)) (justify left bottom) hide)
      )
      (property "ki_description" " " (at 0 0 0)
        (effects (font (size 1.27 1.27)) hide)
      )
      (symbol "C_100n_0402_31_0_1"
        (polyline
          (pts
            (xy 2.032 -1.524)
            (xy 2.032 1.524)
          )
          (stroke (width 0.3048) (type default))
          (fill (type none))
        )
        (polyline
          (pts
            (xy 3.048 -1.524)
            (xy 3.048 1.524)
          )
          (stroke (width 0.3302) (type default))
          (fill (type none))
        )
      )
      (symbol "C_100n_0402_31_1_1"
        (pin passive line (at 0 0 0) (length 2.032)
          (name "~" (effects (font (size 1.27 1.27))))
          (number "1" (effects (font (size 1.27 1.27))))
        )
        (pin passive line (at 5.08 0 180) (length 2.032)
          (name "~" (effects (font (size 1.27 1.27))))
          (number "2" (effects (font (size 1.27 1.27))))
        )
      )
    )
	(symbol "data-center-rdimm-ddr4-tester:C_100n_0402_32" (pin_numbers hide) (pin_names hide) (in_bom yes) (on_board yes)
      (property "Reference" "C" (at 20.32 -5.08 0)
        (effects (font (size 1.27 1.27) (thickness 0.15)) (justify left bottom))
      )
      (property "Value" "C_100n_0402_32" (at 20.32 -10.16 0)
        (effects (font (size 1.27 1.27) (thickness 0.15)) (justify left bottom) hide)
      )
      (property "Footprint" "data-center-rdimm-ddr4-tester-footprints:C_0402_1005Metric" (at 20.32 -12.7 0)
        (effects (font (size 1.27 1.27) (thickness 0.15)) (justify left bottom) hide)
      )
      (property "Datasheet" "https://search.murata.co.jp/Ceramy/image/img/A01X/G101/ENG/GRM155R61H104KE14-01.pdf" (at 20.32 -15.24 0)
        (effects (font (size 1.27 1.27) (thickness 0.15)) (justify left bottom) hide)
      )
      (property "MPN" "GRM155R61H104KE14D" (at 20.32 -17.78 0)
        (effects (font (size 1.27 1.27) (thickness 0.15)) (justify left bottom) hide)
      )
      (property "Manufacturer" "Murata" (at 20.32 -20.32 0)
        (effects (font (size 1.27 1.27) (thickness 0.15)) (justify left bottom) hide)
      )
      (property "License" "Apache-2.0" (at 20.32 -22.86 0)
        (effects (font (size 1.27 1.27) (thickness 0.15)) (justify left bottom) hide)
      )
      (property "Author" "Antmicro" (at 20.32 -25.4 0)
        (effects (font (size 1.27 1.27) (thickness 0.15)) (justify left bottom) hide)
      )
      (property "Val" "100n" (at 20.32 -7.62 0)
        (effects (font (size 1.27 1.27) (thickness 0.15)) (justify left bottom))
      )
      (property "Voltage" "50V" (at 20.32 -27.94 0)
        (effects (font (size 1.27 1.27)) (justify left bottom) hide)
      )
      (property "Dielectric" "X5R" (at 20.32 -30.48 0)
        (effects (font (size 1.27 1.27)) (justify left bottom) hide)
      )
      (property "ki_description" " " (at 0 0 0)
        (effects (font (size 1.27 1.27)) hide)
      )
      (symbol "C_100n_0402_32_0_1"
        (polyline
          (pts
            (xy 2.032 -1.524)
            (xy 2.032 1.524)
          )
          (stroke (width 0.3048) (type default))
          (fill (type none))
        )
        (polyline
          (pts
            (xy 3.048 -1.524)
            (xy 3.048 1.524)
          )
          (stroke (width 0.3302) (type default))
          (fill (type none))
        )
      )
      (symbol "C_100n_0402_32_1_1"
        (pin passive line (at 0 0 0) (length 2.032)
          (name "~" (effects (font (size 1.27 1.27))))
          (number "1" (effects (font (size 1.27 1.27))))
        )
        (pin passive line (at 5.08 0 180) (length 2.032)
          (name "~" (effects (font (size 1.27 1.27))))
          (number "2" (effects (font (size 1.27 1.27))))
        )
      )
    )
	(symbol "data-center-rdimm-ddr4-tester:C_100n_0805_100V" (pin_numbers hide) (pin_names hide) (in_bom yes) (on_board yes)
      (property "Reference" "C" (at 20.32 -5.08 0)
        (effects (font (size 1.27 1.27) (thickness 0.15)) (justify left bottom))
      )
      (property "Value" "C_100n_0805_100V" (at 20.32 -10.16 0)
        (effects (font (size 1.27 1.27) (thickness 0.15)) (justify left bottom) hide)
      )
      (property "Footprint" "data-center-rdimm-ddr4-tester-footprints:C_0805_2012Metric" (at 20.32 -12.7 0)
        (effects (font (size 1.27 1.27) (thickness 0.15)) (justify left bottom) hide)
      )
      (property "Datasheet" "https://www.mouser.pl/datasheet/2/585/MLCC-1837944.pdf" (at 20.32 -15.24 0)
        (effects (font (size 1.27 1.27) (thickness 0.15)) (justify left bottom) hide)
      )
      (property "MPN" "CL21B104KCFNNNE" (at 20.32 -17.78 0)
        (effects (font (size 1.27 1.27) (thickness 0.15)) (justify left bottom) hide)
      )
      (property "Manufacturer" "SAMSUNG" (at 20.32 -20.32 0)
        (effects (font (size 1.27 1.27) (thickness 0.15)) (justify left bottom) hide)
      )
      (property "License" "Apache-2.0" (at 20.32 -22.86 0)
        (effects (font (size 1.27 1.27) (thickness 0.15)) (justify left bottom) hide)
      )
      (property "Author" "Antmicro" (at 20.32 -25.4 0)
        (effects (font (size 1.27 1.27) (thickness 0.15)) (justify left bottom) hide)
      )
      (property "Val" "100n/100V" (at 20.32 -7.62 0)
        (effects (font (size 1.27 1.27) (thickness 0.15)) (justify left bottom))
      )
      (property "Voltage" "100V" (at 20.32 -27.94 0)
        (effects (font (size 1.27 1.27)) (justify left bottom) hide)
      )
      (property "Dielectric" "X7R" (at 20.32 -30.48 0)
        (effects (font (size 1.27 1.27)) (justify left bottom) hide)
      )
      (property "ki_description" " " (at 0 0 0)
        (effects (font (size 1.27 1.27)) hide)
      )
      (symbol "C_100n_0805_100V_0_1"
        (polyline
          (pts
            (xy 2.032 -1.524)
            (xy 2.032 1.524)
          )
          (stroke (width 0.3048) (type default))
          (fill (type none))
        )
        (polyline
          (pts
            (xy 3.048 -1.524)
            (xy 3.048 1.524)
          )
          (stroke (width 0.3302) (type default))
          (fill (type none))
        )
      )
      (symbol "C_100n_0805_100V_1_1"
        (pin passive line (at 0 0 0) (length 2.032)
          (name "~" (effects (font (size 1.27 1.27))))
          (number "1" (effects (font (size 1.27 1.27))))
        )
        (pin passive line (at 5.08 0 180) (length 2.032)
          (name "~" (effects (font (size 1.27 1.27))))
          (number "2" (effects (font (size 1.27 1.27))))
        )
      )
    )
	(symbol "data-center-rdimm-ddr4-tester:C_100n_16V_0402" (pin_numbers hide) (pin_names hide) (in_bom yes) (on_board yes)
      (property "Reference" "C" (at 20.32 -5.08 0)
        (effects (font (size 1.27 1.27) (thickness 0.15)) (justify left bottom))
      )
      (property "Value" "C_100n_16V_0402" (at 20.32 -10.16 0)
        (effects (font (size 1.27 1.27) (thickness 0.15)) (justify left bottom) hide)
      )
      (property "Footprint" "data-center-rdimm-ddr4-tester-footprints:C_0402_1005Metric" (at 20.32 -12.7 0)
        (effects (font (size 1.27 1.27) (thickness 0.15)) (justify left bottom) hide)
      )
      (property "Datasheet" " " (at 20.32 -15.24 0)
        (effects (font (size 1.27 1.27) (thickness 0.15)) (justify left bottom) hide)
      )
      (property "MPN" "MC0402B104K160CT" (at 20.32 -17.78 0)
        (effects (font (size 1.27 1.27) (thickness 0.15)) (justify left bottom) hide)
      )
      (property "Manufacturer" "Multicomp" (at 20.32 -20.32 0)
        (effects (font (size 1.27 1.27) (thickness 0.15)) (justify left bottom) hide)
      )
      (property "License" "Apache-2.0" (at 20.32 -22.86 0)
        (effects (font (size 1.27 1.27) (thickness 0.15)) (justify left bottom) hide)
      )
      (property "Author" "Antmicro" (at 20.32 -25.4 0)
        (effects (font (size 1.27 1.27) (thickness 0.15)) (justify left bottom) hide)
      )
      (property "Val" "100n" (at 20.32 -7.62 0)
        (effects (font (size 1.27 1.27) (thickness 0.15)) (justify left bottom))
      )
      (property "Voltage" "" (at 20.32 -27.94 0)
        (effects (font (size 1.27 1.27)) (justify left bottom) hide)
      )
      (property "Dielectric" "" (at 20.32 -30.48 0)
        (effects (font (size 1.27 1.27)) (justify left bottom) hide)
      )
      (property "ki_description" " " (at 0 0 0)
        (effects (font (size 1.27 1.27)) hide)
      )
      (symbol "C_100n_16V_0402_0_1"
        (polyline
          (pts
            (xy 2.032 -1.524)
            (xy 2.032 1.524)
          )
          (stroke (width 0.3048) (type default))
          (fill (type none))
        )
        (polyline
          (pts
            (xy 3.048 -1.524)
            (xy 3.048 1.524)
          )
          (stroke (width 0.3302) (type default))
          (fill (type none))
        )
      )
      (symbol "C_100n_16V_0402_1_1"
        (pin passive line (at 0 0 0) (length 2.032)
          (name "~" (effects (font (size 1.27 1.27))))
          (number "1" (effects (font (size 1.27 1.27))))
        )
        (pin passive line (at 5.08 0 180) (length 2.032)
          (name "~" (effects (font (size 1.27 1.27))))
          (number "2" (effects (font (size 1.27 1.27))))
        )
      )
    )
	(symbol "data-center-rdimm-ddr4-tester:C_100u_KEMET_A" (pin_numbers hide) (pin_names hide) (in_bom yes) (on_board yes)
      (property "Reference" "C" (at 13.97 0 0)
        (effects (font (size 1.27 1.27) (thickness 0.15)) (justify left bottom))
      )
      (property "Value" "C_100u_KEMET_A" (at 13.97 -5.08 0)
        (effects (font (size 1.27 1.27) (thickness 0.15)) (justify left bottom) hide)
      )
      (property "Footprint" "data-center-rdimm-ddr4-tester-footprints:KEMET_A" (at 13.97 -7.62 0)
        (effects (font (size 1.27 1.27) (thickness 0.15)) (justify left bottom) hide)
      )
      (property "Datasheet" " " (at 13.97 -10.16 0)
        (effects (font (size 1.27 1.27) (thickness 0.15)) (justify left bottom) hide)
      )
      (property "MPN" "298D107X06R3A2T" (at 13.97 -12.7 0)
        (effects (font (size 1.27 1.27) (thickness 0.15)) (justify left bottom) hide)
      )
      (property "Manufacturer" "Vishay" (at 13.97 -15.24 0)
        (effects (font (size 1.27 1.27) (thickness 0.15)) (justify left bottom) hide)
      )
      (property "License" "Apache-2.0" (at 13.97 -17.78 0)
        (effects (font (size 1.27 1.27) (thickness 0.15)) (justify left bottom) hide)
      )
      (property "Author" "Antmicro" (at 13.97 -20.32 0)
        (effects (font (size 1.27 1.27) (thickness 0.15)) (justify left bottom) hide)
      )
      (property "Val" "100u" (at 13.97 -2.54 0)
        (effects (font (size 1.27 1.27) (thickness 0.15)) (justify left bottom))
      )
      (property "Voltage" "" (at 13.97 -22.86 0)
        (effects (font (size 1.27 1.27)) (justify left bottom) hide)
      )
      (property "Dielectric" "" (at 13.97 -25.4 0)
        (effects (font (size 1.27 1.27)) (justify left bottom) hide)
      )
      (property "ki_description" " " (at 0 0 0)
        (effects (font (size 1.27 1.27)) hide)
      )
      (symbol "C_100u_KEMET_A_0_1"
        (rectangle (start -1.524 -2.921) (end 1.524 -3.302)
          (stroke (width 0) (type default))
          (fill (type outline))
        )
        (rectangle (start -1.524 -1.905) (end 1.524 -2.286)
          (stroke (width 0) (type default))
          (fill (type none))
        )
        (polyline
          (pts
            (xy -1.27 -0.9652)
            (xy -0.762 -0.9652)
          )
          (stroke (width 0) (type default))
          (fill (type none))
        )
        (polyline
          (pts
            (xy -1.016 -1.2192)
            (xy -1.016 -0.7112)
          )
          (stroke (width 0) (type default))
          (fill (type none))
        )
      )
      (symbol "C_100u_KEMET_A_1_1"
        (pin passive line (at 0 0 270) (length 1.8542)
          (name "~" (effects (font (size 1.27 1.27))))
          (number "1" (effects (font (size 1.27 1.27))))
        )
        (pin passive line (at 0 -5.08 90) (length 1.8542)
          (name "~" (effects (font (size 1.27 1.27))))
          (number "2" (effects (font (size 1.27 1.27))))
        )
      )
    )
	(symbol "data-center-rdimm-ddr4-tester:C_330u_KEMET_D" (pin_numbers hide) (pin_names hide) (in_bom yes) (on_board yes)
      (property "Reference" "C" (at 13.97 0 0)
        (effects (font (size 1.27 1.27) (thickness 0.15)) (justify left bottom))
      )
      (property "Value" "C_330u_KEMET_D" (at 13.97 -5.08 0)
        (effects (font (size 1.27 1.27) (thickness 0.15)) (justify left bottom) hide)
      )
      (property "Footprint" "data-center-rdimm-ddr4-tester-footprints:KEMET_D" (at 13.97 -7.62 0)
        (effects (font (size 1.27 1.27) (thickness 0.15)) (justify left bottom) hide)
      )
      (property "Datasheet" " " (at 13.97 -10.16 0)
        (effects (font (size 1.27 1.27) (thickness 0.15)) (justify left bottom) hide)
      )
      (property "MPN" "T520D337M006ATE045" (at 13.97 -12.7 0)
        (effects (font (size 1.27 1.27) (thickness 0.15)) (justify left bottom) hide)
      )
      (property "Manufacturer" "KEMET" (at 13.97 -15.24 0)
        (effects (font (size 1.27 1.27) (thickness 0.15)) (justify left bottom) hide)
      )
      (property "License" "Apache-2.0" (at 13.97 -17.78 0)
        (effects (font (size 1.27 1.27) (thickness 0.15)) (justify left bottom) hide)
      )
      (property "Author" "Antmicro" (at 13.97 -20.32 0)
        (effects (font (size 1.27 1.27) (thickness 0.15)) (justify left bottom) hide)
      )
      (property "Val" "330u" (at 13.97 -2.54 0)
        (effects (font (size 1.27 1.27) (thickness 0.15)) (justify left bottom))
      )
      (property "Voltage" "" (at 13.97 -22.86 0)
        (effects (font (size 1.27 1.27)) (justify left bottom) hide)
      )
      (property "Dielectric" "" (at 13.97 -25.4 0)
        (effects (font (size 1.27 1.27)) (justify left bottom) hide)
      )
      (property "ki_description" " " (at 0 0 0)
        (effects (font (size 1.27 1.27)) hide)
      )
      (symbol "C_330u_KEMET_D_0_1"
        (rectangle (start -1.524 -2.921) (end 1.524 -3.302)
          (stroke (width 0) (type default))
          (fill (type outline))
        )
        (rectangle (start -1.524 -1.905) (end 1.524 -2.286)
          (stroke (width 0) (type default))
          (fill (type none))
        )
        (polyline
          (pts
            (xy -1.27 -0.9652)
            (xy -0.762 -0.9652)
          )
          (stroke (width 0) (type default))
          (fill (type none))
        )
        (polyline
          (pts
            (xy -1.016 -1.2192)
            (xy -1.016 -0.7112)
          )
          (stroke (width 0) (type default))
          (fill (type none))
        )
      )
      (symbol "C_330u_KEMET_D_1_1"
        (pin passive line (at 0 0 270) (length 1.8542)
          (name "~" (effects (font (size 1.27 1.27))))
          (number "1" (effects (font (size 1.27 1.27))))
        )
        (pin passive line (at 0 -5.08 90) (length 1.8542)
          (name "~" (effects (font (size 1.27 1.27))))
          (number "2" (effects (font (size 1.27 1.27))))
        )
      )
    )
	(symbol "data-center-rdimm-ddr4-tester:C_47u_0603_10" (pin_numbers hide) (pin_names hide) (in_bom yes) (on_board yes)
      (property "Reference" "C" (at 20.32 -5.08 0)
        (effects (font (size 1.27 1.27) (thickness 0.15)) (justify left bottom))
      )
      (property "Value" "C_47u_0603_10" (at 20.32 -10.16 0)
        (effects (font (size 1.27 1.27) (thickness 0.15)) (justify left bottom) hide)
      )
      (property "Footprint" "data-center-rdimm-ddr4-tester-footprints:C_0603_1608Metric" (at 20.32 -12.7 0)
        (effects (font (size 1.27 1.27) (thickness 0.15)) (justify left bottom) hide)
      )
      (property "Datasheet" " " (at 20.32 -15.24 0)
        (effects (font (size 1.27 1.27) (thickness 0.15)) (justify left bottom) hide)
      )
      (property "MPN" "GRM188R60J476ME15D" (at 20.32 -17.78 0)
        (effects (font (size 1.27 1.27) (thickness 0.15)) (justify left bottom) hide)
      )
      (property "Manufacturer" "Murata" (at 20.32 -20.32 0)
        (effects (font (size 1.27 1.27) (thickness 0.15)) (justify left bottom) hide)
      )
      (property "License" "Apache-2.0" (at 20.32 -22.86 0)
        (effects (font (size 1.27 1.27) (thickness 0.15)) (justify left bottom) hide)
      )
      (property "Author" "Antmicro" (at 20.32 -25.4 0)
        (effects (font (size 1.27 1.27) (thickness 0.15)) (justify left bottom) hide)
      )
      (property "Val" "47u" (at 20.32 -7.62 0)
        (effects (font (size 1.27 1.27) (thickness 0.15)) (justify left bottom))
      )
      (property "Voltage" "" (at 20.32 -27.94 0)
        (effects (font (size 1.27 1.27)) (justify left bottom) hide)
      )
      (property "Dielectric" "" (at 20.32 -30.48 0)
        (effects (font (size 1.27 1.27)) (justify left bottom) hide)
      )
      (property "ki_description" " " (at 0 0 0)
        (effects (font (size 1.27 1.27)) hide)
      )
      (symbol "C_47u_0603_10_0_1"
        (polyline
          (pts
            (xy 2.032 -1.524)
            (xy 2.032 1.524)
          )
          (stroke (width 0.3048) (type default))
          (fill (type none))
        )
        (polyline
          (pts
            (xy 3.048 -1.524)
            (xy 3.048 1.524)
          )
          (stroke (width 0.3302) (type default))
          (fill (type none))
        )
      )
      (symbol "C_47u_0603_10_1_1"
        (pin passive line (at 0 0 0) (length 2.032)
          (name "~" (effects (font (size 1.27 1.27))))
          (number "1" (effects (font (size 1.27 1.27))))
        )
        (pin passive line (at 5.08 0 180) (length 2.032)
          (name "~" (effects (font (size 1.27 1.27))))
          (number "2" (effects (font (size 1.27 1.27))))
        )
      )
    )
	(symbol "data-center-rdimm-ddr4-tester:FB_120Z_2A_0603" (pin_numbers hide) (pin_names hide) (in_bom yes) (on_board yes)
      (property "Reference" "FB" (at 15.24 -2.54 0)
        (effects (font (size 1.27 1.27) (thickness 0.15)) (justify left bottom))
      )
      (property "Value" "FB_120Z_2A_0603" (at 15.24 -5.08 0)
        (effects (font (size 1.27 1.27) (thickness 0.15)) (justify left bottom) hide)
      )
      (property "Footprint" "data-center-rdimm-ddr4-tester-footprints:FB_0603_1608Metric" (at 15.24 -7.62 0)
        (effects (font (size 1.27 1.27) (thickness 0.15)) (justify left bottom) hide)
      )
      (property "Datasheet" "https://www.murata.com/en-us/products/productdata/8796738650142/ENFA0003.pdf" (at 15.24 -10.16 0)
        (effects (font (size 1.27 1.27) (thickness 0.15)) (justify left bottom) hide)
      )
      (property "MPN" "BLM18PG121SN1D" (at 15.24 -12.7 0)
        (effects (font (size 1.27 1.27) (thickness 0.15)) (justify left bottom))
      )
      (property "Manufacturer" "Murata" (at 15.24 -15.24 0)
        (effects (font (size 1.27 1.27) (thickness 0.15)) (justify left bottom) hide)
      )
      (property "Val" "240" (at 20.32 -10.16 0)
        (effects (font (size 1.27 1.27) (thickness 0.15)) (justify left bottom))
      )
      (property "Author" "Antmicro" (at 15.24 -17.78 0)
        (effects (font (size 1.27 1.27) (thickness 0.15)) (justify left bottom) hide)
      )
      (property "Current" "0.2A" (at 20.32 -22.86 0)
        (effects (font (size 1.27 1.27) (thickness 0.15)) (justify left bottom) hide)
      )
      (property "License" "Apache-2.0" (at 15.24 -20.32 0)
        (effects (font (size 1.27 1.27) (thickness 0.15)) (justify left bottom) hide)
      )
      (property "ki_keywords" " Multilayer Suppression Beads " (at 0 0 0)
        (effects (font (size 1.27 1.27)) hide)
      )
      (property "ki_description" "Ferrite Beads WE-TMSB Suppression 240Ohm 200mA " (at 0 0 0)
        (effects (font (size 1.27 1.27)) hide)
      )
      (symbol "FB_120Z_2A_0603_0_1"
        (polyline
          (pts
            (xy 1.651 0)
            (xy 1.2446 0)
          )
          (stroke (width 0) (type default))
          (fill (type none))
        )
        (polyline
          (pts
            (xy 3.81 0)
            (xy 3.3274 0)
          )
          (stroke (width 0) (type default))
          (fill (type none))
        )
        (polyline
          (pts
            (xy 2.2606 -1.8288)
            (xy 1.0414 -1.1176)
            (xy 2.7432 1.8288)
            (xy 3.9624 1.1176)
            (xy 2.2606 -1.8288)
          )
          (stroke (width 0) (type default))
          (fill (type none))
        )
      )
      (symbol "FB_120Z_2A_0603_1_1"
        (pin passive line (at 0 0 0) (length 1.27)
          (name "~" (effects (font (size 1.27 1.27))))
          (number "1" (effects (font (size 1.27 1.27))))
        )
        (pin passive line (at 5.08 0 180) (length 1.27)
          (name "~" (effects (font (size 1.27 1.27))))
          (number "2" (effects (font (size 1.27 1.27))))
        )
      )
    )
	(symbol "data-center-rdimm-ddr4-tester:FB_220Z_2A_0603" (pin_numbers hide) (pin_names hide) (in_bom yes) (on_board yes)
      (property "Reference" "FB" (at 13.97 0 0)
        (effects (font (size 1.27 1.27) (thickness 0.15)) (justify left bottom))
      )
      (property "Value" "FB_220Z_2A_0603" (at 13.97 -2.54 0)
        (effects (font (size 1.27 1.27) (thickness 0.15)) (justify left bottom))
      )
      (property "Footprint" "data-center-rdimm-ddr4-tester-footprints:FB_0805_2012Metric" (at 13.97 -5.08 0)
        (effects (font (size 1.27 1.27) (thickness 0.15)) (justify left bottom) hide)
      )
      (property "Datasheet" "https://www.murata.com/products/productdata/8796738977822/ENFA0005.pdf?1653276712000" (at 13.97 -7.62 0)
        (effects (font (size 1.27 1.27) (thickness 0.15)) (justify left bottom) hide)
      )
      (property "MPN" "BLM21PG221SN1D" (at 13.97 -10.16 0)
        (effects (font (size 1.27 1.27) (thickness 0.15)) (justify left bottom) hide)
      )
      (property "Manufacturer" "Murata" (at 13.97 -12.7 0)
        (effects (font (size 1.27 1.27) (thickness 0.15)) (justify left bottom) hide)
      )
      (property "Author" "Antmicro" (at 13.97 -15.24 0)
        (effects (font (size 1.27 1.27) (thickness 0.15)) (justify left bottom) hide)
      )
      (property "License" "Apache-2.0" (at 13.97 -17.78 0)
        (effects (font (size 1.27 1.27) (thickness 0.15)) (justify left bottom) hide)
      )
      (symbol "FB_220Z_2A_0603_0_1"
        (polyline
          (pts
            (xy 1.651 0)
            (xy 1.2446 0)
          )
          (stroke (width 0) (type default))
          (fill (type none))
        )
        (polyline
          (pts
            (xy 3.81 0)
            (xy 3.3274 0)
          )
          (stroke (width 0) (type default))
          (fill (type none))
        )
        (polyline
          (pts
            (xy 2.2606 -1.8288)
            (xy 1.0414 -1.1176)
            (xy 2.7432 1.8288)
            (xy 3.9624 1.1176)
            (xy 2.2606 -1.8288)
          )
          (stroke (width 0) (type default))
          (fill (type none))
        )
      )
      (symbol "FB_220Z_2A_0603_1_1"
        (pin passive line (at 0 0 0) (length 1.27)
          (name "~" (effects (font (size 1.27 1.27))))
          (number "1" (effects (font (size 1.27 1.27))))
        )
        (pin passive line (at 5.08 0 180) (length 1.27)
          (name "~" (effects (font (size 1.27 1.27))))
          (number "2" (effects (font (size 1.27 1.27))))
        )
      )
    )
	(symbol "data-center-rdimm-ddr4-tester:FB_600Z_0.5A_0603" (pin_numbers hide) (pin_names hide) (in_bom yes) (on_board yes)
      (property "Reference" "FB" (at 15.24 -2.54 0)
        (effects (font (size 1.27 1.27) (thickness 0.15)) (justify left bottom))
      )
      (property "Value" "FB_600Z_0.5A_0603" (at 15.24 -5.08 0)
        (effects (font (size 1.27 1.27) (thickness 0.15)) (justify left bottom) hide)
      )
      (property "Footprint" "data-center-rdimm-ddr4-tester-footprints:FB_0603_1608Metric" (at 15.24 -7.62 0)
        (effects (font (size 1.27 1.27) (thickness 0.15)) (justify left bottom) hide)
      )
      (property "Datasheet" "https://www.murata.com/en-us/products/productdata/8796738650142/ENFA0003.pdf" (at 15.24 -10.16 0)
        (effects (font (size 1.27 1.27) (thickness 0.15)) (justify left bottom) hide)
      )
      (property "MPN" "BLM18AG601SN1D" (at 15.24 -12.7 0)
        (effects (font (size 1.27 1.27) (thickness 0.15)) (justify left bottom))
      )
      (property "Manufacturer" "Murata" (at 15.24 -15.24 0)
        (effects (font (size 1.27 1.27) (thickness 0.15)) (justify left bottom) hide)
      )
      (property "Val" "240" (at 20.32 -10.16 0)
        (effects (font (size 1.27 1.27) (thickness 0.15)) (justify left bottom))
      )
      (property "Author" "Antmicro" (at 15.24 -17.78 0)
        (effects (font (size 1.27 1.27) (thickness 0.15)) (justify left bottom) hide)
      )
      (property "Current" "0.2A" (at 20.32 -22.86 0)
        (effects (font (size 1.27 1.27) (thickness 0.15)) (justify left bottom) hide)
      )
      (property "License" "Apache-2.0" (at 15.24 -20.32 0)
        (effects (font (size 1.27 1.27) (thickness 0.15)) (justify left bottom) hide)
      )
      (property "ki_keywords" " Multilayer Suppression Beads " (at 0 0 0)
        (effects (font (size 1.27 1.27)) hide)
      )
      (property "ki_description" "Ferrite Beads WE-TMSB Suppression 240Ohm 200mA " (at 0 0 0)
        (effects (font (size 1.27 1.27)) hide)
      )
      (symbol "FB_600Z_0.5A_0603_0_1"
        (polyline
          (pts
            (xy 1.651 0)
            (xy 1.2446 0)
          )
          (stroke (width 0) (type default))
          (fill (type none))
        )
        (polyline
          (pts
            (xy 3.81 0)
            (xy 3.3274 0)
          )
          (stroke (width 0) (type default))
          (fill (type none))
        )
        (polyline
          (pts
            (xy 2.2606 -1.8288)
            (xy 1.0414 -1.1176)
            (xy 2.7432 1.8288)
            (xy 3.9624 1.1176)
            (xy 2.2606 -1.8288)
          )
          (stroke (width 0) (type default))
          (fill (type none))
        )
      )
      (symbol "FB_600Z_0.5A_0603_1_1"
        (pin passive line (at 0 0 0) (length 1.27)
          (name "~" (effects (font (size 1.27 1.27))))
          (number "1" (effects (font (size 1.27 1.27))))
        )
        (pin passive line (at 5.08 0 180) (length 1.27)
          (name "~" (effects (font (size 1.27 1.27))))
          (number "2" (effects (font (size 1.27 1.27))))
        )
      )
    )
	(symbol "data-center-rdimm-ddr4-tester:GND_10" (power) (pin_names (offset 0)) (in_bom yes) (on_board yes)
      (property "Reference" "#PWR" (at 0 -6.35 0)
        (effects (font (size 1.27 1.27)) hide)
      )
      (property "Value" "GND_10" (at 0 -3.81 0)
        (effects (font (size 1.27 1.27)))
      )
      (property "Footprint" "" (at 0 0 0)
        (effects (font (size 1.27 1.27)) hide)
      )
      (property "Datasheet" "" (at 0 0 0)
        (effects (font (size 1.27 1.27)) hide)
      )
      (symbol "GND_10_0_1"
        (polyline
          (pts
            (xy 0 0)
            (xy 0 -1.27)
            (xy 1.27 -1.27)
            (xy 0 -2.54)
            (xy -1.27 -1.27)
            (xy 0 -1.27)
          )
          (stroke (width 0) (type default))
          (fill (type none))
        )
      )
      (symbol "GND_10_1_1"
        (pin power_in line (at 0 0 270) (length 0) hide
          (name "GND" (effects (font (size 1.27 1.27))))
          (number "1" (effects (font (size 1.27 1.27))))
        )
      )
    )
	(symbol "data-center-rdimm-ddr4-tester:GND_11" (power) (pin_names (offset 0)) (in_bom yes) (on_board yes)
      (property "Reference" "#PWR" (at 0 -6.35 0)
        (effects (font (size 1.27 1.27)) hide)
      )
      (property "Value" "GND_11" (at 0 -3.81 0)
        (effects (font (size 1.27 1.27)))
      )
      (property "Footprint" "" (at 0 0 0)
        (effects (font (size 1.27 1.27)) hide)
      )
      (property "Datasheet" "" (at 0 0 0)
        (effects (font (size 1.27 1.27)) hide)
      )
      (symbol "GND_11_0_1"
        (polyline
          (pts
            (xy 0 0)
            (xy 0 -1.27)
            (xy 1.27 -1.27)
            (xy 0 -2.54)
            (xy -1.27 -1.27)
            (xy 0 -1.27)
          )
          (stroke (width 0) (type default))
          (fill (type none))
        )
      )
      (symbol "GND_11_1_1"
        (pin power_in line (at 0 0 270) (length 0) hide
          (name "GND" (effects (font (size 1.27 1.27))))
          (number "1" (effects (font (size 1.27 1.27))))
        )
      )
    )
	(symbol "data-center-rdimm-ddr4-tester:GND_12" (power) (pin_names (offset 0)) (in_bom yes) (on_board yes)
      (property "Reference" "#PWR" (at 0 -6.35 0)
        (effects (font (size 1.27 1.27)) hide)
      )
      (property "Value" "GND_12" (at 0 -3.81 0)
        (effects (font (size 1.27 1.27)))
      )
      (property "Footprint" "" (at 0 0 0)
        (effects (font (size 1.27 1.27)) hide)
      )
      (property "Datasheet" "" (at 0 0 0)
        (effects (font (size 1.27 1.27)) hide)
      )
      (symbol "GND_12_0_1"
        (polyline
          (pts
            (xy 0 0)
            (xy 0 -1.27)
            (xy 1.27 -1.27)
            (xy 0 -2.54)
            (xy -1.27 -1.27)
            (xy 0 -1.27)
          )
          (stroke (width 0) (type default))
          (fill (type none))
        )
      )
      (symbol "GND_12_1_1"
        (pin power_in line (at 0 0 270) (length 0) hide
          (name "GND" (effects (font (size 1.27 1.27))))
          (number "1" (effects (font (size 1.27 1.27))))
        )
      )
    )
	(symbol "data-center-rdimm-ddr4-tester:GND_13" (power) (pin_names (offset 0)) (in_bom yes) (on_board yes)
      (property "Reference" "#PWR" (at 0 -6.35 0)
        (effects (font (size 1.27 1.27)) hide)
      )
      (property "Value" "GND_13" (at 0 -3.81 0)
        (effects (font (size 1.27 1.27)))
      )
      (property "Footprint" "" (at 0 0 0)
        (effects (font (size 1.27 1.27)) hide)
      )
      (property "Datasheet" "" (at 0 0 0)
        (effects (font (size 1.27 1.27)) hide)
      )
      (symbol "GND_13_0_1"
        (polyline
          (pts
            (xy 0 0)
            (xy 0 -1.27)
            (xy 1.27 -1.27)
            (xy 0 -2.54)
            (xy -1.27 -1.27)
            (xy 0 -1.27)
          )
          (stroke (width 0) (type default))
          (fill (type none))
        )
      )
      (symbol "GND_13_1_1"
        (pin power_in line (at 0 0 270) (length 0) hide
          (name "GND" (effects (font (size 1.27 1.27))))
          (number "1" (effects (font (size 1.27 1.27))))
        )
      )
    )
	(symbol "data-center-rdimm-ddr4-tester:GND_14" (power) (pin_names (offset 0)) (in_bom yes) (on_board yes)
      (property "Reference" "#PWR" (at 0 -6.35 0)
        (effects (font (size 1.27 1.27)) hide)
      )
      (property "Value" "GND_14" (at 0 -3.81 0)
        (effects (font (size 1.27 1.27)))
      )
      (property "Footprint" "" (at 0 0 0)
        (effects (font (size 1.27 1.27)) hide)
      )
      (property "Datasheet" "" (at 0 0 0)
        (effects (font (size 1.27 1.27)) hide)
      )
      (symbol "GND_14_0_1"
        (polyline
          (pts
            (xy 0 0)
            (xy 0 -1.27)
            (xy 1.27 -1.27)
            (xy 0 -2.54)
            (xy -1.27 -1.27)
            (xy 0 -1.27)
          )
          (stroke (width 0) (type default))
          (fill (type none))
        )
      )
      (symbol "GND_14_1_1"
        (pin power_in line (at 0 0 270) (length 0) hide
          (name "GND" (effects (font (size 1.27 1.27))))
          (number "1" (effects (font (size 1.27 1.27))))
        )
      )
    )
	(symbol "data-center-rdimm-ddr4-tester:GND_15" (power) (pin_names (offset 0)) (in_bom yes) (on_board yes)
      (property "Reference" "#PWR" (at 0 -6.35 0)
        (effects (font (size 1.27 1.27)) hide)
      )
      (property "Value" "GND_15" (at 0 -3.81 0)
        (effects (font (size 1.27 1.27)))
      )
      (property "Footprint" "" (at 0 0 0)
        (effects (font (size 1.27 1.27)) hide)
      )
      (property "Datasheet" "" (at 0 0 0)
        (effects (font (size 1.27 1.27)) hide)
      )
      (symbol "GND_15_0_1"
        (polyline
          (pts
            (xy 0 0)
            (xy 0 -1.27)
            (xy 1.27 -1.27)
            (xy 0 -2.54)
            (xy -1.27 -1.27)
            (xy 0 -1.27)
          )
          (stroke (width 0) (type default))
          (fill (type none))
        )
      )
      (symbol "GND_15_1_1"
        (pin power_in line (at 0 0 270) (length 0) hide
          (name "GND" (effects (font (size 1.27 1.27))))
          (number "1" (effects (font (size 1.27 1.27))))
        )
      )
    )
	(symbol "data-center-rdimm-ddr4-tester:GND_16" (power) (pin_names (offset 0)) (in_bom yes) (on_board yes)
      (property "Reference" "#PWR" (at 0 -6.35 0)
        (effects (font (size 1.27 1.27)) hide)
      )
      (property "Value" "GND_16" (at 0 -3.81 0)
        (effects (font (size 1.27 1.27)))
      )
      (property "Footprint" "" (at 0 0 0)
        (effects (font (size 1.27 1.27)) hide)
      )
      (property "Datasheet" "" (at 0 0 0)
        (effects (font (size 1.27 1.27)) hide)
      )
      (symbol "GND_16_0_1"
        (polyline
          (pts
            (xy 0 0)
            (xy 0 -1.27)
            (xy 1.27 -1.27)
            (xy 0 -2.54)
            (xy -1.27 -1.27)
            (xy 0 -1.27)
          )
          (stroke (width 0) (type default))
          (fill (type none))
        )
      )
      (symbol "GND_16_1_1"
        (pin power_in line (at 0 0 270) (length 0) hide
          (name "GND" (effects (font (size 1.27 1.27))))
          (number "1" (effects (font (size 1.27 1.27))))
        )
      )
    )
	(symbol "data-center-rdimm-ddr4-tester:GND_17" (power) (pin_names (offset 0)) (in_bom yes) (on_board yes)
      (property "Reference" "#PWR" (at 0 -6.35 0)
        (effects (font (size 1.27 1.27)) hide)
      )
      (property "Value" "GND_17" (at 0 -3.81 0)
        (effects (font (size 1.27 1.27)))
      )
      (property "Footprint" "" (at 0 0 0)
        (effects (font (size 1.27 1.27)) hide)
      )
      (property "Datasheet" "" (at 0 0 0)
        (effects (font (size 1.27 1.27)) hide)
      )
      (symbol "GND_17_0_1"
        (polyline
          (pts
            (xy 0 0)
            (xy 0 -1.27)
            (xy 1.27 -1.27)
            (xy 0 -2.54)
            (xy -1.27 -1.27)
            (xy 0 -1.27)
          )
          (stroke (width 0) (type default))
          (fill (type none))
        )
      )
      (symbol "GND_17_1_1"
        (pin power_in line (at 0 0 270) (length 0) hide
          (name "GND" (effects (font (size 1.27 1.27))))
          (number "1" (effects (font (size 1.27 1.27))))
        )
      )
    )
	(symbol "data-center-rdimm-ddr4-tester:GND_18" (power) (pin_names (offset 0)) (in_bom yes) (on_board yes)
      (property "Reference" "#PWR" (at 0 -6.35 0)
        (effects (font (size 1.27 1.27)) hide)
      )
      (property "Value" "GND_18" (at 0 -3.81 0)
        (effects (font (size 1.27 1.27)))
      )
      (property "Footprint" "" (at 0 0 0)
        (effects (font (size 1.27 1.27)) hide)
      )
      (property "Datasheet" "" (at 0 0 0)
        (effects (font (size 1.27 1.27)) hide)
      )
      (symbol "GND_18_0_1"
        (polyline
          (pts
            (xy 0 0)
            (xy 0 -1.27)
            (xy 1.27 -1.27)
            (xy 0 -2.54)
            (xy -1.27 -1.27)
            (xy 0 -1.27)
          )
          (stroke (width 0) (type default))
          (fill (type none))
        )
      )
      (symbol "GND_18_1_1"
        (pin power_in line (at 0 0 270) (length 0) hide
          (name "GND" (effects (font (size 1.27 1.27))))
          (number "1" (effects (font (size 1.27 1.27))))
        )
      )
    )
	(symbol "data-center-rdimm-ddr4-tester:GND_19" (power) (pin_names (offset 0)) (in_bom yes) (on_board yes)
      (property "Reference" "#PWR" (at 0 -6.35 0)
        (effects (font (size 1.27 1.27)) hide)
      )
      (property "Value" "GND_19" (at 0 -3.81 0)
        (effects (font (size 1.27 1.27)))
      )
      (property "Footprint" "" (at 0 0 0)
        (effects (font (size 1.27 1.27)) hide)
      )
      (property "Datasheet" "" (at 0 0 0)
        (effects (font (size 1.27 1.27)) hide)
      )
      (symbol "GND_19_0_1"
        (polyline
          (pts
            (xy 0 0)
            (xy 0 -1.27)
            (xy 1.27 -1.27)
            (xy 0 -2.54)
            (xy -1.27 -1.27)
            (xy 0 -1.27)
          )
          (stroke (width 0) (type default))
          (fill (type none))
        )
      )
      (symbol "GND_19_1_1"
        (pin power_in line (at 0 0 270) (length 0) hide
          (name "GND" (effects (font (size 1.27 1.27))))
          (number "1" (effects (font (size 1.27 1.27))))
        )
      )
    )
	(symbol "data-center-rdimm-ddr4-tester:GND_20" (power) (pin_names (offset 0)) (in_bom yes) (on_board yes)
      (property "Reference" "#PWR" (at 0 -6.35 0)
        (effects (font (size 1.27 1.27)) hide)
      )
      (property "Value" "GND_20" (at 0 -3.81 0)
        (effects (font (size 1.27 1.27)))
      )
      (property "Footprint" "" (at 0 0 0)
        (effects (font (size 1.27 1.27)) hide)
      )
      (property "Datasheet" "" (at 0 0 0)
        (effects (font (size 1.27 1.27)) hide)
      )
      (symbol "GND_20_0_1"
        (polyline
          (pts
            (xy 0 0)
            (xy 0 -1.27)
            (xy 1.27 -1.27)
            (xy 0 -2.54)
            (xy -1.27 -1.27)
            (xy 0 -1.27)
          )
          (stroke (width 0) (type default))
          (fill (type none))
        )
      )
      (symbol "GND_20_1_1"
        (pin power_in line (at 0 0 270) (length 0) hide
          (name "GND" (effects (font (size 1.27 1.27))))
          (number "1" (effects (font (size 1.27 1.27))))
        )
      )
    )
	(symbol "data-center-rdimm-ddr4-tester:GND_21" (power) (pin_names (offset 0)) (in_bom yes) (on_board yes)
      (property "Reference" "#PWR" (at 0 -6.35 0)
        (effects (font (size 1.27 1.27)) hide)
      )
      (property "Value" "GND_21" (at 0 -3.81 0)
        (effects (font (size 1.27 1.27)))
      )
      (property "Footprint" "" (at 0 0 0)
        (effects (font (size 1.27 1.27)) hide)
      )
      (property "Datasheet" "" (at 0 0 0)
        (effects (font (size 1.27 1.27)) hide)
      )
      (symbol "GND_21_0_1"
        (polyline
          (pts
            (xy 0 0)
            (xy 0 -1.27)
            (xy 1.27 -1.27)
            (xy 0 -2.54)
            (xy -1.27 -1.27)
            (xy 0 -1.27)
          )
          (stroke (width 0) (type default))
          (fill (type none))
        )
      )
      (symbol "GND_21_1_1"
        (pin power_in line (at 0 0 270) (length 0) hide
          (name "GND" (effects (font (size 1.27 1.27))))
          (number "1" (effects (font (size 1.27 1.27))))
        )
      )
    )
	(symbol "data-center-rdimm-ddr4-tester:GND_22" (power) (pin_names (offset 0)) (in_bom yes) (on_board yes)
      (property "Reference" "#PWR" (at 0 -6.35 0)
        (effects (font (size 1.27 1.27)) hide)
      )
      (property "Value" "GND_22" (at 0 -3.81 0)
        (effects (font (size 1.27 1.27)))
      )
      (property "Footprint" "" (at 0 0 0)
        (effects (font (size 1.27 1.27)) hide)
      )
      (property "Datasheet" "" (at 0 0 0)
        (effects (font (size 1.27 1.27)) hide)
      )
      (symbol "GND_22_0_1"
        (polyline
          (pts
            (xy 0 0)
            (xy 0 -1.27)
            (xy 1.27 -1.27)
            (xy 0 -2.54)
            (xy -1.27 -1.27)
            (xy 0 -1.27)
          )
          (stroke (width 0) (type default))
          (fill (type none))
        )
      )
      (symbol "GND_22_1_1"
        (pin power_in line (at 0 0 270) (length 0) hide
          (name "GND" (effects (font (size 1.27 1.27))))
          (number "1" (effects (font (size 1.27 1.27))))
        )
      )
    )
	(symbol "data-center-rdimm-ddr4-tester:GND_23" (power) (pin_names (offset 0)) (in_bom yes) (on_board yes)
      (property "Reference" "#PWR" (at 0 -6.35 0)
        (effects (font (size 1.27 1.27)) hide)
      )
      (property "Value" "GND_23" (at 0 -3.81 0)
        (effects (font (size 1.27 1.27)))
      )
      (property "Footprint" "" (at 0 0 0)
        (effects (font (size 1.27 1.27)) hide)
      )
      (property "Datasheet" "" (at 0 0 0)
        (effects (font (size 1.27 1.27)) hide)
      )
      (symbol "GND_23_0_1"
        (polyline
          (pts
            (xy 0 0)
            (xy 0 -1.27)
            (xy 1.27 -1.27)
            (xy 0 -2.54)
            (xy -1.27 -1.27)
            (xy 0 -1.27)
          )
          (stroke (width 0) (type default))
          (fill (type none))
        )
      )
      (symbol "GND_23_1_1"
        (pin power_in line (at 0 0 270) (length 0) hide
          (name "GND" (effects (font (size 1.27 1.27))))
          (number "1" (effects (font (size 1.27 1.27))))
        )
      )
    )
	(symbol "data-center-rdimm-ddr4-tester:GND_24" (power) (pin_names (offset 0)) (in_bom yes) (on_board yes)
      (property "Reference" "#PWR" (at 0 -6.35 0)
        (effects (font (size 1.27 1.27)) hide)
      )
      (property "Value" "GND_24" (at 0 -3.81 0)
        (effects (font (size 1.27 1.27)))
      )
      (property "Footprint" "" (at 0 0 0)
        (effects (font (size 1.27 1.27)) hide)
      )
      (property "Datasheet" "" (at 0 0 0)
        (effects (font (size 1.27 1.27)) hide)
      )
      (symbol "GND_24_0_1"
        (polyline
          (pts
            (xy 0 0)
            (xy 0 -1.27)
            (xy 1.27 -1.27)
            (xy 0 -2.54)
            (xy -1.27 -1.27)
            (xy 0 -1.27)
          )
          (stroke (width 0) (type default))
          (fill (type none))
        )
      )
      (symbol "GND_24_1_1"
        (pin power_in line (at 0 0 270) (length 0) hide
          (name "GND" (effects (font (size 1.27 1.27))))
          (number "1" (effects (font (size 1.27 1.27))))
        )
      )
    )
	(symbol "data-center-rdimm-ddr4-tester:GND_25" (power) (pin_names (offset 0)) (in_bom yes) (on_board yes)
      (property "Reference" "#PWR" (at 0 -6.35 0)
        (effects (font (size 1.27 1.27)) hide)
      )
      (property "Value" "GND_25" (at 0 -3.81 0)
        (effects (font (size 1.27 1.27)))
      )
      (property "Footprint" "" (at 0 0 0)
        (effects (font (size 1.27 1.27)) hide)
      )
      (property "Datasheet" "" (at 0 0 0)
        (effects (font (size 1.27 1.27)) hide)
      )
      (symbol "GND_25_0_1"
        (polyline
          (pts
            (xy 0 0)
            (xy 0 -1.27)
            (xy 1.27 -1.27)
            (xy 0 -2.54)
            (xy -1.27 -1.27)
            (xy 0 -1.27)
          )
          (stroke (width 0) (type default))
          (fill (type none))
        )
      )
      (symbol "GND_25_1_1"
        (pin power_in line (at 0 0 270) (length 0) hide
          (name "GND" (effects (font (size 1.27 1.27))))
          (number "1" (effects (font (size 1.27 1.27))))
        )
      )
    )
	(symbol "data-center-rdimm-ddr4-tester:GND_26" (power) (pin_names (offset 0)) (in_bom yes) (on_board yes)
      (property "Reference" "#PWR" (at 0 -6.35 0)
        (effects (font (size 1.27 1.27)) hide)
      )
      (property "Value" "GND_26" (at 0 -3.81 0)
        (effects (font (size 1.27 1.27)))
      )
      (property "Footprint" "" (at 0 0 0)
        (effects (font (size 1.27 1.27)) hide)
      )
      (property "Datasheet" "" (at 0 0 0)
        (effects (font (size 1.27 1.27)) hide)
      )
      (symbol "GND_26_0_1"
        (polyline
          (pts
            (xy 0 0)
            (xy 0 -1.27)
            (xy 1.27 -1.27)
            (xy 0 -2.54)
            (xy -1.27 -1.27)
            (xy 0 -1.27)
          )
          (stroke (width 0) (type default))
          (fill (type none))
        )
      )
      (symbol "GND_26_1_1"
        (pin power_in line (at 0 0 270) (length 0) hide
          (name "GND" (effects (font (size 1.27 1.27))))
          (number "1" (effects (font (size 1.27 1.27))))
        )
      )
    )
	(symbol "data-center-rdimm-ddr4-tester:GND_27" (power) (pin_names (offset 0)) (in_bom yes) (on_board yes)
      (property "Reference" "#PWR" (at 0 -6.35 0)
        (effects (font (size 1.27 1.27)) hide)
      )
      (property "Value" "GND_27" (at 0 -3.81 0)
        (effects (font (size 1.27 1.27)))
      )
      (property "Footprint" "" (at 0 0 0)
        (effects (font (size 1.27 1.27)) hide)
      )
      (property "Datasheet" "" (at 0 0 0)
        (effects (font (size 1.27 1.27)) hide)
      )
      (symbol "GND_27_0_1"
        (polyline
          (pts
            (xy 0 0)
            (xy 0 -1.27)
            (xy 1.27 -1.27)
            (xy 0 -2.54)
            (xy -1.27 -1.27)
            (xy 0 -1.27)
          )
          (stroke (width 0) (type default))
          (fill (type none))
        )
      )
      (symbol "GND_27_1_1"
        (pin power_in line (at 0 0 270) (length 0) hide
          (name "GND" (effects (font (size 1.27 1.27))))
          (number "1" (effects (font (size 1.27 1.27))))
        )
      )
    )
	(symbol "data-center-rdimm-ddr4-tester:GND_28" (power) (pin_names (offset 0)) (in_bom yes) (on_board yes)
      (property "Reference" "#PWR" (at 0 -6.35 0)
        (effects (font (size 1.27 1.27)) hide)
      )
      (property "Value" "GND_28" (at 0 -3.81 0)
        (effects (font (size 1.27 1.27)))
      )
      (property "Footprint" "" (at 0 0 0)
        (effects (font (size 1.27 1.27)) hide)
      )
      (property "Datasheet" "" (at 0 0 0)
        (effects (font (size 1.27 1.27)) hide)
      )
      (symbol "GND_28_0_1"
        (polyline
          (pts
            (xy 0 0)
            (xy 0 -1.27)
            (xy 1.27 -1.27)
            (xy 0 -2.54)
            (xy -1.27 -1.27)
            (xy 0 -1.27)
          )
          (stroke (width 0) (type default))
          (fill (type none))
        )
      )
      (symbol "GND_28_1_1"
        (pin power_in line (at 0 0 270) (length 0) hide
          (name "GND" (effects (font (size 1.27 1.27))))
          (number "1" (effects (font (size 1.27 1.27))))
        )
      )
    )
	(symbol "data-center-rdimm-ddr4-tester:GND_29" (power) (pin_names (offset 0)) (in_bom yes) (on_board yes)
      (property "Reference" "#PWR" (at 0 -6.35 0)
        (effects (font (size 1.27 1.27)) hide)
      )
      (property "Value" "GND_29" (at 0 -3.81 0)
        (effects (font (size 1.27 1.27)))
      )
      (property "Footprint" "" (at 0 0 0)
        (effects (font (size 1.27 1.27)) hide)
      )
      (property "Datasheet" "" (at 0 0 0)
        (effects (font (size 1.27 1.27)) hide)
      )
      (symbol "GND_29_0_1"
        (polyline
          (pts
            (xy 0 0)
            (xy 0 -1.27)
            (xy 1.27 -1.27)
            (xy 0 -2.54)
            (xy -1.27 -1.27)
            (xy 0 -1.27)
          )
          (stroke (width 0) (type default))
          (fill (type none))
        )
      )
      (symbol "GND_29_1_1"
        (pin power_in line (at 0 0 270) (length 0) hide
          (name "GND" (effects (font (size 1.27 1.27))))
          (number "1" (effects (font (size 1.27 1.27))))
        )
      )
    )
	(symbol "data-center-rdimm-ddr4-tester:GND_30" (power) (pin_names (offset 0)) (in_bom yes) (on_board yes)
      (property "Reference" "#PWR" (at 0 -6.35 0)
        (effects (font (size 1.27 1.27)) hide)
      )
      (property "Value" "GND_30" (at 0 -3.81 0)
        (effects (font (size 1.27 1.27)))
      )
      (property "Footprint" "" (at 0 0 0)
        (effects (font (size 1.27 1.27)) hide)
      )
      (property "Datasheet" "" (at 0 0 0)
        (effects (font (size 1.27 1.27)) hide)
      )
      (symbol "GND_30_0_1"
        (polyline
          (pts
            (xy 0 0)
            (xy 0 -1.27)
            (xy 1.27 -1.27)
            (xy 0 -2.54)
            (xy -1.27 -1.27)
            (xy 0 -1.27)
          )
          (stroke (width 0) (type default))
          (fill (type none))
        )
      )
      (symbol "GND_30_1_1"
        (pin power_in line (at 0 0 270) (length 0) hide
          (name "GND" (effects (font (size 1.27 1.27))))
          (number "1" (effects (font (size 1.27 1.27))))
        )
      )
    )
	(symbol "data-center-rdimm-ddr4-tester:GND_31" (power) (pin_names (offset 0)) (in_bom yes) (on_board yes)
      (property "Reference" "#PWR" (at 0 -6.35 0)
        (effects (font (size 1.27 1.27)) hide)
      )
      (property "Value" "GND_31" (at 0 -3.81 0)
        (effects (font (size 1.27 1.27)))
      )
      (property "Footprint" "" (at 0 0 0)
        (effects (font (size 1.27 1.27)) hide)
      )
      (property "Datasheet" "" (at 0 0 0)
        (effects (font (size 1.27 1.27)) hide)
      )
      (symbol "GND_31_0_1"
        (polyline
          (pts
            (xy 0 0)
            (xy 0 -1.27)
            (xy 1.27 -1.27)
            (xy 0 -2.54)
            (xy -1.27 -1.27)
            (xy 0 -1.27)
          )
          (stroke (width 0) (type default))
          (fill (type none))
        )
      )
      (symbol "GND_31_1_1"
        (pin power_in line (at 0 0 270) (length 0) hide
          (name "GND" (effects (font (size 1.27 1.27))))
          (number "1" (effects (font (size 1.27 1.27))))
        )
      )
    )
	(symbol "data-center-rdimm-ddr4-tester:GND_32" (power) (pin_names (offset 0)) (in_bom yes) (on_board yes)
      (property "Reference" "#PWR" (at 0 -6.35 0)
        (effects (font (size 1.27 1.27)) hide)
      )
      (property "Value" "GND_32" (at 0 -3.81 0)
        (effects (font (size 1.27 1.27)))
      )
      (property "Footprint" "" (at 0 0 0)
        (effects (font (size 1.27 1.27)) hide)
      )
      (property "Datasheet" "" (at 0 0 0)
        (effects (font (size 1.27 1.27)) hide)
      )
      (symbol "GND_32_0_1"
        (polyline
          (pts
            (xy 0 0)
            (xy 0 -1.27)
            (xy 1.27 -1.27)
            (xy 0 -2.54)
            (xy -1.27 -1.27)
            (xy 0 -1.27)
          )
          (stroke (width 0) (type default))
          (fill (type none))
        )
      )
      (symbol "GND_32_1_1"
        (pin power_in line (at 0 0 270) (length 0) hide
          (name "GND" (effects (font (size 1.27 1.27))))
          (number "1" (effects (font (size 1.27 1.27))))
        )
      )
    )
	(symbol "data-center-rdimm-ddr4-tester:GND_33" (power) (pin_names (offset 0)) (in_bom yes) (on_board yes)
      (property "Reference" "#PWR" (at 0 -6.35 0)
        (effects (font (size 1.27 1.27)) hide)
      )
      (property "Value" "GND_33" (at 0 -3.81 0)
        (effects (font (size 1.27 1.27)))
      )
      (property "Footprint" "" (at 0 0 0)
        (effects (font (size 1.27 1.27)) hide)
      )
      (property "Datasheet" "" (at 0 0 0)
        (effects (font (size 1.27 1.27)) hide)
      )
      (symbol "GND_33_0_1"
        (polyline
          (pts
            (xy 0 0)
            (xy 0 -1.27)
            (xy 1.27 -1.27)
            (xy 0 -2.54)
            (xy -1.27 -1.27)
            (xy 0 -1.27)
          )
          (stroke (width 0) (type default))
          (fill (type none))
        )
      )
      (symbol "GND_33_1_1"
        (pin power_in line (at 0 0 270) (length 0) hide
          (name "GND" (effects (font (size 1.27 1.27))))
          (number "1" (effects (font (size 1.27 1.27))))
        )
      )
    )
	(symbol "data-center-rdimm-ddr4-tester:GND_34" (power) (pin_names (offset 0)) (in_bom yes) (on_board yes)
      (property "Reference" "#PWR" (at 0 -6.35 0)
        (effects (font (size 1.27 1.27)) hide)
      )
      (property "Value" "GND_34" (at 0 -3.81 0)
        (effects (font (size 1.27 1.27)))
      )
      (property "Footprint" "" (at 0 0 0)
        (effects (font (size 1.27 1.27)) hide)
      )
      (property "Datasheet" "" (at 0 0 0)
        (effects (font (size 1.27 1.27)) hide)
      )
      (symbol "GND_34_0_1"
        (polyline
          (pts
            (xy 0 0)
            (xy 0 -1.27)
            (xy 1.27 -1.27)
            (xy 0 -2.54)
            (xy -1.27 -1.27)
            (xy 0 -1.27)
          )
          (stroke (width 0) (type default))
          (fill (type none))
        )
      )
      (symbol "GND_34_1_1"
        (pin power_in line (at 0 0 270) (length 0) hide
          (name "GND" (effects (font (size 1.27 1.27))))
          (number "1" (effects (font (size 1.27 1.27))))
        )
      )
    )
	(symbol "data-center-rdimm-ddr4-tester:GND_36" (power) (pin_names (offset 0)) (in_bom yes) (on_board yes)
      (property "Reference" "#PWR" (at 0 -6.35 0)
        (effects (font (size 1.27 1.27)) hide)
      )
      (property "Value" "GND_36" (at 0 -3.81 0)
        (effects (font (size 1.27 1.27)))
      )
      (property "Footprint" "" (at 0 0 0)
        (effects (font (size 1.27 1.27)) hide)
      )
      (property "Datasheet" "" (at 0 0 0)
        (effects (font (size 1.27 1.27)) hide)
      )
      (symbol "GND_36_0_1"
        (polyline
          (pts
            (xy 0 0)
            (xy 0 -1.27)
            (xy 1.27 -1.27)
            (xy 0 -2.54)
            (xy -1.27 -1.27)
            (xy 0 -1.27)
          )
          (stroke (width 0) (type default))
          (fill (type none))
        )
      )
      (symbol "GND_36_1_1"
        (pin power_in line (at 0 0 270) (length 0) hide
          (name "GND" (effects (font (size 1.27 1.27))))
          (number "1" (effects (font (size 1.27 1.27))))
        )
      )
    )
	(symbol "data-center-rdimm-ddr4-tester:GND_37" (power) (pin_names (offset 0)) (in_bom yes) (on_board yes)
      (property "Reference" "#PWR" (at 0 -6.35 0)
        (effects (font (size 1.27 1.27)) hide)
      )
      (property "Value" "GND_37" (at 0 -3.81 0)
        (effects (font (size 1.27 1.27)))
      )
      (property "Footprint" "" (at 0 0 0)
        (effects (font (size 1.27 1.27)) hide)
      )
      (property "Datasheet" "" (at 0 0 0)
        (effects (font (size 1.27 1.27)) hide)
      )
      (symbol "GND_37_0_1"
        (polyline
          (pts
            (xy 0 0)
            (xy 0 -1.27)
            (xy 1.27 -1.27)
            (xy 0 -2.54)
            (xy -1.27 -1.27)
            (xy 0 -1.27)
          )
          (stroke (width 0) (type default))
          (fill (type none))
        )
      )
      (symbol "GND_37_1_1"
        (pin power_in line (at 0 0 270) (length 0) hide
          (name "GND" (effects (font (size 1.27 1.27))))
          (number "1" (effects (font (size 1.27 1.27))))
        )
      )
    )
	(symbol "data-center-rdimm-ddr4-tester:GND_38" (power) (pin_names (offset 0)) (in_bom yes) (on_board yes)
      (property "Reference" "#PWR" (at 0 -6.35 0)
        (effects (font (size 1.27 1.27)) hide)
      )
      (property "Value" "GND_38" (at 0 -3.81 0)
        (effects (font (size 1.27 1.27)))
      )
      (property "Footprint" "" (at 0 0 0)
        (effects (font (size 1.27 1.27)) hide)
      )
      (property "Datasheet" "" (at 0 0 0)
        (effects (font (size 1.27 1.27)) hide)
      )
      (symbol "GND_38_0_1"
        (polyline
          (pts
            (xy 0 0)
            (xy 0 -1.27)
            (xy 1.27 -1.27)
            (xy 0 -2.54)
            (xy -1.27 -1.27)
            (xy 0 -1.27)
          )
          (stroke (width 0) (type default))
          (fill (type none))
        )
      )
      (symbol "GND_38_1_1"
        (pin power_in line (at 0 0 270) (length 0) hide
          (name "GND" (effects (font (size 1.27 1.27))))
          (number "1" (effects (font (size 1.27 1.27))))
        )
      )
    )
	(symbol "data-center-rdimm-ddr4-tester:GND_39" (power) (pin_names (offset 0)) (in_bom yes) (on_board yes)
      (property "Reference" "#PWR" (at 0 -6.35 0)
        (effects (font (size 1.27 1.27)) hide)
      )
      (property "Value" "GND_39" (at 0 -3.81 0)
        (effects (font (size 1.27 1.27)))
      )
      (property "Footprint" "" (at 0 0 0)
        (effects (font (size 1.27 1.27)) hide)
      )
      (property "Datasheet" "" (at 0 0 0)
        (effects (font (size 1.27 1.27)) hide)
      )
      (symbol "GND_39_0_1"
        (polyline
          (pts
            (xy 0 0)
            (xy 0 -1.27)
            (xy 1.27 -1.27)
            (xy 0 -2.54)
            (xy -1.27 -1.27)
            (xy 0 -1.27)
          )
          (stroke (width 0) (type default))
          (fill (type none))
        )
      )
      (symbol "GND_39_1_1"
        (pin power_in line (at 0 0 270) (length 0) hide
          (name "GND" (effects (font (size 1.27 1.27))))
          (number "1" (effects (font (size 1.27 1.27))))
        )
      )
    )
	(symbol "data-center-rdimm-ddr4-tester:GND_40" (power) (pin_names (offset 0)) (in_bom yes) (on_board yes)
      (property "Reference" "#PWR" (at 0 -6.35 0)
        (effects (font (size 1.27 1.27)) hide)
      )
      (property "Value" "GND_40" (at 0 -3.81 0)
        (effects (font (size 1.27 1.27)))
      )
      (property "Footprint" "" (at 0 0 0)
        (effects (font (size 1.27 1.27)) hide)
      )
      (property "Datasheet" "" (at 0 0 0)
        (effects (font (size 1.27 1.27)) hide)
      )
      (symbol "GND_40_0_1"
        (polyline
          (pts
            (xy 0 0)
            (xy 0 -1.27)
            (xy 1.27 -1.27)
            (xy 0 -2.54)
            (xy -1.27 -1.27)
            (xy 0 -1.27)
          )
          (stroke (width 0) (type default))
          (fill (type none))
        )
      )
      (symbol "GND_40_1_1"
        (pin power_in line (at 0 0 270) (length 0) hide
          (name "GND" (effects (font (size 1.27 1.27))))
          (number "1" (effects (font (size 1.27 1.27))))
        )
      )
    )
	(symbol "data-center-rdimm-ddr4-tester:GND_41" (power) (pin_names (offset 0)) (in_bom yes) (on_board yes)
      (property "Reference" "#PWR" (at 0 -6.35 0)
        (effects (font (size 1.27 1.27)) hide)
      )
      (property "Value" "GND_41" (at 0 -3.81 0)
        (effects (font (size 1.27 1.27)))
      )
      (property "Footprint" "" (at 0 0 0)
        (effects (font (size 1.27 1.27)) hide)
      )
      (property "Datasheet" "" (at 0 0 0)
        (effects (font (size 1.27 1.27)) hide)
      )
      (symbol "GND_41_0_1"
        (polyline
          (pts
            (xy 0 0)
            (xy 0 -1.27)
            (xy 1.27 -1.27)
            (xy 0 -2.54)
            (xy -1.27 -1.27)
            (xy 0 -1.27)
          )
          (stroke (width 0) (type default))
          (fill (type none))
        )
      )
      (symbol "GND_41_1_1"
        (pin power_in line (at 0 0 270) (length 0) hide
          (name "GND" (effects (font (size 1.27 1.27))))
          (number "1" (effects (font (size 1.27 1.27))))
        )
      )
    )
	(symbol "data-center-rdimm-ddr4-tester:GND_42" (power) (pin_names (offset 0)) (in_bom yes) (on_board yes)
      (property "Reference" "#PWR" (at 0 -6.35 0)
        (effects (font (size 1.27 1.27)) hide)
      )
      (property "Value" "GND_42" (at 0 -3.81 0)
        (effects (font (size 1.27 1.27)))
      )
      (property "Footprint" "" (at 0 0 0)
        (effects (font (size 1.27 1.27)) hide)
      )
      (property "Datasheet" "" (at 0 0 0)
        (effects (font (size 1.27 1.27)) hide)
      )
      (symbol "GND_42_0_1"
        (polyline
          (pts
            (xy 0 0)
            (xy 0 -1.27)
            (xy 1.27 -1.27)
            (xy 0 -2.54)
            (xy -1.27 -1.27)
            (xy 0 -1.27)
          )
          (stroke (width 0) (type default))
          (fill (type none))
        )
      )
      (symbol "GND_42_1_1"
        (pin power_in line (at 0 0 270) (length 0) hide
          (name "GND" (effects (font (size 1.27 1.27))))
          (number "1" (effects (font (size 1.27 1.27))))
        )
      )
    )
	(symbol "data-center-rdimm-ddr4-tester:GND_43" (power) (pin_names (offset 0)) (in_bom yes) (on_board yes)
      (property "Reference" "#PWR" (at 0 -6.35 0)
        (effects (font (size 1.27 1.27)) hide)
      )
      (property "Value" "GND_43" (at 0 -3.81 0)
        (effects (font (size 1.27 1.27)))
      )
      (property "Footprint" "" (at 0 0 0)
        (effects (font (size 1.27 1.27)) hide)
      )
      (property "Datasheet" "" (at 0 0 0)
        (effects (font (size 1.27 1.27)) hide)
      )
      (symbol "GND_43_0_1"
        (polyline
          (pts
            (xy 0 0)
            (xy 0 -1.27)
            (xy 1.27 -1.27)
            (xy 0 -2.54)
            (xy -1.27 -1.27)
            (xy 0 -1.27)
          )
          (stroke (width 0) (type default))
          (fill (type none))
        )
      )
      (symbol "GND_43_1_1"
        (pin power_in line (at 0 0 270) (length 0) hide
          (name "GND" (effects (font (size 1.27 1.27))))
          (number "1" (effects (font (size 1.27 1.27))))
        )
      )
    )
	(symbol "data-center-rdimm-ddr4-tester:GND_44" (power) (pin_names (offset 0)) (in_bom yes) (on_board yes)
      (property "Reference" "#PWR" (at 0 -6.35 0)
        (effects (font (size 1.27 1.27)) hide)
      )
      (property "Value" "GND_44" (at 0 -3.81 0)
        (effects (font (size 1.27 1.27)))
      )
      (property "Footprint" "" (at 0 0 0)
        (effects (font (size 1.27 1.27)) hide)
      )
      (property "Datasheet" "" (at 0 0 0)
        (effects (font (size 1.27 1.27)) hide)
      )
      (symbol "GND_44_0_1"
        (polyline
          (pts
            (xy 0 0)
            (xy 0 -1.27)
            (xy 1.27 -1.27)
            (xy 0 -2.54)
            (xy -1.27 -1.27)
            (xy 0 -1.27)
          )
          (stroke (width 0) (type default))
          (fill (type none))
        )
      )
      (symbol "GND_44_1_1"
        (pin power_in line (at 0 0 270) (length 0) hide
          (name "GND" (effects (font (size 1.27 1.27))))
          (number "1" (effects (font (size 1.27 1.27))))
        )
      )
    )
	(symbol "data-center-rdimm-ddr4-tester:GND_46" (power) (pin_names (offset 0)) (in_bom yes) (on_board yes)
      (property "Reference" "#PWR" (at 0 -6.35 0)
        (effects (font (size 1.27 1.27)) hide)
      )
      (property "Value" "GND_46" (at 0 -3.81 0)
        (effects (font (size 1.27 1.27)))
      )
      (property "Footprint" "" (at 0 0 0)
        (effects (font (size 1.27 1.27)) hide)
      )
      (property "Datasheet" "" (at 0 0 0)
        (effects (font (size 1.27 1.27)) hide)
      )
      (symbol "GND_46_0_1"
        (polyline
          (pts
            (xy 0 0)
            (xy 0 -1.27)
            (xy 1.27 -1.27)
            (xy 0 -2.54)
            (xy -1.27 -1.27)
            (xy 0 -1.27)
          )
          (stroke (width 0) (type default))
          (fill (type none))
        )
      )
      (symbol "GND_46_1_1"
        (pin power_in line (at 0 0 270) (length 0) hide
          (name "GND" (effects (font (size 1.27 1.27))))
          (number "1" (effects (font (size 1.27 1.27))))
        )
      )
    )
	(symbol "data-center-rdimm-ddr4-tester:GND_47" (power) (pin_names (offset 0)) (in_bom yes) (on_board yes)
      (property "Reference" "#PWR" (at 0 -6.35 0)
        (effects (font (size 1.27 1.27)) hide)
      )
      (property "Value" "GND_47" (at 0 -3.81 0)
        (effects (font (size 1.27 1.27)))
      )
      (property "Footprint" "" (at 0 0 0)
        (effects (font (size 1.27 1.27)) hide)
      )
      (property "Datasheet" "" (at 0 0 0)
        (effects (font (size 1.27 1.27)) hide)
      )
      (symbol "GND_47_0_1"
        (polyline
          (pts
            (xy 0 0)
            (xy 0 -1.27)
            (xy 1.27 -1.27)
            (xy 0 -2.54)
            (xy -1.27 -1.27)
            (xy 0 -1.27)
          )
          (stroke (width 0) (type default))
          (fill (type none))
        )
      )
      (symbol "GND_47_1_1"
        (pin power_in line (at 0 0 270) (length 0) hide
          (name "GND" (effects (font (size 1.27 1.27))))
          (number "1" (effects (font (size 1.27 1.27))))
        )
      )
    )
	(symbol "data-center-rdimm-ddr4-tester:GND_48" (power) (pin_names (offset 0)) (in_bom yes) (on_board yes)
      (property "Reference" "#PWR" (at 0 -6.35 0)
        (effects (font (size 1.27 1.27)) hide)
      )
      (property "Value" "GND_48" (at 0 -3.81 0)
        (effects (font (size 1.27 1.27)))
      )
      (property "Footprint" "" (at 0 0 0)
        (effects (font (size 1.27 1.27)) hide)
      )
      (property "Datasheet" "" (at 0 0 0)
        (effects (font (size 1.27 1.27)) hide)
      )
      (symbol "GND_48_0_1"
        (polyline
          (pts
            (xy 0 0)
            (xy 0 -1.27)
            (xy 1.27 -1.27)
            (xy 0 -2.54)
            (xy -1.27 -1.27)
            (xy 0 -1.27)
          )
          (stroke (width 0) (type default))
          (fill (type none))
        )
      )
      (symbol "GND_48_1_1"
        (pin power_in line (at 0 0 270) (length 0) hide
          (name "GND" (effects (font (size 1.27 1.27))))
          (number "1" (effects (font (size 1.27 1.27))))
        )
      )
    )
	(symbol "data-center-rdimm-ddr4-tester:GND_49" (power) (pin_names (offset 0)) (in_bom yes) (on_board yes)
      (property "Reference" "#PWR" (at 0 -6.35 0)
        (effects (font (size 1.27 1.27)) hide)
      )
      (property "Value" "GND_49" (at 0 -3.81 0)
        (effects (font (size 1.27 1.27)))
      )
      (property "Footprint" "" (at 0 0 0)
        (effects (font (size 1.27 1.27)) hide)
      )
      (property "Datasheet" "" (at 0 0 0)
        (effects (font (size 1.27 1.27)) hide)
      )
      (symbol "GND_49_0_1"
        (polyline
          (pts
            (xy 0 0)
            (xy 0 -1.27)
            (xy 1.27 -1.27)
            (xy 0 -2.54)
            (xy -1.27 -1.27)
            (xy 0 -1.27)
          )
          (stroke (width 0) (type default))
          (fill (type none))
        )
      )
      (symbol "GND_49_1_1"
        (pin power_in line (at 0 0 270) (length 0) hide
          (name "GND" (effects (font (size 1.27 1.27))))
          (number "1" (effects (font (size 1.27 1.27))))
        )
      )
    )
	(symbol "data-center-rdimm-ddr4-tester:GND_50" (power) (pin_names (offset 0)) (in_bom yes) (on_board yes)
      (property "Reference" "#PWR" (at 0 -6.35 0)
        (effects (font (size 1.27 1.27)) hide)
      )
      (property "Value" "GND_50" (at 0 -3.81 0)
        (effects (font (size 1.27 1.27)))
      )
      (property "Footprint" "" (at 0 0 0)
        (effects (font (size 1.27 1.27)) hide)
      )
      (property "Datasheet" "" (at 0 0 0)
        (effects (font (size 1.27 1.27)) hide)
      )
      (symbol "GND_50_0_1"
        (polyline
          (pts
            (xy 0 0)
            (xy 0 -1.27)
            (xy 1.27 -1.27)
            (xy 0 -2.54)
            (xy -1.27 -1.27)
            (xy 0 -1.27)
          )
          (stroke (width 0) (type default))
          (fill (type none))
        )
      )
      (symbol "GND_50_1_1"
        (pin power_in line (at 0 0 270) (length 0) hide
          (name "GND" (effects (font (size 1.27 1.27))))
          (number "1" (effects (font (size 1.27 1.27))))
        )
      )
    )
	(symbol "data-center-rdimm-ddr4-tester:GND_51" (power) (pin_names (offset 0)) (in_bom yes) (on_board yes)
      (property "Reference" "#PWR" (at 0 -6.35 0)
        (effects (font (size 1.27 1.27)) hide)
      )
      (property "Value" "GND_51" (at 0 -3.81 0)
        (effects (font (size 1.27 1.27)))
      )
      (property "Footprint" "" (at 0 0 0)
        (effects (font (size 1.27 1.27)) hide)
      )
      (property "Datasheet" "" (at 0 0 0)
        (effects (font (size 1.27 1.27)) hide)
      )
      (symbol "GND_51_0_1"
        (polyline
          (pts
            (xy 0 0)
            (xy 0 -1.27)
            (xy 1.27 -1.27)
            (xy 0 -2.54)
            (xy -1.27 -1.27)
            (xy 0 -1.27)
          )
          (stroke (width 0) (type default))
          (fill (type none))
        )
      )
      (symbol "GND_51_1_1"
        (pin power_in line (at 0 0 270) (length 0) hide
          (name "GND" (effects (font (size 1.27 1.27))))
          (number "1" (effects (font (size 1.27 1.27))))
        )
      )
    )
	(symbol "data-center-rdimm-ddr4-tester:GND_52" (power) (pin_names (offset 0)) (in_bom yes) (on_board yes)
      (property "Reference" "#PWR" (at 0 -6.35 0)
        (effects (font (size 1.27 1.27)) hide)
      )
      (property "Value" "GND_52" (at 0 -3.81 0)
        (effects (font (size 1.27 1.27)))
      )
      (property "Footprint" "" (at 0 0 0)
        (effects (font (size 1.27 1.27)) hide)
      )
      (property "Datasheet" "" (at 0 0 0)
        (effects (font (size 1.27 1.27)) hide)
      )
      (symbol "GND_52_0_1"
        (polyline
          (pts
            (xy 0 0)
            (xy 0 -1.27)
            (xy 1.27 -1.27)
            (xy 0 -2.54)
            (xy -1.27 -1.27)
            (xy 0 -1.27)
          )
          (stroke (width 0) (type default))
          (fill (type none))
        )
      )
      (symbol "GND_52_1_1"
        (pin power_in line (at 0 0 270) (length 0) hide
          (name "GND" (effects (font (size 1.27 1.27))))
          (number "1" (effects (font (size 1.27 1.27))))
        )
      )
    )
	(symbol "data-center-rdimm-ddr4-tester:GND_53" (power) (pin_names (offset 0)) (in_bom yes) (on_board yes)
      (property "Reference" "#PWR" (at 0 -6.35 0)
        (effects (font (size 1.27 1.27)) hide)
      )
      (property "Value" "GND_53" (at 0 -3.81 0)
        (effects (font (size 1.27 1.27)))
      )
      (property "Footprint" "" (at 0 0 0)
        (effects (font (size 1.27 1.27)) hide)
      )
      (property "Datasheet" "" (at 0 0 0)
        (effects (font (size 1.27 1.27)) hide)
      )
      (symbol "GND_53_0_1"
        (polyline
          (pts
            (xy 0 0)
            (xy 0 -1.27)
            (xy 1.27 -1.27)
            (xy 0 -2.54)
            (xy -1.27 -1.27)
            (xy 0 -1.27)
          )
          (stroke (width 0) (type default))
          (fill (type none))
        )
      )
      (symbol "GND_53_1_1"
        (pin power_in line (at 0 0 270) (length 0) hide
          (name "GND" (effects (font (size 1.27 1.27))))
          (number "1" (effects (font (size 1.27 1.27))))
        )
      )
    )
	(symbol "data-center-rdimm-ddr4-tester:GND_54" (power) (pin_names (offset 0)) (in_bom yes) (on_board yes)
      (property "Reference" "#PWR" (at 0 -6.35 0)
        (effects (font (size 1.27 1.27)) hide)
      )
      (property "Value" "GND_54" (at 0 -3.81 0)
        (effects (font (size 1.27 1.27)))
      )
      (property "Footprint" "" (at 0 0 0)
        (effects (font (size 1.27 1.27)) hide)
      )
      (property "Datasheet" "" (at 0 0 0)
        (effects (font (size 1.27 1.27)) hide)
      )
      (symbol "GND_54_0_1"
        (polyline
          (pts
            (xy 0 0)
            (xy 0 -1.27)
            (xy 1.27 -1.27)
            (xy 0 -2.54)
            (xy -1.27 -1.27)
            (xy 0 -1.27)
          )
          (stroke (width 0) (type default))
          (fill (type none))
        )
      )
      (symbol "GND_54_1_1"
        (pin power_in line (at 0 0 270) (length 0) hide
          (name "GND" (effects (font (size 1.27 1.27))))
          (number "1" (effects (font (size 1.27 1.27))))
        )
      )
    )
	(symbol "data-center-rdimm-ddr4-tester:GND_55" (power) (pin_names (offset 0)) (in_bom yes) (on_board yes)
      (property "Reference" "#PWR" (at 0 -6.35 0)
        (effects (font (size 1.27 1.27)) hide)
      )
      (property "Value" "GND_55" (at 0 -3.81 0)
        (effects (font (size 1.27 1.27)))
      )
      (property "Footprint" "" (at 0 0 0)
        (effects (font (size 1.27 1.27)) hide)
      )
      (property "Datasheet" "" (at 0 0 0)
        (effects (font (size 1.27 1.27)) hide)
      )
      (symbol "GND_55_0_1"
        (polyline
          (pts
            (xy 0 0)
            (xy 0 -1.27)
            (xy 1.27 -1.27)
            (xy 0 -2.54)
            (xy -1.27 -1.27)
            (xy 0 -1.27)
          )
          (stroke (width 0) (type default))
          (fill (type none))
        )
      )
      (symbol "GND_55_1_1"
        (pin power_in line (at 0 0 270) (length 0) hide
          (name "GND" (effects (font (size 1.27 1.27))))
          (number "1" (effects (font (size 1.27 1.27))))
        )
      )
    )
	(symbol "data-center-rdimm-ddr4-tester:GND_56" (power) (pin_names (offset 0)) (in_bom yes) (on_board yes)
      (property "Reference" "#PWR" (at 0 -6.35 0)
        (effects (font (size 1.27 1.27)) hide)
      )
      (property "Value" "GND_56" (at 0 -3.81 0)
        (effects (font (size 1.27 1.27)))
      )
      (property "Footprint" "" (at 0 0 0)
        (effects (font (size 1.27 1.27)) hide)
      )
      (property "Datasheet" "" (at 0 0 0)
        (effects (font (size 1.27 1.27)) hide)
      )
      (symbol "GND_56_0_1"
        (polyline
          (pts
            (xy 0 0)
            (xy 0 -1.27)
            (xy 1.27 -1.27)
            (xy 0 -2.54)
            (xy -1.27 -1.27)
            (xy 0 -1.27)
          )
          (stroke (width 0) (type default))
          (fill (type none))
        )
      )
      (symbol "GND_56_1_1"
        (pin power_in line (at 0 0 270) (length 0) hide
          (name "GND" (effects (font (size 1.27 1.27))))
          (number "1" (effects (font (size 1.27 1.27))))
        )
      )
    )
	(symbol "data-center-rdimm-ddr4-tester:GND_57" (power) (pin_names (offset 0)) (in_bom yes) (on_board yes)
      (property "Reference" "#PWR" (at 0 -6.35 0)
        (effects (font (size 1.27 1.27)) hide)
      )
      (property "Value" "GND_57" (at 0 -3.81 0)
        (effects (font (size 1.27 1.27)))
      )
      (property "Footprint" "" (at 0 0 0)
        (effects (font (size 1.27 1.27)) hide)
      )
      (property "Datasheet" "" (at 0 0 0)
        (effects (font (size 1.27 1.27)) hide)
      )
      (symbol "GND_57_0_1"
        (polyline
          (pts
            (xy 0 0)
            (xy 0 -1.27)
            (xy 1.27 -1.27)
            (xy 0 -2.54)
            (xy -1.27 -1.27)
            (xy 0 -1.27)
          )
          (stroke (width 0) (type default))
          (fill (type none))
        )
      )
      (symbol "GND_57_1_1"
        (pin power_in line (at 0 0 270) (length 0) hide
          (name "GND" (effects (font (size 1.27 1.27))))
          (number "1" (effects (font (size 1.27 1.27))))
        )
      )
    )
	(symbol "data-center-rdimm-ddr4-tester:GND_58" (power) (pin_names (offset 0)) (in_bom yes) (on_board yes)
      (property "Reference" "#PWR" (at 0 -6.35 0)
        (effects (font (size 1.27 1.27)) hide)
      )
      (property "Value" "GND_58" (at 0 -3.81 0)
        (effects (font (size 1.27 1.27)))
      )
      (property "Footprint" "" (at 0 0 0)
        (effects (font (size 1.27 1.27)) hide)
      )
      (property "Datasheet" "" (at 0 0 0)
        (effects (font (size 1.27 1.27)) hide)
      )
      (symbol "GND_58_0_1"
        (polyline
          (pts
            (xy 0 0)
            (xy 0 -1.27)
            (xy 1.27 -1.27)
            (xy 0 -2.54)
            (xy -1.27 -1.27)
            (xy 0 -1.27)
          )
          (stroke (width 0) (type default))
          (fill (type none))
        )
      )
      (symbol "GND_58_1_1"
        (pin power_in line (at 0 0 270) (length 0) hide
          (name "GND" (effects (font (size 1.27 1.27))))
          (number "1" (effects (font (size 1.27 1.27))))
        )
      )
    )
	(symbol "data-center-rdimm-ddr4-tester:GND_59" (power) (pin_names (offset 0)) (in_bom yes) (on_board yes)
      (property "Reference" "#PWR" (at 0 -6.35 0)
        (effects (font (size 1.27 1.27)) hide)
      )
      (property "Value" "GND_59" (at 0 -3.81 0)
        (effects (font (size 1.27 1.27)))
      )
      (property "Footprint" "" (at 0 0 0)
        (effects (font (size 1.27 1.27)) hide)
      )
      (property "Datasheet" "" (at 0 0 0)
        (effects (font (size 1.27 1.27)) hide)
      )
      (symbol "GND_59_0_1"
        (polyline
          (pts
            (xy 0 0)
            (xy 0 -1.27)
            (xy 1.27 -1.27)
            (xy 0 -2.54)
            (xy -1.27 -1.27)
            (xy 0 -1.27)
          )
          (stroke (width 0) (type default))
          (fill (type none))
        )
      )
      (symbol "GND_59_1_1"
        (pin power_in line (at 0 0 270) (length 0) hide
          (name "GND" (effects (font (size 1.27 1.27))))
          (number "1" (effects (font (size 1.27 1.27))))
        )
      )
    )
	(symbol "data-center-rdimm-ddr4-tester:GND_60" (power) (pin_names (offset 0)) (in_bom yes) (on_board yes)
      (property "Reference" "#PWR" (at 0 -6.35 0)
        (effects (font (size 1.27 1.27)) hide)
      )
      (property "Value" "GND_60" (at 0 -3.81 0)
        (effects (font (size 1.27 1.27)))
      )
      (property "Footprint" "" (at 0 0 0)
        (effects (font (size 1.27 1.27)) hide)
      )
      (property "Datasheet" "" (at 0 0 0)
        (effects (font (size 1.27 1.27)) hide)
      )
      (symbol "GND_60_0_1"
        (polyline
          (pts
            (xy 0 0)
            (xy 0 -1.27)
            (xy 1.27 -1.27)
            (xy 0 -2.54)
            (xy -1.27 -1.27)
            (xy 0 -1.27)
          )
          (stroke (width 0) (type default))
          (fill (type none))
        )
      )
      (symbol "GND_60_1_1"
        (pin power_in line (at 0 0 270) (length 0) hide
          (name "GND" (effects (font (size 1.27 1.27))))
          (number "1" (effects (font (size 1.27 1.27))))
        )
      )
    )
	(symbol "data-center-rdimm-ddr4-tester:GND_61" (power) (pin_names (offset 0)) (in_bom yes) (on_board yes)
      (property "Reference" "#PWR" (at 0 -6.35 0)
        (effects (font (size 1.27 1.27)) hide)
      )
      (property "Value" "GND_61" (at 0 -3.81 0)
        (effects (font (size 1.27 1.27)))
      )
      (property "Footprint" "" (at 0 0 0)
        (effects (font (size 1.27 1.27)) hide)
      )
      (property "Datasheet" "" (at 0 0 0)
        (effects (font (size 1.27 1.27)) hide)
      )
      (symbol "GND_61_0_1"
        (polyline
          (pts
            (xy 0 0)
            (xy 0 -1.27)
            (xy 1.27 -1.27)
            (xy 0 -2.54)
            (xy -1.27 -1.27)
            (xy 0 -1.27)
          )
          (stroke (width 0) (type default))
          (fill (type none))
        )
      )
      (symbol "GND_61_1_1"
        (pin power_in line (at 0 0 270) (length 0) hide
          (name "GND" (effects (font (size 1.27 1.27))))
          (number "1" (effects (font (size 1.27 1.27))))
        )
      )
    )
	(symbol "data-center-rdimm-ddr4-tester:GND_62" (power) (pin_names (offset 0)) (in_bom yes) (on_board yes)
      (property "Reference" "#PWR" (at 0 -6.35 0)
        (effects (font (size 1.27 1.27)) hide)
      )
      (property "Value" "GND_62" (at 0 -3.81 0)
        (effects (font (size 1.27 1.27)))
      )
      (property "Footprint" "" (at 0 0 0)
        (effects (font (size 1.27 1.27)) hide)
      )
      (property "Datasheet" "" (at 0 0 0)
        (effects (font (size 1.27 1.27)) hide)
      )
      (symbol "GND_62_0_1"
        (polyline
          (pts
            (xy 0 0)
            (xy 0 -1.27)
            (xy 1.27 -1.27)
            (xy 0 -2.54)
            (xy -1.27 -1.27)
            (xy 0 -1.27)
          )
          (stroke (width 0) (type default))
          (fill (type none))
        )
      )
      (symbol "GND_62_1_1"
        (pin power_in line (at 0 0 270) (length 0) hide
          (name "GND" (effects (font (size 1.27 1.27))))
          (number "1" (effects (font (size 1.27 1.27))))
        )
      )
    )
	(symbol "data-center-rdimm-ddr4-tester:GND_63" (power) (pin_names (offset 0)) (in_bom yes) (on_board yes)
      (property "Reference" "#PWR" (at 0 -6.35 0)
        (effects (font (size 1.27 1.27)) hide)
      )
      (property "Value" "GND_63" (at 0 -3.81 0)
        (effects (font (size 1.27 1.27)))
      )
      (property "Footprint" "" (at 0 0 0)
        (effects (font (size 1.27 1.27)) hide)
      )
      (property "Datasheet" "" (at 0 0 0)
        (effects (font (size 1.27 1.27)) hide)
      )
      (symbol "GND_63_0_1"
        (polyline
          (pts
            (xy 0 0)
            (xy 0 -1.27)
            (xy 1.27 -1.27)
            (xy 0 -2.54)
            (xy -1.27 -1.27)
            (xy 0 -1.27)
          )
          (stroke (width 0) (type default))
          (fill (type none))
        )
      )
      (symbol "GND_63_1_1"
        (pin power_in line (at 0 0 270) (length 0) hide
          (name "GND" (effects (font (size 1.27 1.27))))
          (number "1" (effects (font (size 1.27 1.27))))
        )
      )
    )
	(symbol "data-center-rdimm-ddr4-tester:GND_64" (power) (pin_names (offset 0)) (in_bom yes) (on_board yes)
      (property "Reference" "#PWR" (at 0 -6.35 0)
        (effects (font (size 1.27 1.27)) hide)
      )
      (property "Value" "GND_64" (at 0 -3.81 0)
        (effects (font (size 1.27 1.27)))
      )
      (property "Footprint" "" (at 0 0 0)
        (effects (font (size 1.27 1.27)) hide)
      )
      (property "Datasheet" "" (at 0 0 0)
        (effects (font (size 1.27 1.27)) hide)
      )
      (symbol "GND_64_0_1"
        (polyline
          (pts
            (xy 0 0)
            (xy 0 -1.27)
            (xy 1.27 -1.27)
            (xy 0 -2.54)
            (xy -1.27 -1.27)
            (xy 0 -1.27)
          )
          (stroke (width 0) (type default))
          (fill (type none))
        )
      )
      (symbol "GND_64_1_1"
        (pin power_in line (at 0 0 270) (length 0) hide
          (name "GND" (effects (font (size 1.27 1.27))))
          (number "1" (effects (font (size 1.27 1.27))))
        )
      )
    )
	(symbol "data-center-rdimm-ddr4-tester:GND_65" (power) (pin_names (offset 0)) (in_bom yes) (on_board yes)
      (property "Reference" "#PWR" (at 0 -6.35 0)
        (effects (font (size 1.27 1.27)) hide)
      )
      (property "Value" "GND_65" (at 0 -3.81 0)
        (effects (font (size 1.27 1.27)))
      )
      (property "Footprint" "" (at 0 0 0)
        (effects (font (size 1.27 1.27)) hide)
      )
      (property "Datasheet" "" (at 0 0 0)
        (effects (font (size 1.27 1.27)) hide)
      )
      (symbol "GND_65_0_1"
        (polyline
          (pts
            (xy 0 0)
            (xy 0 -1.27)
            (xy 1.27 -1.27)
            (xy 0 -2.54)
            (xy -1.27 -1.27)
            (xy 0 -1.27)
          )
          (stroke (width 0) (type default))
          (fill (type none))
        )
      )
      (symbol "GND_65_1_1"
        (pin power_in line (at 0 0 270) (length 0) hide
          (name "GND" (effects (font (size 1.27 1.27))))
          (number "1" (effects (font (size 1.27 1.27))))
        )
      )
    )
	(symbol "data-center-rdimm-ddr4-tester:GND_66" (power) (pin_names (offset 0)) (in_bom yes) (on_board yes)
      (property "Reference" "#PWR" (at 0 -6.35 0)
        (effects (font (size 1.27 1.27)) hide)
      )
      (property "Value" "GND_66" (at 0 -3.81 0)
        (effects (font (size 1.27 1.27)))
      )
      (property "Footprint" "" (at 0 0 0)
        (effects (font (size 1.27 1.27)) hide)
      )
      (property "Datasheet" "" (at 0 0 0)
        (effects (font (size 1.27 1.27)) hide)
      )
      (symbol "GND_66_0_1"
        (polyline
          (pts
            (xy 0 0)
            (xy 0 -1.27)
            (xy 1.27 -1.27)
            (xy 0 -2.54)
            (xy -1.27 -1.27)
            (xy 0 -1.27)
          )
          (stroke (width 0) (type default))
          (fill (type none))
        )
      )
      (symbol "GND_66_1_1"
        (pin power_in line (at 0 0 270) (length 0) hide
          (name "GND" (effects (font (size 1.27 1.27))))
          (number "1" (effects (font (size 1.27 1.27))))
        )
      )
    )
	(symbol "data-center-rdimm-ddr4-tester:GND_67" (power) (pin_names (offset 0)) (in_bom yes) (on_board yes)
      (property "Reference" "#PWR" (at 0 -6.35 0)
        (effects (font (size 1.27 1.27)) hide)
      )
      (property "Value" "GND_67" (at 0 -3.81 0)
        (effects (font (size 1.27 1.27)))
      )
      (property "Footprint" "" (at 0 0 0)
        (effects (font (size 1.27 1.27)) hide)
      )
      (property "Datasheet" "" (at 0 0 0)
        (effects (font (size 1.27 1.27)) hide)
      )
      (symbol "GND_67_0_1"
        (polyline
          (pts
            (xy 0 0)
            (xy 0 -1.27)
            (xy 1.27 -1.27)
            (xy 0 -2.54)
            (xy -1.27 -1.27)
            (xy 0 -1.27)
          )
          (stroke (width 0) (type default))
          (fill (type none))
        )
      )
      (symbol "GND_67_1_1"
        (pin power_in line (at 0 0 270) (length 0) hide
          (name "GND" (effects (font (size 1.27 1.27))))
          (number "1" (effects (font (size 1.27 1.27))))
        )
      )
    )
	(symbol "data-center-rdimm-ddr4-tester:GND_68" (power) (pin_names (offset 0)) (in_bom yes) (on_board yes)
      (property "Reference" "#PWR" (at 0 -6.35 0)
        (effects (font (size 1.27 1.27)) hide)
      )
      (property "Value" "GND_68" (at 0 -3.81 0)
        (effects (font (size 1.27 1.27)))
      )
      (property "Footprint" "" (at 0 0 0)
        (effects (font (size 1.27 1.27)) hide)
      )
      (property "Datasheet" "" (at 0 0 0)
        (effects (font (size 1.27 1.27)) hide)
      )
      (symbol "GND_68_0_1"
        (polyline
          (pts
            (xy 0 0)
            (xy 0 -1.27)
            (xy 1.27 -1.27)
            (xy 0 -2.54)
            (xy -1.27 -1.27)
            (xy 0 -1.27)
          )
          (stroke (width 0) (type default))
          (fill (type none))
        )
      )
      (symbol "GND_68_1_1"
        (pin power_in line (at 0 0 270) (length 0) hide
          (name "GND" (effects (font (size 1.27 1.27))))
          (number "1" (effects (font (size 1.27 1.27))))
        )
      )
    )
	(symbol "data-center-rdimm-ddr4-tester:GND_69" (power) (pin_names (offset 0)) (in_bom yes) (on_board yes)
      (property "Reference" "#PWR" (at 0 -6.35 0)
        (effects (font (size 1.27 1.27)) hide)
      )
      (property "Value" "GND_69" (at 0 -3.81 0)
        (effects (font (size 1.27 1.27)))
      )
      (property "Footprint" "" (at 0 0 0)
        (effects (font (size 1.27 1.27)) hide)
      )
      (property "Datasheet" "" (at 0 0 0)
        (effects (font (size 1.27 1.27)) hide)
      )
      (symbol "GND_69_0_1"
        (polyline
          (pts
            (xy 0 0)
            (xy 0 -1.27)
            (xy 1.27 -1.27)
            (xy 0 -2.54)
            (xy -1.27 -1.27)
            (xy 0 -1.27)
          )
          (stroke (width 0) (type default))
          (fill (type none))
        )
      )
      (symbol "GND_69_1_1"
        (pin power_in line (at 0 0 270) (length 0) hide
          (name "GND" (effects (font (size 1.27 1.27))))
          (number "1" (effects (font (size 1.27 1.27))))
        )
      )
    )
	(symbol "data-center-rdimm-ddr4-tester:GND_70" (power) (pin_names (offset 0)) (in_bom yes) (on_board yes)
      (property "Reference" "#PWR" (at 0 -6.35 0)
        (effects (font (size 1.27 1.27)) hide)
      )
      (property "Value" "GND_70" (at 0 -3.81 0)
        (effects (font (size 1.27 1.27)))
      )
      (property "Footprint" "" (at 0 0 0)
        (effects (font (size 1.27 1.27)) hide)
      )
      (property "Datasheet" "" (at 0 0 0)
        (effects (font (size 1.27 1.27)) hide)
      )
      (symbol "GND_70_0_1"
        (polyline
          (pts
            (xy 0 0)
            (xy 0 -1.27)
            (xy 1.27 -1.27)
            (xy 0 -2.54)
            (xy -1.27 -1.27)
            (xy 0 -1.27)
          )
          (stroke (width 0) (type default))
          (fill (type none))
        )
      )
      (symbol "GND_70_1_1"
        (pin power_in line (at 0 0 270) (length 0) hide
          (name "GND" (effects (font (size 1.27 1.27))))
          (number "1" (effects (font (size 1.27 1.27))))
        )
      )
    )
	(symbol "data-center-rdimm-ddr4-tester:GND_71" (power) (pin_names (offset 0)) (in_bom yes) (on_board yes)
      (property "Reference" "#PWR" (at 0 -6.35 0)
        (effects (font (size 1.27 1.27)) hide)
      )
      (property "Value" "GND_71" (at 0 -3.81 0)
        (effects (font (size 1.27 1.27)))
      )
      (property "Footprint" "" (at 0 0 0)
        (effects (font (size 1.27 1.27)) hide)
      )
      (property "Datasheet" "" (at 0 0 0)
        (effects (font (size 1.27 1.27)) hide)
      )
      (symbol "GND_71_0_1"
        (polyline
          (pts
            (xy 0 0)
            (xy 0 -1.27)
            (xy 1.27 -1.27)
            (xy 0 -2.54)
            (xy -1.27 -1.27)
            (xy 0 -1.27)
          )
          (stroke (width 0) (type default))
          (fill (type none))
        )
      )
      (symbol "GND_71_1_1"
        (pin power_in line (at 0 0 270) (length 0) hide
          (name "GND" (effects (font (size 1.27 1.27))))
          (number "1" (effects (font (size 1.27 1.27))))
        )
      )
    )
	(symbol "data-center-rdimm-ddr4-tester:GND_72" (power) (pin_names (offset 0)) (in_bom yes) (on_board yes)
      (property "Reference" "#PWR" (at 0 -6.35 0)
        (effects (font (size 1.27 1.27)) hide)
      )
      (property "Value" "GND_72" (at 0 -3.81 0)
        (effects (font (size 1.27 1.27)))
      )
      (property "Footprint" "" (at 0 0 0)
        (effects (font (size 1.27 1.27)) hide)
      )
      (property "Datasheet" "" (at 0 0 0)
        (effects (font (size 1.27 1.27)) hide)
      )
      (symbol "GND_72_0_1"
        (polyline
          (pts
            (xy 0 0)
            (xy 0 -1.27)
            (xy 1.27 -1.27)
            (xy 0 -2.54)
            (xy -1.27 -1.27)
            (xy 0 -1.27)
          )
          (stroke (width 0) (type default))
          (fill (type none))
        )
      )
      (symbol "GND_72_1_1"
        (pin power_in line (at 0 0 270) (length 0) hide
          (name "GND" (effects (font (size 1.27 1.27))))
          (number "1" (effects (font (size 1.27 1.27))))
        )
      )
    )
	(symbol "data-center-rdimm-ddr4-tester:GND_73" (power) (pin_names (offset 0)) (in_bom yes) (on_board yes)
      (property "Reference" "#PWR" (at 0 -6.35 0)
        (effects (font (size 1.27 1.27)) hide)
      )
      (property "Value" "GND_73" (at 0 -3.81 0)
        (effects (font (size 1.27 1.27)))
      )
      (property "Footprint" "" (at 0 0 0)
        (effects (font (size 1.27 1.27)) hide)
      )
      (property "Datasheet" "" (at 0 0 0)
        (effects (font (size 1.27 1.27)) hide)
      )
      (symbol "GND_73_0_1"
        (polyline
          (pts
            (xy 0 0)
            (xy 0 -1.27)
            (xy 1.27 -1.27)
            (xy 0 -2.54)
            (xy -1.27 -1.27)
            (xy 0 -1.27)
          )
          (stroke (width 0) (type default))
          (fill (type none))
        )
      )
      (symbol "GND_73_1_1"
        (pin power_in line (at 0 0 270) (length 0) hide
          (name "GND" (effects (font (size 1.27 1.27))))
          (number "1" (effects (font (size 1.27 1.27))))
        )
      )
    )
	(symbol "data-center-rdimm-ddr4-tester:GND_74" (power) (pin_names (offset 0)) (in_bom yes) (on_board yes)
      (property "Reference" "#PWR" (at 0 -6.35 0)
        (effects (font (size 1.27 1.27)) hide)
      )
      (property "Value" "GND_74" (at 0 -3.81 0)
        (effects (font (size 1.27 1.27)))
      )
      (property "Footprint" "" (at 0 0 0)
        (effects (font (size 1.27 1.27)) hide)
      )
      (property "Datasheet" "" (at 0 0 0)
        (effects (font (size 1.27 1.27)) hide)
      )
      (symbol "GND_74_0_1"
        (polyline
          (pts
            (xy 0 0)
            (xy 0 -1.27)
            (xy 1.27 -1.27)
            (xy 0 -2.54)
            (xy -1.27 -1.27)
            (xy 0 -1.27)
          )
          (stroke (width 0) (type default))
          (fill (type none))
        )
      )
      (symbol "GND_74_1_1"
        (pin power_in line (at 0 0 270) (length 0) hide
          (name "GND" (effects (font (size 1.27 1.27))))
          (number "1" (effects (font (size 1.27 1.27))))
        )
      )
    )
	(symbol "data-center-rdimm-ddr4-tester:GND_75" (power) (pin_names (offset 0)) (in_bom yes) (on_board yes)
      (property "Reference" "#PWR" (at 0 -6.35 0)
        (effects (font (size 1.27 1.27)) hide)
      )
      (property "Value" "GND_75" (at 0 -3.81 0)
        (effects (font (size 1.27 1.27)))
      )
      (property "Footprint" "" (at 0 0 0)
        (effects (font (size 1.27 1.27)) hide)
      )
      (property "Datasheet" "" (at 0 0 0)
        (effects (font (size 1.27 1.27)) hide)
      )
      (symbol "GND_75_0_1"
        (polyline
          (pts
            (xy 0 0)
            (xy 0 -1.27)
            (xy 1.27 -1.27)
            (xy 0 -2.54)
            (xy -1.27 -1.27)
            (xy 0 -1.27)
          )
          (stroke (width 0) (type default))
          (fill (type none))
        )
      )
      (symbol "GND_75_1_1"
        (pin power_in line (at 0 0 270) (length 0) hide
          (name "GND" (effects (font (size 1.27 1.27))))
          (number "1" (effects (font (size 1.27 1.27))))
        )
      )
    )
	(symbol "data-center-rdimm-ddr4-tester:GND_76" (power) (pin_names (offset 0)) (in_bom yes) (on_board yes)
      (property "Reference" "#PWR" (at 0 -6.35 0)
        (effects (font (size 1.27 1.27)) hide)
      )
      (property "Value" "GND_76" (at 0 -3.81 0)
        (effects (font (size 1.27 1.27)))
      )
      (property "Footprint" "" (at 0 0 0)
        (effects (font (size 1.27 1.27)) hide)
      )
      (property "Datasheet" "" (at 0 0 0)
        (effects (font (size 1.27 1.27)) hide)
      )
      (symbol "GND_76_0_1"
        (polyline
          (pts
            (xy 0 0)
            (xy 0 -1.27)
            (xy 1.27 -1.27)
            (xy 0 -2.54)
            (xy -1.27 -1.27)
            (xy 0 -1.27)
          )
          (stroke (width 0) (type default))
          (fill (type none))
        )
      )
      (symbol "GND_76_1_1"
        (pin power_in line (at 0 0 270) (length 0) hide
          (name "GND" (effects (font (size 1.27 1.27))))
          (number "1" (effects (font (size 1.27 1.27))))
        )
      )
    )
	(symbol "data-center-rdimm-ddr4-tester:GND_77" (power) (pin_names (offset 0)) (in_bom yes) (on_board yes)
      (property "Reference" "#PWR" (at 0 -6.35 0)
        (effects (font (size 1.27 1.27)) hide)
      )
      (property "Value" "GND_77" (at 0 -3.81 0)
        (effects (font (size 1.27 1.27)))
      )
      (property "Footprint" "" (at 0 0 0)
        (effects (font (size 1.27 1.27)) hide)
      )
      (property "Datasheet" "" (at 0 0 0)
        (effects (font (size 1.27 1.27)) hide)
      )
      (symbol "GND_77_0_1"
        (polyline
          (pts
            (xy 0 0)
            (xy 0 -1.27)
            (xy 1.27 -1.27)
            (xy 0 -2.54)
            (xy -1.27 -1.27)
            (xy 0 -1.27)
          )
          (stroke (width 0) (type default))
          (fill (type none))
        )
      )
      (symbol "GND_77_1_1"
        (pin power_in line (at 0 0 270) (length 0) hide
          (name "GND" (effects (font (size 1.27 1.27))))
          (number "1" (effects (font (size 1.27 1.27))))
        )
      )
    )
	(symbol "data-center-rdimm-ddr4-tester:GND_78" (power) (pin_names (offset 0)) (in_bom yes) (on_board yes)
      (property "Reference" "#PWR" (at 0 -6.35 0)
        (effects (font (size 1.27 1.27)) hide)
      )
      (property "Value" "GND_78" (at 0 -3.81 0)
        (effects (font (size 1.27 1.27)))
      )
      (property "Footprint" "" (at 0 0 0)
        (effects (font (size 1.27 1.27)) hide)
      )
      (property "Datasheet" "" (at 0 0 0)
        (effects (font (size 1.27 1.27)) hide)
      )
      (symbol "GND_78_0_1"
        (polyline
          (pts
            (xy 0 0)
            (xy 0 -1.27)
            (xy 1.27 -1.27)
            (xy 0 -2.54)
            (xy -1.27 -1.27)
            (xy 0 -1.27)
          )
          (stroke (width 0) (type default))
          (fill (type none))
        )
      )
      (symbol "GND_78_1_1"
        (pin power_in line (at 0 0 270) (length 0) hide
          (name "GND" (effects (font (size 1.27 1.27))))
          (number "1" (effects (font (size 1.27 1.27))))
        )
      )
    )
	(symbol "data-center-rdimm-ddr4-tester:GND_79" (power) (pin_names (offset 0)) (in_bom yes) (on_board yes)
      (property "Reference" "#PWR" (at 0 -6.35 0)
        (effects (font (size 1.27 1.27)) hide)
      )
      (property "Value" "GND_79" (at 0 -3.81 0)
        (effects (font (size 1.27 1.27)))
      )
      (property "Footprint" "" (at 0 0 0)
        (effects (font (size 1.27 1.27)) hide)
      )
      (property "Datasheet" "" (at 0 0 0)
        (effects (font (size 1.27 1.27)) hide)
      )
      (symbol "GND_79_0_1"
        (polyline
          (pts
            (xy 0 0)
            (xy 0 -1.27)
            (xy 1.27 -1.27)
            (xy 0 -2.54)
            (xy -1.27 -1.27)
            (xy 0 -1.27)
          )
          (stroke (width 0) (type default))
          (fill (type none))
        )
      )
      (symbol "GND_79_1_1"
        (pin power_in line (at 0 0 270) (length 0) hide
          (name "GND" (effects (font (size 1.27 1.27))))
          (number "1" (effects (font (size 1.27 1.27))))
        )
      )
    )
	(symbol "data-center-rdimm-ddr4-tester:GND_81" (power) (pin_names (offset 0)) (in_bom yes) (on_board yes)
      (property "Reference" "#PWR" (at 0 -6.35 0)
        (effects (font (size 1.27 1.27)) hide)
      )
      (property "Value" "GND_81" (at 0 -3.81 0)
        (effects (font (size 1.27 1.27)))
      )
      (property "Footprint" "" (at 0 0 0)
        (effects (font (size 1.27 1.27)) hide)
      )
      (property "Datasheet" "" (at 0 0 0)
        (effects (font (size 1.27 1.27)) hide)
      )
      (symbol "GND_81_0_1"
        (polyline
          (pts
            (xy 0 0)
            (xy 0 -1.27)
            (xy 1.27 -1.27)
            (xy 0 -2.54)
            (xy -1.27 -1.27)
            (xy 0 -1.27)
          )
          (stroke (width 0) (type default))
          (fill (type none))
        )
      )
      (symbol "GND_81_1_1"
        (pin power_in line (at 0 0 270) (length 0) hide
          (name "GND" (effects (font (size 1.27 1.27))))
          (number "1" (effects (font (size 1.27 1.27))))
        )
      )
    )
	(symbol "data-center-rdimm-ddr4-tester:GND_82" (power) (pin_names (offset 0)) (in_bom yes) (on_board yes)
      (property "Reference" "#PWR" (at 0 -6.35 0)
        (effects (font (size 1.27 1.27)) hide)
      )
      (property "Value" "GND_82" (at 0 -3.81 0)
        (effects (font (size 1.27 1.27)))
      )
      (property "Footprint" "" (at 0 0 0)
        (effects (font (size 1.27 1.27)) hide)
      )
      (property "Datasheet" "" (at 0 0 0)
        (effects (font (size 1.27 1.27)) hide)
      )
      (symbol "GND_82_0_1"
        (polyline
          (pts
            (xy 0 0)
            (xy 0 -1.27)
            (xy 1.27 -1.27)
            (xy 0 -2.54)
            (xy -1.27 -1.27)
            (xy 0 -1.27)
          )
          (stroke (width 0) (type default))
          (fill (type none))
        )
      )
      (symbol "GND_82_1_1"
        (pin power_in line (at 0 0 270) (length 0) hide
          (name "GND" (effects (font (size 1.27 1.27))))
          (number "1" (effects (font (size 1.27 1.27))))
        )
      )
    )
	(symbol "data-center-rdimm-ddr4-tester:GND_83" (power) (pin_names (offset 0)) (in_bom yes) (on_board yes)
      (property "Reference" "#PWR" (at 0 -6.35 0)
        (effects (font (size 1.27 1.27)) hide)
      )
      (property "Value" "GND_83" (at 0 -3.81 0)
        (effects (font (size 1.27 1.27)))
      )
      (property "Footprint" "" (at 0 0 0)
        (effects (font (size 1.27 1.27)) hide)
      )
      (property "Datasheet" "" (at 0 0 0)
        (effects (font (size 1.27 1.27)) hide)
      )
      (symbol "GND_83_0_1"
        (polyline
          (pts
            (xy 0 0)
            (xy 0 -1.27)
            (xy 1.27 -1.27)
            (xy 0 -2.54)
            (xy -1.27 -1.27)
            (xy 0 -1.27)
          )
          (stroke (width 0) (type default))
          (fill (type none))
        )
      )
      (symbol "GND_83_1_1"
        (pin power_in line (at 0 0 270) (length 0) hide
          (name "GND" (effects (font (size 1.27 1.27))))
          (number "1" (effects (font (size 1.27 1.27))))
        )
      )
    )
	(symbol "data-center-rdimm-ddr4-tester:GND_85" (power) (pin_names (offset 0)) (in_bom yes) (on_board yes)
      (property "Reference" "#PWR" (at 0 -6.35 0)
        (effects (font (size 1.27 1.27)) hide)
      )
      (property "Value" "GND_85" (at 0 -3.81 0)
        (effects (font (size 1.27 1.27)))
      )
      (property "Footprint" "" (at 0 0 0)
        (effects (font (size 1.27 1.27)) hide)
      )
      (property "Datasheet" "" (at 0 0 0)
        (effects (font (size 1.27 1.27)) hide)
      )
      (symbol "GND_85_0_1"
        (polyline
          (pts
            (xy 0 0)
            (xy 0 -1.27)
            (xy 1.27 -1.27)
            (xy 0 -2.54)
            (xy -1.27 -1.27)
            (xy 0 -1.27)
          )
          (stroke (width 0) (type default))
          (fill (type none))
        )
      )
      (symbol "GND_85_1_1"
        (pin power_in line (at 0 0 270) (length 0) hide
          (name "GND" (effects (font (size 1.27 1.27))))
          (number "1" (effects (font (size 1.27 1.27))))
        )
      )
    )
	(symbol "data-center-rdimm-ddr4-tester:GND_86" (power) (pin_names (offset 0)) (in_bom yes) (on_board yes)
      (property "Reference" "#PWR" (at 0 -6.35 0)
        (effects (font (size 1.27 1.27)) hide)
      )
      (property "Value" "GND_86" (at 0 -3.81 0)
        (effects (font (size 1.27 1.27)))
      )
      (property "Footprint" "" (at 0 0 0)
        (effects (font (size 1.27 1.27)) hide)
      )
      (property "Datasheet" "" (at 0 0 0)
        (effects (font (size 1.27 1.27)) hide)
      )
      (symbol "GND_86_0_1"
        (polyline
          (pts
            (xy 0 0)
            (xy 0 -1.27)
            (xy 1.27 -1.27)
            (xy 0 -2.54)
            (xy -1.27 -1.27)
            (xy 0 -1.27)
          )
          (stroke (width 0) (type default))
          (fill (type none))
        )
      )
      (symbol "GND_86_1_1"
        (pin power_in line (at 0 0 270) (length 0) hide
          (name "GND" (effects (font (size 1.27 1.27))))
          (number "1" (effects (font (size 1.27 1.27))))
        )
      )
    )
	(symbol "data-center-rdimm-ddr4-tester:GND_87" (power) (pin_names (offset 0)) (in_bom yes) (on_board yes)
      (property "Reference" "#PWR" (at 0 -6.35 0)
        (effects (font (size 1.27 1.27)) hide)
      )
      (property "Value" "GND_87" (at 0 -3.81 0)
        (effects (font (size 1.27 1.27)))
      )
      (property "Footprint" "" (at 0 0 0)
        (effects (font (size 1.27 1.27)) hide)
      )
      (property "Datasheet" "" (at 0 0 0)
        (effects (font (size 1.27 1.27)) hide)
      )
      (symbol "GND_87_0_1"
        (polyline
          (pts
            (xy 0 0)
            (xy 0 -1.27)
            (xy 1.27 -1.27)
            (xy 0 -2.54)
            (xy -1.27 -1.27)
            (xy 0 -1.27)
          )
          (stroke (width 0) (type default))
          (fill (type none))
        )
      )
      (symbol "GND_87_1_1"
        (pin power_in line (at 0 0 270) (length 0) hide
          (name "GND" (effects (font (size 1.27 1.27))))
          (number "1" (effects (font (size 1.27 1.27))))
        )
      )
    )
	(symbol "data-center-rdimm-ddr4-tester:GND_88" (power) (pin_names (offset 0)) (in_bom yes) (on_board yes)
      (property "Reference" "#PWR" (at 0 -6.35 0)
        (effects (font (size 1.27 1.27)) hide)
      )
      (property "Value" "GND_88" (at 0 -3.81 0)
        (effects (font (size 1.27 1.27)))
      )
      (property "Footprint" "" (at 0 0 0)
        (effects (font (size 1.27 1.27)) hide)
      )
      (property "Datasheet" "" (at 0 0 0)
        (effects (font (size 1.27 1.27)) hide)
      )
      (symbol "GND_88_0_1"
        (polyline
          (pts
            (xy 0 0)
            (xy 0 -1.27)
            (xy 1.27 -1.27)
            (xy 0 -2.54)
            (xy -1.27 -1.27)
            (xy 0 -1.27)
          )
          (stroke (width 0) (type default))
          (fill (type none))
        )
      )
      (symbol "GND_88_1_1"
        (pin power_in line (at 0 0 270) (length 0) hide
          (name "GND" (effects (font (size 1.27 1.27))))
          (number "1" (effects (font (size 1.27 1.27))))
        )
      )
    )
	(symbol "data-center-rdimm-ddr4-tester:GND_89" (power) (pin_names (offset 0)) (in_bom yes) (on_board yes)
      (property "Reference" "#PWR" (at 0 -6.35 0)
        (effects (font (size 1.27 1.27)) hide)
      )
      (property "Value" "GND_89" (at 0 -3.81 0)
        (effects (font (size 1.27 1.27)))
      )
      (property "Footprint" "" (at 0 0 0)
        (effects (font (size 1.27 1.27)) hide)
      )
      (property "Datasheet" "" (at 0 0 0)
        (effects (font (size 1.27 1.27)) hide)
      )
      (symbol "GND_89_0_1"
        (polyline
          (pts
            (xy 0 0)
            (xy 0 -1.27)
            (xy 1.27 -1.27)
            (xy 0 -2.54)
            (xy -1.27 -1.27)
            (xy 0 -1.27)
          )
          (stroke (width 0) (type default))
          (fill (type none))
        )
      )
      (symbol "GND_89_1_1"
        (pin power_in line (at 0 0 270) (length 0) hide
          (name "GND" (effects (font (size 1.27 1.27))))
          (number "1" (effects (font (size 1.27 1.27))))
        )
      )
    )
	(symbol "data-center-rdimm-ddr4-tester:GND_90" (power) (pin_names (offset 0)) (in_bom yes) (on_board yes)
      (property "Reference" "#PWR" (at 0 -6.35 0)
        (effects (font (size 1.27 1.27)) hide)
      )
      (property "Value" "GND_90" (at 0 -3.81 0)
        (effects (font (size 1.27 1.27)))
      )
      (property "Footprint" "" (at 0 0 0)
        (effects (font (size 1.27 1.27)) hide)
      )
      (property "Datasheet" "" (at 0 0 0)
        (effects (font (size 1.27 1.27)) hide)
      )
      (symbol "GND_90_0_1"
        (polyline
          (pts
            (xy 0 0)
            (xy 0 -1.27)
            (xy 1.27 -1.27)
            (xy 0 -2.54)
            (xy -1.27 -1.27)
            (xy 0 -1.27)
          )
          (stroke (width 0) (type default))
          (fill (type none))
        )
      )
      (symbol "GND_90_1_1"
        (pin power_in line (at 0 0 270) (length 0) hide
          (name "GND" (effects (font (size 1.27 1.27))))
          (number "1" (effects (font (size 1.27 1.27))))
        )
      )
    )
	(symbol "data-center-rdimm-ddr4-tester:GND_91" (power) (pin_names (offset 0)) (in_bom yes) (on_board yes)
      (property "Reference" "#PWR" (at 0 -6.35 0)
        (effects (font (size 1.27 1.27)) hide)
      )
      (property "Value" "GND_91" (at 0 -3.81 0)
        (effects (font (size 1.27 1.27)))
      )
      (property "Footprint" "" (at 0 0 0)
        (effects (font (size 1.27 1.27)) hide)
      )
      (property "Datasheet" "" (at 0 0 0)
        (effects (font (size 1.27 1.27)) hide)
      )
      (symbol "GND_91_0_1"
        (polyline
          (pts
            (xy 0 0)
            (xy 0 -1.27)
            (xy 1.27 -1.27)
            (xy 0 -2.54)
            (xy -1.27 -1.27)
            (xy 0 -1.27)
          )
          (stroke (width 0) (type default))
          (fill (type none))
        )
      )
      (symbol "GND_91_1_1"
        (pin power_in line (at 0 0 270) (length 0) hide
          (name "GND" (effects (font (size 1.27 1.27))))
          (number "1" (effects (font (size 1.27 1.27))))
        )
      )
    )
	(symbol "data-center-rdimm-ddr4-tester:GND_92" (power) (pin_names (offset 0)) (in_bom yes) (on_board yes)
      (property "Reference" "#PWR" (at 0 -6.35 0)
        (effects (font (size 1.27 1.27)) hide)
      )
      (property "Value" "GND_92" (at 0 -3.81 0)
        (effects (font (size 1.27 1.27)))
      )
      (property "Footprint" "" (at 0 0 0)
        (effects (font (size 1.27 1.27)) hide)
      )
      (property "Datasheet" "" (at 0 0 0)
        (effects (font (size 1.27 1.27)) hide)
      )
      (symbol "GND_92_0_1"
        (polyline
          (pts
            (xy 0 0)
            (xy 0 -1.27)
            (xy 1.27 -1.27)
            (xy 0 -2.54)
            (xy -1.27 -1.27)
            (xy 0 -1.27)
          )
          (stroke (width 0) (type default))
          (fill (type none))
        )
      )
      (symbol "GND_92_1_1"
        (pin power_in line (at 0 0 270) (length 0) hide
          (name "GND" (effects (font (size 1.27 1.27))))
          (number "1" (effects (font (size 1.27 1.27))))
        )
      )
    )
	(symbol "data-center-rdimm-ddr4-tester:GND_93" (power) (pin_names (offset 0)) (in_bom yes) (on_board yes)
      (property "Reference" "#PWR" (at 0 -6.35 0)
        (effects (font (size 1.27 1.27)) hide)
      )
      (property "Value" "GND_93" (at 0 -3.81 0)
        (effects (font (size 1.27 1.27)))
      )
      (property "Footprint" "" (at 0 0 0)
        (effects (font (size 1.27 1.27)) hide)
      )
      (property "Datasheet" "" (at 0 0 0)
        (effects (font (size 1.27 1.27)) hide)
      )
      (symbol "GND_93_0_1"
        (polyline
          (pts
            (xy 0 0)
            (xy 0 -1.27)
            (xy 1.27 -1.27)
            (xy 0 -2.54)
            (xy -1.27 -1.27)
            (xy 0 -1.27)
          )
          (stroke (width 0) (type default))
          (fill (type none))
        )
      )
      (symbol "GND_93_1_1"
        (pin power_in line (at 0 0 270) (length 0) hide
          (name "GND" (effects (font (size 1.27 1.27))))
          (number "1" (effects (font (size 1.27 1.27))))
        )
      )
    )
	(symbol "data-center-rdimm-ddr4-tester:GND_94" (power) (pin_names (offset 0)) (in_bom yes) (on_board yes)
      (property "Reference" "#PWR" (at 0 -6.35 0)
        (effects (font (size 1.27 1.27)) hide)
      )
      (property "Value" "GND_94" (at 0 -3.81 0)
        (effects (font (size 1.27 1.27)))
      )
      (property "Footprint" "" (at 0 0 0)
        (effects (font (size 1.27 1.27)) hide)
      )
      (property "Datasheet" "" (at 0 0 0)
        (effects (font (size 1.27 1.27)) hide)
      )
      (symbol "GND_94_0_1"
        (polyline
          (pts
            (xy 0 0)
            (xy 0 -1.27)
            (xy 1.27 -1.27)
            (xy 0 -2.54)
            (xy -1.27 -1.27)
            (xy 0 -1.27)
          )
          (stroke (width 0) (type default))
          (fill (type none))
        )
      )
      (symbol "GND_94_1_1"
        (pin power_in line (at 0 0 270) (length 0) hide
          (name "GND" (effects (font (size 1.27 1.27))))
          (number "1" (effects (font (size 1.27 1.27))))
        )
      )
    )
	(symbol "data-center-rdimm-ddr4-tester:GND_95" (power) (pin_names (offset 0)) (in_bom yes) (on_board yes)
      (property "Reference" "#PWR" (at 0 -6.35 0)
        (effects (font (size 1.27 1.27)) hide)
      )
      (property "Value" "GND_95" (at 0 -3.81 0)
        (effects (font (size 1.27 1.27)))
      )
      (property "Footprint" "" (at 0 0 0)
        (effects (font (size 1.27 1.27)) hide)
      )
      (property "Datasheet" "" (at 0 0 0)
        (effects (font (size 1.27 1.27)) hide)
      )
      (symbol "GND_95_0_1"
        (polyline
          (pts
            (xy 0 0)
            (xy 0 -1.27)
            (xy 1.27 -1.27)
            (xy 0 -2.54)
            (xy -1.27 -1.27)
            (xy 0 -1.27)
          )
          (stroke (width 0) (type default))
          (fill (type none))
        )
      )
      (symbol "GND_95_1_1"
        (pin power_in line (at 0 0 270) (length 0) hide
          (name "GND" (effects (font (size 1.27 1.27))))
          (number "1" (effects (font (size 1.27 1.27))))
        )
      )
    )
	(symbol "data-center-rdimm-ddr4-tester:GND_96" (power) (pin_names (offset 0)) (in_bom yes) (on_board yes)
      (property "Reference" "#PWR" (at 0 -6.35 0)
        (effects (font (size 1.27 1.27)) hide)
      )
      (property "Value" "GND_96" (at 0 -3.81 0)
        (effects (font (size 1.27 1.27)))
      )
      (property "Footprint" "" (at 0 0 0)
        (effects (font (size 1.27 1.27)) hide)
      )
      (property "Datasheet" "" (at 0 0 0)
        (effects (font (size 1.27 1.27)) hide)
      )
      (symbol "GND_96_0_1"
        (polyline
          (pts
            (xy 0 0)
            (xy 0 -1.27)
            (xy 1.27 -1.27)
            (xy 0 -2.54)
            (xy -1.27 -1.27)
            (xy 0 -1.27)
          )
          (stroke (width 0) (type default))
          (fill (type none))
        )
      )
      (symbol "GND_96_1_1"
        (pin power_in line (at 0 0 270) (length 0) hide
          (name "GND" (effects (font (size 1.27 1.27))))
          (number "1" (effects (font (size 1.27 1.27))))
        )
      )
    )
	(symbol "data-center-rdimm-ddr4-tester:GND_97" (power) (pin_names (offset 0)) (in_bom yes) (on_board yes)
      (property "Reference" "#PWR" (at 0 -6.35 0)
        (effects (font (size 1.27 1.27)) hide)
      )
      (property "Value" "GND_97" (at 0 -3.81 0)
        (effects (font (size 1.27 1.27)))
      )
      (property "Footprint" "" (at 0 0 0)
        (effects (font (size 1.27 1.27)) hide)
      )
      (property "Datasheet" "" (at 0 0 0)
        (effects (font (size 1.27 1.27)) hide)
      )
      (symbol "GND_97_0_1"
        (polyline
          (pts
            (xy 0 0)
            (xy 0 -1.27)
            (xy 1.27 -1.27)
            (xy 0 -2.54)
            (xy -1.27 -1.27)
            (xy 0 -1.27)
          )
          (stroke (width 0) (type default))
          (fill (type none))
        )
      )
      (symbol "GND_97_1_1"
        (pin power_in line (at 0 0 270) (length 0) hide
          (name "GND" (effects (font (size 1.27 1.27))))
          (number "1" (effects (font (size 1.27 1.27))))
        )
      )
    )
	(symbol "data-center-rdimm-ddr4-tester:GND_98" (power) (pin_names (offset 0)) (in_bom yes) (on_board yes)
      (property "Reference" "#PWR" (at 0 -6.35 0)
        (effects (font (size 1.27 1.27)) hide)
      )
      (property "Value" "GND_98" (at 0 -3.81 0)
        (effects (font (size 1.27 1.27)))
      )
      (property "Footprint" "" (at 0 0 0)
        (effects (font (size 1.27 1.27)) hide)
      )
      (property "Datasheet" "" (at 0 0 0)
        (effects (font (size 1.27 1.27)) hide)
      )
      (symbol "GND_98_0_1"
        (polyline
          (pts
            (xy 0 0)
            (xy 0 -1.27)
            (xy 1.27 -1.27)
            (xy 0 -2.54)
            (xy -1.27 -1.27)
            (xy 0 -1.27)
          )
          (stroke (width 0) (type default))
          (fill (type none))
        )
      )
      (symbol "GND_98_1_1"
        (pin power_in line (at 0 0 270) (length 0) hide
          (name "GND" (effects (font (size 1.27 1.27))))
          (number "1" (effects (font (size 1.27 1.27))))
        )
      )
    )
	(symbol "data-center-rdimm-ddr4-tester:LM3881MME_NOPB" (in_bom yes) (on_board yes)
      (property "Reference" "U" (at 43.18 -2.54 0)
        (effects (font (size 1.27 1.27) (thickness 0.15)) (justify left bottom))
      )
      (property "Value" "LM3881MME_NOPB" (at 43.18 -5.08 0)
        (effects (font (size 1.27 1.27) (thickness 0.15)) (justify left bottom))
      )
      (property "Footprint" "data-center-rdimm-ddr4-tester-footprints:VSSOP-8_3x3mm_P0.65mm" (at 43.18 -7.62 0)
        (effects (font (size 1.27 1.27) (thickness 0.15)) (justify left bottom) hide)
      )
      (property "Datasheet" "http://www.ti.com/lit/ds/symlink/lm3881.pdf" (at 43.18 -10.16 0)
        (effects (font (size 1.27 1.27) (thickness 0.15)) (justify left bottom) hide)
      )
      (property "Manufacturer" "Texas Instruments" (at 43.18 -12.7 0)
        (effects (font (size 1.27 1.27) (thickness 0.15)) (justify left bottom) hide)
      )
      (property "MPN" "LM3881MME/NOPB" (at 43.18 -15.24 0)
        (effects (font (size 1.27 1.27) (thickness 0.15)) (justify left bottom) hide)
      )
      (property "Author" "Antmicro" (at 43.18 -17.78 0)
        (effects (font (size 1.27 1.27) (thickness 0.15)) (justify left bottom) hide)
      )
      (property "License" "Apache-2.0" (at 43.18 -20.32 0)
        (effects (font (size 1.27 1.27) (thickness 0.15)) (justify left bottom) hide)
      )
      (property "ki_description" "LM3881MME/NOPB" (at 0 0 0)
        (effects (font (size 1.27 1.27)) hide)
      )
      (symbol "LM3881MME_NOPB_1_1"
        (rectangle (start 2.54 2.54) (end 15.24 -15.24)
          (stroke (width 0.254) (type default))
          (fill (type background))
        )
        (pin power_in line (at 0 0 0) (length 2.54)
          (name "VCC" (effects (font (size 1.27 1.27))))
          (number "1" (effects (font (size 1.27 1.27))))
        )
        (pin passive line (at 0 -2.54 0) (length 2.54)
          (name "EN" (effects (font (size 1.27 1.27))))
          (number "2" (effects (font (size 1.27 1.27))))
        )
        (pin power_in line (at 0 -12.7 0) (length 2.54)
          (name "GND" (effects (font (size 1.27 1.27))))
          (number "3" (effects (font (size 1.27 1.27))))
        )
        (pin input line (at 0 -5.08 0) (length 2.54)
          (name "INV" (effects (font (size 1.27 1.27))))
          (number "4" (effects (font (size 1.27 1.27))))
        )
        (pin passive line (at 0 -7.62 0) (length 2.54)
          (name "TADJ" (effects (font (size 1.27 1.27))))
          (number "5" (effects (font (size 1.27 1.27))))
        )
        (pin open_collector line (at 17.78 -10.16 180) (length 2.54)
          (name "FLAG3" (effects (font (size 1.27 1.27))))
          (number "6" (effects (font (size 1.27 1.27))))
        )
        (pin open_collector line (at 17.78 -5.08 180) (length 2.54)
          (name "FLAG2" (effects (font (size 1.27 1.27))))
          (number "7" (effects (font (size 1.27 1.27))))
        )
        (pin open_collector line (at 17.78 0 180) (length 2.54)
          (name "FLAG1" (effects (font (size 1.27 1.27))))
          (number "8" (effects (font (size 1.27 1.27))))
        )
      )
    )
	(symbol "data-center-rdimm-ddr4-tester:L_1u5_6A_1716" (pin_numbers hide) (pin_names hide) (in_bom yes) (on_board yes)
      (property "Reference" "L" (at 15.24 -2.54 0)
        (effects (font (size 1.27 1.27) (thickness 0.15)) (justify left bottom))
      )
      (property "Value" "L_1u5_6A_1716" (at 15.24 -5.08 0)
        (effects (font (size 1.27 1.27) (thickness 0.15)) (justify left bottom) hide)
      )
      (property "Footprint" "data-center-rdimm-ddr4-tester-footprints:L_1716_4441Metric" (at 15.24 -10.16 0)
        (effects (font (size 1.27 1.27) (thickness 0.15)) (justify left bottom) hide)
      )
      (property "Datasheet" "https://www.mouser.pl/datasheet/2/54/srp0420-1838509.pdf" (at 15.24 -12.7 0)
        (effects (font (size 1.27 1.27) (thickness 0.15)) (justify left bottom) hide)
      )
      (property "MPN" "SRP0420-1R5K" (at 15.24 -15.24 0)
        (effects (font (size 1.27 1.27) (thickness 0.15)) (justify left bottom) hide)
      )
      (property "Manufacturer" "Bourns" (at 15.24 -17.78 0)
        (effects (font (size 1.27 1.27) (thickness 0.15)) (justify left bottom) hide)
      )
      (property "MaxCur" "6A" (at 15.24 -20.32 0)
        (effects (font (size 1.27 1.27) (thickness 0.15)) (justify left bottom) hide)
      )
      (property "ISat" "" (at 13.97 -16.51 0)
        (effects (font (size 1.27 1.27)) (justify left) hide)
      )
      (property "Size" "4.40x4.10" (at 15.24 -22.86 0)
        (effects (font (size 1.27 1.27) (thickness 0.15)) (justify left bottom) hide)
      )
      (property "IMax" "" (at 13.97 -20.32 0)
        (effects (font (size 1.27 1.27) (thickness 0.15)) (justify left bottom) hide)
      )
      (property "Val" "1u5/6A" (at 15.24 -7.62 0)
        (effects (font (size 1.27 1.27) (thickness 0.15)) (justify left bottom))
      )
      (property "Author" "Antmicro" (at 15.24 -25.4 0)
        (effects (font (size 1.27 1.27) (thickness 0.15)) (justify left bottom) hide)
      )
      (property "License" "Apache-2.0" (at 15.24 -27.94 0)
        (effects (font (size 1.27 1.27) (thickness 0.15)) (justify left bottom) hide)
      )
      (symbol "L_1u5_6A_1716_0_1"
        (arc (start 1.524 0) (mid 1.016 0.5058) (end 0.508 0)
          (stroke (width 0) (type default))
          (fill (type none))
        )
        (arc (start 2.54 0) (mid 2.032 0.5058) (end 1.524 0)
          (stroke (width 0) (type default))
          (fill (type none))
        )
        (arc (start 3.556 0) (mid 3.048 0.5058) (end 2.54 0)
          (stroke (width 0) (type default))
          (fill (type none))
        )
        (arc (start 4.572 0) (mid 4.064 0.5058) (end 3.556 0)
          (stroke (width 0) (type default))
          (fill (type none))
        )
      )
      (symbol "L_1u5_6A_1716_1_1"
        (pin passive line (at 0 0 0) (length 0.508)
          (name "~" (effects (font (size 1.27 1.27))))
          (number "1" (effects (font (size 1.27 1.27))))
        )
        (pin passive line (at 5.08 0 180) (length 0.508)
          (name "~" (effects (font (size 1.27 1.27))))
          (number "2" (effects (font (size 1.27 1.27))))
        )
      )
    )
	(symbol "data-center-rdimm-ddr4-tester:L_680n_6.1A_1210" (pin_numbers hide) (pin_names hide) (in_bom yes) (on_board yes)
      (property "Reference" "L" (at 13.97 0 0)
        (effects (font (size 1.27 1.27) (thickness 0.15)) (justify left bottom))
      )
      (property "Value" "L_680n_6.1A_1210" (at 13.97 -2.54 0)
        (effects (font (size 1.27 1.27) (thickness 0.15)) (justify left bottom) hide)
      )
      (property "Footprint" "data-center-rdimm-ddr4-tester-footprints:L_1210_3225Metric" (at 13.97 -7.62 0)
        (effects (font (size 1.27 1.27) (thickness 0.15)) (justify left bottom) hide)
      )
      (property "Datasheet" "https://www.murata.com/en-global/products/productdetail?partno=DFE322512F-R68M%23" (at 13.97 -10.16 0)
        (effects (font (size 1.27 1.27) (thickness 0.15)) (justify left bottom) hide)
      )
      (property "Val" "680n/6.1A" (at 13.97 -5.08 0)
        (effects (font (size 1.27 1.27) (thickness 0.15)) (justify left bottom))
      )
      (property "Manufacturer" "Murata" (at 13.97 -12.7 0)
        (effects (font (size 1.27 1.27) (thickness 0.15)) (justify left bottom) hide)
      )
      (property "MPN" "DFE322512F-R68M=P2" (at 13.97 -15.24 0)
        (effects (font (size 1.27 1.27) (thickness 0.15)) (justify left bottom) hide)
      )
      (property "ISat" "" (at 13.97 -16.51 0)
        (effects (font (size 1.27 1.27)) (justify left) hide)
      )
      (property "IMax" "" (at 13.97 -20.32 0)
        (effects (font (size 1.27 1.27) (thickness 0.15)) (justify left bottom) hide)
      )
      (property "Size" "3.2x2.5" (at 13.97 -22.86 0)
        (effects (font (size 1.27 1.27) (thickness 0.15)) (justify left bottom) hide)
      )
      (property "Author" "Antmicro" (at 13.97 -25.4 0)
        (effects (font (size 1.27 1.27) (thickness 0.15)) (justify left bottom) hide)
      )
      (property "License" "Apache-2.0" (at 13.97 -27.94 0)
        (effects (font (size 1.27 1.27) (thickness 0.15)) (justify left bottom) hide)
      )
      (symbol "L_680n_6.1A_1210_0_1"
        (arc (start 1.524 0) (mid 1.016 0.5058) (end 0.508 0)
          (stroke (width 0) (type default))
          (fill (type none))
        )
        (arc (start 2.54 0) (mid 2.032 0.5058) (end 1.524 0)
          (stroke (width 0) (type default))
          (fill (type none))
        )
        (arc (start 3.556 0) (mid 3.048 0.5058) (end 2.54 0)
          (stroke (width 0) (type default))
          (fill (type none))
        )
        (arc (start 4.572 0) (mid 4.064 0.5058) (end 3.556 0)
          (stroke (width 0) (type default))
          (fill (type none))
        )
      )
      (symbol "L_680n_6.1A_1210_1_1"
        (pin passive line (at 0 0 0) (length 0.508)
          (name "~" (effects (font (size 1.27 1.27))))
          (number "1" (effects (font (size 1.27 1.27))))
        )
        (pin passive line (at 5.08 0 180) (length 0.508)
          (name "~" (effects (font (size 1.27 1.27))))
          (number "2" (effects (font (size 1.27 1.27))))
        )
      )
    )
	(symbol "data-center-rdimm-ddr4-tester:L_7u2_7.9A_WE-PDF" (pin_numbers hide) (pin_names hide) (in_bom yes) (on_board yes)
      (property "Reference" "L" (at 13.97 0 0)
        (effects (font (size 1.27 1.27) (thickness 0.15)) (justify left bottom))
      )
      (property "Value" "L_7u2_7.9A_WE-PDF" (at 13.97 -2.54 0)
        (effects (font (size 1.27 1.27) (thickness 0.15)) (justify left bottom) hide)
      )
      (property "Footprint" "data-center-rdimm-ddr4-tester-footprints:L_WE-PDF" (at 13.97 -7.62 0)
        (effects (font (size 1.27 1.27) (thickness 0.15)) (justify left bottom) hide)
      )
      (property "Datasheet" "https://www.we-online.com/catalog/datasheet/7447798720.pdf" (at 13.97 -10.16 0)
        (effects (font (size 1.27 1.27) (thickness 0.15)) (justify left bottom) hide)
      )
      (property "Val" "7u2/7.9A" (at 13.97 -5.08 0)
        (effects (font (size 1.27 1.27) (thickness 0.15)) (justify left bottom))
      )
      (property "Manufacturer" "Würth Elektronik" (at 13.97 -12.7 0)
        (effects (font (size 1.27 1.27) (thickness 0.15)) (justify left bottom) hide)
      )
      (property "MPN" "7447798720" (at 13.97 -15.24 0)
        (effects (font (size 1.27 1.27) (thickness 0.15)) (justify left bottom) hide)
      )
      (property "ISat" "" (at 13.97 -16.51 0)
        (effects (font (size 1.27 1.27)) (justify left) hide)
      )
      (property "IMax" "" (at 13.97 -20.32 0)
        (effects (font (size 1.27 1.27) (thickness 0.15)) (justify left bottom) hide)
      )
      (property "Size" "10.2x10.2" (at 13.97 -22.86 0)
        (effects (font (size 1.27 1.27) (thickness 0.15)) (justify left bottom) hide)
      )
      (property "Author" "Antmicro" (at 13.97 -25.4 0)
        (effects (font (size 1.27 1.27) (thickness 0.15)) (justify left bottom) hide)
      )
      (property "License" "Apache-2.0" (at 13.97 -27.94 0)
        (effects (font (size 1.27 1.27) (thickness 0.15)) (justify left bottom) hide)
      )
      (symbol "L_7u2_7.9A_WE-PDF_0_1"
        (arc (start 1.524 0) (mid 1.016 0.5058) (end 0.508 0)
          (stroke (width 0) (type default))
          (fill (type none))
        )
        (arc (start 2.54 0) (mid 2.032 0.5058) (end 1.524 0)
          (stroke (width 0) (type default))
          (fill (type none))
        )
        (arc (start 3.556 0) (mid 3.048 0.5058) (end 2.54 0)
          (stroke (width 0) (type default))
          (fill (type none))
        )
        (arc (start 4.572 0) (mid 4.064 0.5058) (end 3.556 0)
          (stroke (width 0) (type default))
          (fill (type none))
        )
      )
      (symbol "L_7u2_7.9A_WE-PDF_1_1"
        (pin passive line (at 0 0 0) (length 0.508)
          (name "~" (effects (font (size 1.27 1.27))))
          (number "1" (effects (font (size 1.27 1.27))))
        )
        (pin passive line (at 5.08 0 180) (length 0.508)
          (name "~" (effects (font (size 1.27 1.27))))
          (number "2" (effects (font (size 1.27 1.27))))
        )
      )
    )
	(symbol "data-center-rdimm-ddr4-tester:Mech_Lightpipe_Mentor_1296.2013" (in_bom yes) (on_board yes)
      (property "Reference" "M" (at 20.32 -2.54 0)
        (effects (font (size 1.27 1.27) (thickness 0.15)) (justify left bottom))
      )
      (property "Value" "Mech_Lightpipe_Mentor_1296.2013" (at 20.32 -5.08 0)
        (effects (font (size 1.27 1.27) (thickness 0.15)) (justify left bottom))
      )
      (property "Footprint" "data-center-rdimm-ddr4-tester-footprints:Mech_Lightpipe_Mentor_1296.2013" (at 20.32 -7.62 0)
        (effects (font (size 1.27 1.27) (thickness 0.15)) (justify left bottom) hide)
      )
      (property "Datasheet" "https://docs.rs-online.com/e47b/0900766b813f6efb.pdf" (at 20.32 -10.16 0)
        (effects (font (size 1.27 1.27) (thickness 0.15)) (justify left bottom) hide)
      )
      (property "Manufacturer" "MENTOR" (at 20.32 -12.7 0)
        (effects (font (size 1.27 1.27) (thickness 0.15)) (justify left bottom) hide)
      )
      (property "MPN" "1296.2013" (at 20.32 -15.24 0)
        (effects (font (size 1.27 1.27) (thickness 0.15)) (justify left bottom) hide)
      )
      (property "Author" "Antmicro" (at 20.32 -17.78 0)
        (effects (font (size 1.27 1.27) (thickness 0.15)) (justify left bottom) hide)
      )
      (property "License" "Apache-2.0" (at 20.32 -20.32 0)
        (effects (font (size 1.27 1.27) (thickness 0.15)) (justify left bottom) hide)
      )
      (property "ki_description" "PCB Mounted 3-Way Right Angle LED Light Pipe, Tri-Level-Row Clear Dome Lens" (at 0 0 0)
        (effects (font (size 1.27 1.27)) hide)
      )
      (symbol "Mech_Lightpipe_Mentor_1296.2013_1_1"
        (rectangle (start 5.08 -2.54) (end -5.08 3.81)
          (stroke (width 0.254) (type default))
          (fill (type background))
        )
        (text "1x3" (at -1.905 -2.54 0)
          (effects (font (size 1.27 1.27) (thickness 0.15)) (justify left bottom))
        )
        (text "Horizontal" (at -5.08 1.524 0)
          (effects (font (size 1.27 1.27) (thickness 0.15)) (justify left bottom))
        )
        (text "lightguide" (at -4.826 -0.508 0)
          (effects (font (size 1.27 1.27) (thickness 0.15)) (justify left bottom))
        )
      )
    )
	(symbol "data-center-rdimm-ddr4-tester:Net-Tie_2" (pin_numbers hide) (pin_names hide) (in_bom yes) (on_board yes)
      (property "Reference" "TP" (at 21.59 0 0)
        (effects (font (size 1.27 1.27) (thickness 0.15)) (justify left bottom))
      )
      (property "Value" "Net-Tie_2" (at 21.59 -2.54 0)
        (effects (font (size 1.27 1.27) (thickness 0.15)) (justify left bottom))
      )
      (property "Footprint" "data-center-rdimm-ddr4-tester-footprints:NetTie-2_SMD_Pad0.127mm" (at 21.59 -5.08 0)
        (effects (font (size 1.27 1.27) (thickness 0.15)) (justify left bottom) hide)
      )
      (property "Datasheet" "" (at 21.59 -7.62 0)
        (effects (font (size 1.27 1.27) (thickness 0.15)) (justify left bottom) hide)
      )
      (property "MPN" "" (at 21.59 -8.89 0)
        (effects (font (size 1.27 1.27)) (justify left) hide)
      )
      (property "Manufacturer" "" (at 21.59 -11.43 0)
        (effects (font (size 1.27 1.27)) (justify left) hide)
      )
      (property "Author" "Antmicro" (at 21.59 -15.24 0)
        (effects (font (size 1.27 1.27) (thickness 0.15)) (justify left bottom) hide)
      )
      (property "License" "Apache-2.0" (at 21.59 -17.78 0)
        (effects (font (size 1.27 1.27) (thickness 0.15)) (justify left bottom) hide)
      )
      (property "ki_keywords" "net tie short" (at 0 0 0)
        (effects (font (size 1.27 1.27)) hide)
      )
      (property "ki_description" "Net tie, 2 pins" (at 0 0 0)
        (effects (font (size 1.27 1.27)) hide)
      )
      (property "ki_fp_filters" "Net*Tie*" (at 0 0 0)
        (effects (font (size 1.27 1.27)) hide)
      )
      (symbol "Net-Tie_2_1_1"
        (polyline
          (pts
            (xy 1.27 0)
            (xy 2.54 0)
          )
          (stroke (width 0.254) (type default))
          (fill (type background))
        )
        (pin passive line (at 0 0 0) (length 1.27)
          (name "1" (effects (font (size 1.27 1.27))))
          (number "1" (effects (font (size 1.27 1.27))))
        )
        (pin passive line (at 3.81 0 180) (length 1.27)
          (name "2" (effects (font (size 1.27 1.27))))
          (number "2" (effects (font (size 1.27 1.27))))
        )
      )
    )
	(symbol "data-center-rdimm-ddr4-tester:Net-Tie_2_10" (pin_numbers hide) (pin_names hide) (in_bom yes) (on_board yes)
      (property "Reference" "TP" (at 21.59 0 0)
        (effects (font (size 1.27 1.27) (thickness 0.15)) (justify left bottom))
      )
      (property "Value" "Net-Tie_2_10" (at 21.59 -2.54 0)
        (effects (font (size 1.27 1.27) (thickness 0.15)) (justify left bottom))
      )
      (property "Footprint" "data-center-rdimm-ddr4-tester-footprints:NetTie-2_SMD_Pad0.127mm" (at 21.59 -5.08 0)
        (effects (font (size 1.27 1.27) (thickness 0.15)) (justify left bottom) hide)
      )
      (property "Datasheet" "" (at 21.59 -7.62 0)
        (effects (font (size 1.27 1.27) (thickness 0.15)) (justify left bottom) hide)
      )
      (property "MPN" "" (at 21.59 -8.89 0)
        (effects (font (size 1.27 1.27)) (justify left) hide)
      )
      (property "Manufacturer" "" (at 21.59 -11.43 0)
        (effects (font (size 1.27 1.27)) (justify left) hide)
      )
      (property "Author" "Antmicro" (at 21.59 -15.24 0)
        (effects (font (size 1.27 1.27) (thickness 0.15)) (justify left bottom) hide)
      )
      (property "License" "Apache-2.0" (at 21.59 -17.78 0)
        (effects (font (size 1.27 1.27) (thickness 0.15)) (justify left bottom) hide)
      )
      (property "ki_keywords" "net tie short" (at 0 0 0)
        (effects (font (size 1.27 1.27)) hide)
      )
      (property "ki_description" "Net tie, 2 pins" (at 0 0 0)
        (effects (font (size 1.27 1.27)) hide)
      )
      (property "ki_fp_filters" "Net*Tie*" (at 0 0 0)
        (effects (font (size 1.27 1.27)) hide)
      )
      (symbol "Net-Tie_2_10_1_1"
        (polyline
          (pts
            (xy 1.27 0)
            (xy 2.54 0)
          )
          (stroke (width 0.254) (type default))
          (fill (type background))
        )
        (pin passive line (at 0 0 0) (length 1.27)
          (name "1" (effects (font (size 1.27 1.27))))
          (number "1" (effects (font (size 1.27 1.27))))
        )
        (pin passive line (at 3.81 0 180) (length 1.27)
          (name "2" (effects (font (size 1.27 1.27))))
          (number "2" (effects (font (size 1.27 1.27))))
        )
      )
    )
	(symbol "data-center-rdimm-ddr4-tester:Net-Tie_2_11" (pin_numbers hide) (pin_names hide) (in_bom yes) (on_board yes)
      (property "Reference" "TP" (at 21.59 0 0)
        (effects (font (size 1.27 1.27) (thickness 0.15)) (justify left bottom))
      )
      (property "Value" "Net-Tie_2_11" (at 21.59 -2.54 0)
        (effects (font (size 1.27 1.27) (thickness 0.15)) (justify left bottom))
      )
      (property "Footprint" "data-center-rdimm-ddr4-tester-footprints:NetTie-2_SMD_Pad0.127mm" (at 21.59 -5.08 0)
        (effects (font (size 1.27 1.27) (thickness 0.15)) (justify left bottom) hide)
      )
      (property "Datasheet" "" (at 21.59 -7.62 0)
        (effects (font (size 1.27 1.27) (thickness 0.15)) (justify left bottom) hide)
      )
      (property "MPN" "" (at 21.59 -8.89 0)
        (effects (font (size 1.27 1.27)) (justify left) hide)
      )
      (property "Manufacturer" "" (at 21.59 -11.43 0)
        (effects (font (size 1.27 1.27)) (justify left) hide)
      )
      (property "Author" "Antmicro" (at 21.59 -15.24 0)
        (effects (font (size 1.27 1.27) (thickness 0.15)) (justify left bottom) hide)
      )
      (property "License" "Apache-2.0" (at 21.59 -17.78 0)
        (effects (font (size 1.27 1.27) (thickness 0.15)) (justify left bottom) hide)
      )
      (property "ki_keywords" "net tie short" (at 0 0 0)
        (effects (font (size 1.27 1.27)) hide)
      )
      (property "ki_description" "Net tie, 2 pins" (at 0 0 0)
        (effects (font (size 1.27 1.27)) hide)
      )
      (property "ki_fp_filters" "Net*Tie*" (at 0 0 0)
        (effects (font (size 1.27 1.27)) hide)
      )
      (symbol "Net-Tie_2_11_1_1"
        (polyline
          (pts
            (xy 1.27 0)
            (xy 2.54 0)
          )
          (stroke (width 0.254) (type default))
          (fill (type background))
        )
        (pin passive line (at 0 0 0) (length 1.27)
          (name "1" (effects (font (size 1.27 1.27))))
          (number "1" (effects (font (size 1.27 1.27))))
        )
        (pin passive line (at 3.81 0 180) (length 1.27)
          (name "2" (effects (font (size 1.27 1.27))))
          (number "2" (effects (font (size 1.27 1.27))))
        )
      )
    )
	(symbol "data-center-rdimm-ddr4-tester:Net-Tie_2_12" (pin_numbers hide) (pin_names hide) (in_bom yes) (on_board yes)
      (property "Reference" "TP" (at 21.59 0 0)
        (effects (font (size 1.27 1.27) (thickness 0.15)) (justify left bottom))
      )
      (property "Value" "Net-Tie_2_12" (at 21.59 -2.54 0)
        (effects (font (size 1.27 1.27) (thickness 0.15)) (justify left bottom))
      )
      (property "Footprint" "data-center-rdimm-ddr4-tester-footprints:NetTie-2_SMD_Pad0.127mm" (at 21.59 -5.08 0)
        (effects (font (size 1.27 1.27) (thickness 0.15)) (justify left bottom) hide)
      )
      (property "Datasheet" "" (at 21.59 -7.62 0)
        (effects (font (size 1.27 1.27) (thickness 0.15)) (justify left bottom) hide)
      )
      (property "MPN" "" (at 21.59 -8.89 0)
        (effects (font (size 1.27 1.27)) (justify left) hide)
      )
      (property "Manufacturer" "" (at 21.59 -11.43 0)
        (effects (font (size 1.27 1.27)) (justify left) hide)
      )
      (property "Author" "Antmicro" (at 21.59 -15.24 0)
        (effects (font (size 1.27 1.27) (thickness 0.15)) (justify left bottom) hide)
      )
      (property "License" "Apache-2.0" (at 21.59 -17.78 0)
        (effects (font (size 1.27 1.27) (thickness 0.15)) (justify left bottom) hide)
      )
      (property "ki_keywords" "net tie short" (at 0 0 0)
        (effects (font (size 1.27 1.27)) hide)
      )
      (property "ki_description" "Net tie, 2 pins" (at 0 0 0)
        (effects (font (size 1.27 1.27)) hide)
      )
      (property "ki_fp_filters" "Net*Tie*" (at 0 0 0)
        (effects (font (size 1.27 1.27)) hide)
      )
      (symbol "Net-Tie_2_12_1_1"
        (polyline
          (pts
            (xy 1.27 0)
            (xy 2.54 0)
          )
          (stroke (width 0.254) (type default))
          (fill (type background))
        )
        (pin passive line (at 0 0 0) (length 1.27)
          (name "1" (effects (font (size 1.27 1.27))))
          (number "1" (effects (font (size 1.27 1.27))))
        )
        (pin passive line (at 3.81 0 180) (length 1.27)
          (name "2" (effects (font (size 1.27 1.27))))
          (number "2" (effects (font (size 1.27 1.27))))
        )
      )
    )
	(symbol "data-center-rdimm-ddr4-tester:Net-Tie_2_13" (pin_numbers hide) (pin_names hide) (in_bom yes) (on_board yes)
      (property "Reference" "TP" (at 21.59 0 0)
        (effects (font (size 1.27 1.27) (thickness 0.15)) (justify left bottom))
      )
      (property "Value" "Net-Tie_2_13" (at 21.59 -2.54 0)
        (effects (font (size 1.27 1.27) (thickness 0.15)) (justify left bottom))
      )
      (property "Footprint" "data-center-rdimm-ddr4-tester-footprints:NetTie-2_SMD_Pad0.127mm" (at 21.59 -5.08 0)
        (effects (font (size 1.27 1.27) (thickness 0.15)) (justify left bottom) hide)
      )
      (property "Datasheet" "" (at 21.59 -7.62 0)
        (effects (font (size 1.27 1.27) (thickness 0.15)) (justify left bottom) hide)
      )
      (property "MPN" "" (at 21.59 -8.89 0)
        (effects (font (size 1.27 1.27)) (justify left) hide)
      )
      (property "Manufacturer" "" (at 21.59 -11.43 0)
        (effects (font (size 1.27 1.27)) (justify left) hide)
      )
      (property "Author" "Antmicro" (at 21.59 -15.24 0)
        (effects (font (size 1.27 1.27) (thickness 0.15)) (justify left bottom) hide)
      )
      (property "License" "Apache-2.0" (at 21.59 -17.78 0)
        (effects (font (size 1.27 1.27) (thickness 0.15)) (justify left bottom) hide)
      )
      (property "ki_keywords" "net tie short" (at 0 0 0)
        (effects (font (size 1.27 1.27)) hide)
      )
      (property "ki_description" "Net tie, 2 pins" (at 0 0 0)
        (effects (font (size 1.27 1.27)) hide)
      )
      (property "ki_fp_filters" "Net*Tie*" (at 0 0 0)
        (effects (font (size 1.27 1.27)) hide)
      )
      (symbol "Net-Tie_2_13_1_1"
        (polyline
          (pts
            (xy 1.27 0)
            (xy 2.54 0)
          )
          (stroke (width 0.254) (type default))
          (fill (type background))
        )
        (pin passive line (at 0 0 0) (length 1.27)
          (name "1" (effects (font (size 1.27 1.27))))
          (number "1" (effects (font (size 1.27 1.27))))
        )
        (pin passive line (at 3.81 0 180) (length 1.27)
          (name "2" (effects (font (size 1.27 1.27))))
          (number "2" (effects (font (size 1.27 1.27))))
        )
      )
    )
	(symbol "data-center-rdimm-ddr4-tester:Net-Tie_2_14" (pin_numbers hide) (pin_names hide) (in_bom yes) (on_board yes)
      (property "Reference" "TP" (at 21.59 0 0)
        (effects (font (size 1.27 1.27) (thickness 0.15)) (justify left bottom))
      )
      (property "Value" "Net-Tie_2_14" (at 21.59 -2.54 0)
        (effects (font (size 1.27 1.27) (thickness 0.15)) (justify left bottom))
      )
      (property "Footprint" "data-center-rdimm-ddr4-tester-footprints:NetTie-2_SMD_Pad0.127mm" (at 21.59 -5.08 0)
        (effects (font (size 1.27 1.27) (thickness 0.15)) (justify left bottom) hide)
      )
      (property "Datasheet" "" (at 21.59 -7.62 0)
        (effects (font (size 1.27 1.27) (thickness 0.15)) (justify left bottom) hide)
      )
      (property "MPN" "" (at 21.59 -8.89 0)
        (effects (font (size 1.27 1.27)) (justify left) hide)
      )
      (property "Manufacturer" "" (at 21.59 -11.43 0)
        (effects (font (size 1.27 1.27)) (justify left) hide)
      )
      (property "Author" "Antmicro" (at 21.59 -15.24 0)
        (effects (font (size 1.27 1.27) (thickness 0.15)) (justify left bottom) hide)
      )
      (property "License" "Apache-2.0" (at 21.59 -17.78 0)
        (effects (font (size 1.27 1.27) (thickness 0.15)) (justify left bottom) hide)
      )
      (property "ki_keywords" "net tie short" (at 0 0 0)
        (effects (font (size 1.27 1.27)) hide)
      )
      (property "ki_description" "Net tie, 2 pins" (at 0 0 0)
        (effects (font (size 1.27 1.27)) hide)
      )
      (property "ki_fp_filters" "Net*Tie*" (at 0 0 0)
        (effects (font (size 1.27 1.27)) hide)
      )
      (symbol "Net-Tie_2_14_1_1"
        (polyline
          (pts
            (xy 1.27 0)
            (xy 2.54 0)
          )
          (stroke (width 0.254) (type default))
          (fill (type background))
        )
        (pin passive line (at 0 0 0) (length 1.27)
          (name "1" (effects (font (size 1.27 1.27))))
          (number "1" (effects (font (size 1.27 1.27))))
        )
        (pin passive line (at 3.81 0 180) (length 1.27)
          (name "2" (effects (font (size 1.27 1.27))))
          (number "2" (effects (font (size 1.27 1.27))))
        )
      )
    )
	(symbol "data-center-rdimm-ddr4-tester:Net-Tie_2_15" (pin_numbers hide) (pin_names hide) (in_bom yes) (on_board yes)
      (property "Reference" "TP" (at 21.59 0 0)
        (effects (font (size 1.27 1.27) (thickness 0.15)) (justify left bottom))
      )
      (property "Value" "Net-Tie_2_15" (at 21.59 -2.54 0)
        (effects (font (size 1.27 1.27) (thickness 0.15)) (justify left bottom))
      )
      (property "Footprint" "data-center-rdimm-ddr4-tester-footprints:NetTie-2_SMD_Pad0.127mm" (at 21.59 -5.08 0)
        (effects (font (size 1.27 1.27) (thickness 0.15)) (justify left bottom) hide)
      )
      (property "Datasheet" "" (at 21.59 -7.62 0)
        (effects (font (size 1.27 1.27) (thickness 0.15)) (justify left bottom) hide)
      )
      (property "MPN" "" (at 21.59 -8.89 0)
        (effects (font (size 1.27 1.27)) (justify left) hide)
      )
      (property "Manufacturer" "" (at 21.59 -11.43 0)
        (effects (font (size 1.27 1.27)) (justify left) hide)
      )
      (property "Author" "Antmicro" (at 21.59 -15.24 0)
        (effects (font (size 1.27 1.27) (thickness 0.15)) (justify left bottom) hide)
      )
      (property "License" "Apache-2.0" (at 21.59 -17.78 0)
        (effects (font (size 1.27 1.27) (thickness 0.15)) (justify left bottom) hide)
      )
      (property "ki_keywords" "net tie short" (at 0 0 0)
        (effects (font (size 1.27 1.27)) hide)
      )
      (property "ki_description" "Net tie, 2 pins" (at 0 0 0)
        (effects (font (size 1.27 1.27)) hide)
      )
      (property "ki_fp_filters" "Net*Tie*" (at 0 0 0)
        (effects (font (size 1.27 1.27)) hide)
      )
      (symbol "Net-Tie_2_15_1_1"
        (polyline
          (pts
            (xy 1.27 0)
            (xy 2.54 0)
          )
          (stroke (width 0.254) (type default))
          (fill (type background))
        )
        (pin passive line (at 0 0 0) (length 1.27)
          (name "1" (effects (font (size 1.27 1.27))))
          (number "1" (effects (font (size 1.27 1.27))))
        )
        (pin passive line (at 3.81 0 180) (length 1.27)
          (name "2" (effects (font (size 1.27 1.27))))
          (number "2" (effects (font (size 1.27 1.27))))
        )
      )
    )
	(symbol "data-center-rdimm-ddr4-tester:Oscillator_SMD_100MHz_ASFLMB" (in_bom yes) (on_board yes)
      (property "Reference" "Y" (at 40.64 -2.54 0)
        (effects (font (size 1.27 1.27) (thickness 0.15)) (justify left bottom))
      )
      (property "Value" "Oscillator_SMD_100MHz_ASFLMB" (at 40.64 -5.08 0)
        (effects (font (size 1.27 1.27) (thickness 0.15)) (justify left bottom))
      )
      (property "Footprint" "data-center-rdimm-ddr4-tester-footprints:Oscillator_SMD_Abracon_ASFLMB_5x3.2x0.85mm" (at 40.64 -7.62 0)
        (effects (font (size 1.27 1.27) (thickness 0.15)) (justify left bottom) hide)
      )
      (property "Datasheet" "https://abracon.com/Oscillators/ASFLMB.pdf" (at 40.64 -10.16 0)
        (effects (font (size 1.27 1.27) (thickness 0.15)) (justify left bottom) hide)
      )
      (property "Manufacturer" "Abracon" (at 40.64 -12.7 0)
        (effects (font (size 1.27 1.27) (thickness 0.15)) (justify left bottom) hide)
      )
      (property "MPN" "ASFLMB-100.000MHZ-XY-T" (at 40.64 -15.24 0)
        (effects (font (size 1.27 1.27) (thickness 0.15)) (justify left bottom) hide)
      )
      (property "Author" "Antmicro" (at 40.64 -17.78 0)
        (effects (font (size 1.27 1.27) (thickness 0.15)) (justify left bottom) hide)
      )
      (property "License" "Apache-2.0" (at 40.64 -20.32 0)
        (effects (font (size 1.27 1.27) (thickness 0.15)) (justify left bottom) hide)
      )
      (property "ki_keywords" "MEMS OSC XO 100.0000MHZ LVCMOS" (at 0 0 0)
        (effects (font (size 1.27 1.27)) hide)
      )
      (property "ki_description" "MEMS OSC XO 100.0000MHZ LVCMOS" (at 0 0 0)
        (effects (font (size 1.27 1.27)) hide)
      )
      (property "ki_fp_filters" "CHIP_100.000MHZ-LC-T_ABR CHIP_100.000MHZ-LC-T_ABR-M CHIP_100.000MHZ-LC-T_ABR-L" (at 0 0 0)
        (effects (font (size 1.27 1.27)) hide)
      )
      (symbol "Oscillator_SMD_100MHz_ASFLMB_1_1"
        (rectangle (start 2.54 2.54) (end 13.97 -5.08)
          (stroke (width 0.254) (type default))
          (fill (type background))
        )
        (pin input line (at 0 -2.54 0) (length 2.54)
          (name "~{STDB}" (effects (font (size 1.27 1.27))))
          (number "1" (effects (font (size 1.27 1.27))))
        )
        (pin unspecified line (at 16.51 -2.54 180) (length 2.54)
          (name "GND" (effects (font (size 1.27 1.27))))
          (number "2" (effects (font (size 1.27 1.27))))
        )
        (pin output line (at 16.51 0 180) (length 2.54)
          (name "OUT" (effects (font (size 1.27 1.27))))
          (number "3" (effects (font (size 1.27 1.27))))
        )
        (pin power_in line (at 0 0 0) (length 2.54)
          (name "V_{DD}" (effects (font (size 1.27 1.27))))
          (number "4" (effects (font (size 1.27 1.27))))
        )
      )
    )
	(symbol "data-center-rdimm-ddr4-tester:Oscillator_SMD_12MHz_KX-7" (pin_names hide) (in_bom yes) (on_board yes)
      (property "Reference" "Y" (at 25.4 -5.08 0)
        (effects (font (size 1.27 1.27) (thickness 0.15)) (justify left bottom))
      )
      (property "Value" "Oscillator_SMD_12MHz_KX-7" (at 25.4 -7.62 0)
        (effects (font (size 1.27 1.27) (thickness 0.15)) (justify left bottom))
      )
      (property "Footprint" "data-center-rdimm-ddr4-tester-footprints:Oscillator_SMD_Geyer_KX-7-4Pin_3.2x2.5mm" (at 25.4 -10.16 0)
        (effects (font (size 1.27 1.27) (thickness 0.15)) (justify left bottom) hide)
      )
      (property "Datasheet" "" (at 25.4 -12.7 0)
        (effects (font (size 1.27 1.27) (thickness 0.15)) (justify left bottom) hide)
      )
      (property "MPN" "ABM8G-12.000MHZ-18-D2Y-T " (at 25.4 -15.24 0)
        (effects (font (size 1.27 1.27) (thickness 0.15)) (justify left bottom) hide)
      )
      (property "Manufacturer" "Abracon" (at 25.4 -17.78 0)
        (effects (font (size 1.27 1.27) (thickness 0.15)) (justify left bottom) hide)
      )
      (property "Val" "12MHz" (at 25.4 -20.32 0)
        (effects (font (size 1.27 1.27) (thickness 0.15)) (justify left bottom) hide)
      )
      (property "Author" "Antmicro" (at 25.4 -22.86 0)
        (effects (font (size 1.27 1.27) (thickness 0.15)) (justify left bottom) hide)
      )
      (property "License" "Apache-2.0" (at 25.4 -25.4 0)
        (effects (font (size 1.27 1.27) (thickness 0.15)) (justify left bottom) hide)
      )
      (symbol "Oscillator_SMD_12MHz_KX-7_1_1"
        (polyline
          (pts
            (xy 2.54 1.27)
            (xy 2.54 -1.27)
          )
          (stroke (width 0.254) (type default))
          (fill (type background))
        )
        (polyline
          (pts
            (xy 5.08 1.27)
            (xy 5.08 -1.27)
          )
          (stroke (width 0.254) (type default))
          (fill (type background))
        )
        (polyline
          (pts
            (xy 1.905 -1.905)
            (xy 1.905 -2.54)
            (xy 5.715 -2.54)
            (xy 5.715 -1.905)
          )
          (stroke (width 0.254) (type default))
          (fill (type none))
        )
        (polyline
          (pts
            (xy 1.905 1.905)
            (xy 1.905 2.54)
            (xy 5.715 2.54)
            (xy 5.715 1.905)
          )
          (stroke (width 0.254) (type default))
          (fill (type none))
        )
        (rectangle (start 3.175 1.905) (end 4.445 -1.905)
          (stroke (width 0.254) (type default))
          (fill (type background))
        )
        (pin passive line (at 0 0 0) (length 2.54)
          (name "~" (effects (font (size 1.27 1.27))))
          (number "1" (effects (font (size 1.27 1.27))))
        )
        (pin passive line (at 3.81 -5.08 90) (length 2.54)
          (name "SH" (effects (font (size 1.27 1.27))))
          (number "2" (effects (font (size 1.27 1.27))))
        )
        (pin passive line (at 7.62 0 180) (length 2.54)
          (name "~" (effects (font (size 1.27 1.27))))
          (number "3" (effects (font (size 1.27 1.27))))
        )
        (pin passive line (at 3.81 -5.08 90) (length 2.54) hide
          (name "SH" (effects (font (size 1.27 1.27))))
          (number "4" (effects (font (size 1.27 1.27))))
        )
      )
    )
	(symbol "data-center-rdimm-ddr4-tester:Oscillator_SMD_25MHz_KX-7" (pin_names hide) (in_bom yes) (on_board yes)
      (property "Reference" "Y" (at 22.86 -5.08 0)
        (effects (font (size 1.27 1.27) (thickness 0.15)) (justify left bottom))
      )
      (property "Value" "Oscillator_SMD_25MHz_KX-7" (at 22.86 -7.62 0)
        (effects (font (size 1.27 1.27) (thickness 0.15)) (justify left bottom))
      )
      (property "Footprint" "data-center-rdimm-ddr4-tester-footprints:Oscillator_SMD_Geyer_KX-7-4Pin_3.2x2.5mm" (at 22.86 -10.16 0)
        (effects (font (size 1.27 1.27) (thickness 0.15)) (justify left bottom) hide)
      )
      (property "Datasheet" "" (at 22.86 -12.7 0)
        (effects (font (size 1.27 1.27) (thickness 0.15)) (justify left bottom) hide)
      )
      (property "MPN" "ABM8G-25.000MHZ-18-D2Y-T" (at 22.86 -15.24 0)
        (effects (font (size 1.27 1.27) (thickness 0.15)) (justify left bottom) hide)
      )
      (property "Manufacturer" "Abracon" (at 22.86 -17.78 0)
        (effects (font (size 1.27 1.27) (thickness 0.15)) (justify left bottom) hide)
      )
      (property "Val" "25MHz" (at 22.86 -20.32 0)
        (effects (font (size 1.27 1.27) (thickness 0.15)) (justify left bottom) hide)
      )
      (property "Author" "Antmicro" (at 22.86 -22.86 0)
        (effects (font (size 1.27 1.27) (thickness 0.15)) (justify left bottom) hide)
      )
      (property "License" "Apache-2.0" (at 22.86 -25.4 0)
        (effects (font (size 1.27 1.27) (thickness 0.15)) (justify left bottom) hide)
      )
      (property "ki_description" "25 MHz ±20ppm Crystal 18pF 60 Ohms 4-SMD, No Lead" (at 0 0 0)
        (effects (font (size 1.27 1.27)) hide)
      )
      (symbol "Oscillator_SMD_25MHz_KX-7_1_1"
        (polyline
          (pts
            (xy 2.54 1.27)
            (xy 2.54 -1.27)
          )
          (stroke (width 0.254) (type default))
          (fill (type background))
        )
        (polyline
          (pts
            (xy 5.08 1.27)
            (xy 5.08 -1.27)
          )
          (stroke (width 0.254) (type default))
          (fill (type background))
        )
        (polyline
          (pts
            (xy 1.905 -1.905)
            (xy 1.905 -2.54)
            (xy 5.715 -2.54)
            (xy 5.715 -1.905)
          )
          (stroke (width 0.254) (type default))
          (fill (type none))
        )
        (polyline
          (pts
            (xy 1.905 1.905)
            (xy 1.905 2.54)
            (xy 5.715 2.54)
            (xy 5.715 1.905)
          )
          (stroke (width 0.254) (type default))
          (fill (type none))
        )
        (rectangle (start 3.175 1.905) (end 4.445 -1.905)
          (stroke (width 0.254) (type default))
          (fill (type background))
        )
        (pin passive line (at 0 0 0) (length 2.54)
          (name "~" (effects (font (size 1.27 1.27))))
          (number "1" (effects (font (size 1.27 1.27))))
        )
        (pin passive line (at 3.81 -5.08 90) (length 2.54)
          (name "SH" (effects (font (size 1.27 1.27))))
          (number "2" (effects (font (size 1.27 1.27))))
        )
        (pin passive line (at 7.62 0 180) (length 2.54)
          (name "~" (effects (font (size 1.27 1.27))))
          (number "3" (effects (font (size 1.27 1.27))))
        )
        (pin passive line (at 3.81 -5.08 90) (length 2.54) hide
          (name "SH" (effects (font (size 1.27 1.27))))
          (number "4" (effects (font (size 1.27 1.27))))
        )
      )
    )
	(symbol "data-center-rdimm-ddr4-tester:PCB_Mount_Hole_3mm_NPTH" (pin_names hide) (in_bom yes) (on_board yes)
      (property "Reference" "MP" (at 17.78 -2.54 0)
        (effects (font (size 1.27 1.27) (thickness 0.15)) (justify left bottom))
      )
      (property "Value" "PCB_Mount_Hole_3mm_NPTH" (at 17.78 -5.08 0)
        (effects (font (size 1.27 1.27) (thickness 0.15)) (justify left bottom))
      )
      (property "Footprint" "data-center-rdimm-ddr4-tester-footprints:mounting-hole-3mm-NPTH" (at 17.78 -7.62 0)
        (effects (font (size 1.27 1.27) (thickness 0.15)) (justify left bottom) hide)
      )
      (property "Datasheet" "" (at 17.78 -10.16 0)
        (effects (font (size 1.27 1.27) (thickness 0.15)) (justify left bottom) hide)
      )
      (property "MPN" "" (at 17.78 -12.7 0)
        (effects (font (size 1.27 1.27) (thickness 0.15)) (justify left bottom) hide)
      )
      (property "Manufacturer" "" (at 17.78 -15.24 0)
        (effects (font (size 1.27 1.27) (thickness 0.15)) (justify left bottom) hide)
      )
      (property "Author" "Antmicro" (at 17.78 -17.78 0)
        (effects (font (size 1.27 1.27) (thickness 0.15)) (justify left bottom) hide)
      )
      (property "License" "Apache-2.0" (at 17.78 -20.32 0)
        (effects (font (size 1.27 1.27) (thickness 0.15)) (justify left bottom) hide)
      )
      (symbol "PCB_Mount_Hole_3mm_NPTH_1_1"
        (circle (center 0 0) (radius 1.8034)
          (stroke (width 0.254) (type default))
          (fill (type none))
        )
        (circle (center 0 0) (radius 4.572)
          (stroke (width 0.254) (type default))
          (fill (type none))
        )
      )
    )
	(symbol "data-center-rdimm-ddr4-tester:R_0R_0201_10" (pin_numbers hide) (pin_names hide) (in_bom yes) (on_board yes)
      (property "Reference" "R" (at 20.32 -5.08 0)
        (effects (font (size 1.27 1.27) (thickness 0.15)) (justify left bottom))
      )
      (property "Value" "R_0R_0201_10" (at 20.32 -12.7 0)
        (effects (font (size 1.27 1.27) (thickness 0.15)) (justify left bottom) hide)
      )
      (property "Footprint" "data-center-rdimm-ddr4-tester-footprints:R_0201" (at 20.32 -15.24 0)
        (effects (font (size 1.27 1.27) (thickness 0.15)) (justify left bottom) hide)
      )
      (property "Datasheet" "https://www.bourns.com/docs/product-datasheets/cr.pdf" (at 20.32 -17.78 0)
        (effects (font (size 1.27 1.27) (thickness 0.15)) (justify left bottom) hide)
      )
      (property "MPN" "CR0201-FX-0R00GLF" (at 20.32 -20.32 0)
        (effects (font (size 1.27 1.27) (thickness 0.15)) (justify left bottom) hide)
      )
      (property "Manufacturer" "Bourns" (at 20.32 -22.86 0)
        (effects (font (size 1.27 1.27) (thickness 0.15)) (justify left bottom) hide)
      )
      (property "License" "Apache-2.0" (at 20.32 -25.4 0)
        (effects (font (size 1.27 1.27) (thickness 0.15)) (justify left bottom) hide)
      )
      (property "Author" "Antmicro" (at 20.32 -27.94 0)
        (effects (font (size 1.27 1.27) (thickness 0.15)) (justify left bottom) hide)
      )
      (property "Val" "0R" (at 20.32 -7.62 0)
        (effects (font (size 1.27 1.27) (thickness 0.15)) (justify left bottom))
      )
      (property "Tolerance" "1%" (at 20.32 -10.16 0)
        (effects (font (size 1.27 1.27)) (justify left bottom) hide)
      )
      (property "ki_description" "0R resistor in 0201 package with 1% tolerance" (at 0 0 0)
        (effects (font (size 1.27 1.27)) hide)
      )
      (symbol "R_0R_0201_10_0_1"
        (rectangle (start 0.635 0.889) (end 4.445 -0.889)
          (stroke (width 0.254) (type default))
          (fill (type none))
        )
      )
      (symbol "R_0R_0201_10_1_1"
        (pin passive line (at 0 0 0) (length 0.635)
          (name "~" (effects (font (size 1.27 1.27))))
          (number "1" (effects (font (size 1.27 1.27))))
        )
        (pin passive line (at 5.08 0 180) (length 0.635)
          (name "~" (effects (font (size 1.27 1.27))))
          (number "2" (effects (font (size 1.27 1.27))))
        )
      )
    )
	(symbol "data-center-rdimm-ddr4-tester:R_0R_0201_11" (pin_numbers hide) (pin_names hide) (in_bom yes) (on_board yes)
      (property "Reference" "R" (at 20.32 -5.08 0)
        (effects (font (size 1.27 1.27) (thickness 0.15)) (justify left bottom))
      )
      (property "Value" "R_0R_0201_11" (at 20.32 -12.7 0)
        (effects (font (size 1.27 1.27) (thickness 0.15)) (justify left bottom) hide)
      )
      (property "Footprint" "data-center-rdimm-ddr4-tester-footprints:R_0201" (at 20.32 -15.24 0)
        (effects (font (size 1.27 1.27) (thickness 0.15)) (justify left bottom) hide)
      )
      (property "Datasheet" "https://www.bourns.com/docs/product-datasheets/cr.pdf" (at 20.32 -17.78 0)
        (effects (font (size 1.27 1.27) (thickness 0.15)) (justify left bottom) hide)
      )
      (property "MPN" "CR0201-FX-0R00GLF" (at 20.32 -20.32 0)
        (effects (font (size 1.27 1.27) (thickness 0.15)) (justify left bottom) hide)
      )
      (property "Manufacturer" "Bourns" (at 20.32 -22.86 0)
        (effects (font (size 1.27 1.27) (thickness 0.15)) (justify left bottom) hide)
      )
      (property "License" "Apache-2.0" (at 20.32 -25.4 0)
        (effects (font (size 1.27 1.27) (thickness 0.15)) (justify left bottom) hide)
      )
      (property "Author" "Antmicro" (at 20.32 -27.94 0)
        (effects (font (size 1.27 1.27) (thickness 0.15)) (justify left bottom) hide)
      )
      (property "Val" "0R" (at 20.32 -7.62 0)
        (effects (font (size 1.27 1.27) (thickness 0.15)) (justify left bottom))
      )
      (property "Tolerance" "1%" (at 20.32 -10.16 0)
        (effects (font (size 1.27 1.27)) (justify left bottom) hide)
      )
      (property "ki_description" "0R resistor in 0201 package with 1% tolerance" (at 0 0 0)
        (effects (font (size 1.27 1.27)) hide)
      )
      (symbol "R_0R_0201_11_0_1"
        (rectangle (start 0.635 0.889) (end 4.445 -0.889)
          (stroke (width 0.254) (type default))
          (fill (type none))
        )
      )
      (symbol "R_0R_0201_11_1_1"
        (pin passive line (at 0 0 0) (length 0.635)
          (name "~" (effects (font (size 1.27 1.27))))
          (number "1" (effects (font (size 1.27 1.27))))
        )
        (pin passive line (at 5.08 0 180) (length 0.635)
          (name "~" (effects (font (size 1.27 1.27))))
          (number "2" (effects (font (size 1.27 1.27))))
        )
      )
    )
	(symbol "data-center-rdimm-ddr4-tester:R_0R_0201_12" (pin_numbers hide) (pin_names hide) (in_bom yes) (on_board yes)
      (property "Reference" "R" (at 20.32 -5.08 0)
        (effects (font (size 1.27 1.27) (thickness 0.15)) (justify left bottom))
      )
      (property "Value" "R_0R_0201_12" (at 20.32 -12.7 0)
        (effects (font (size 1.27 1.27) (thickness 0.15)) (justify left bottom) hide)
      )
      (property "Footprint" "data-center-rdimm-ddr4-tester-footprints:R_0201" (at 20.32 -15.24 0)
        (effects (font (size 1.27 1.27) (thickness 0.15)) (justify left bottom) hide)
      )
      (property "Datasheet" "https://www.bourns.com/docs/product-datasheets/cr.pdf" (at 20.32 -17.78 0)
        (effects (font (size 1.27 1.27) (thickness 0.15)) (justify left bottom) hide)
      )
      (property "MPN" "CR0201-FX-0R00GLF" (at 20.32 -20.32 0)
        (effects (font (size 1.27 1.27) (thickness 0.15)) (justify left bottom) hide)
      )
      (property "Manufacturer" "Bourns" (at 20.32 -22.86 0)
        (effects (font (size 1.27 1.27) (thickness 0.15)) (justify left bottom) hide)
      )
      (property "License" "Apache-2.0" (at 20.32 -25.4 0)
        (effects (font (size 1.27 1.27) (thickness 0.15)) (justify left bottom) hide)
      )
      (property "Author" "Antmicro" (at 20.32 -27.94 0)
        (effects (font (size 1.27 1.27) (thickness 0.15)) (justify left bottom) hide)
      )
      (property "Val" "0R" (at 20.32 -7.62 0)
        (effects (font (size 1.27 1.27) (thickness 0.15)) (justify left bottom))
      )
      (property "Tolerance" "1%" (at 20.32 -10.16 0)
        (effects (font (size 1.27 1.27)) (justify left bottom) hide)
      )
      (property "ki_description" "0R resistor in 0201 package with 1% tolerance" (at 0 0 0)
        (effects (font (size 1.27 1.27)) hide)
      )
      (symbol "R_0R_0201_12_0_1"
        (rectangle (start 0.635 0.889) (end 4.445 -0.889)
          (stroke (width 0.254) (type default))
          (fill (type none))
        )
      )
      (symbol "R_0R_0201_12_1_1"
        (pin passive line (at 0 0 0) (length 0.635)
          (name "~" (effects (font (size 1.27 1.27))))
          (number "1" (effects (font (size 1.27 1.27))))
        )
        (pin passive line (at 5.08 0 180) (length 0.635)
          (name "~" (effects (font (size 1.27 1.27))))
          (number "2" (effects (font (size 1.27 1.27))))
        )
      )
    )
	(symbol "data-center-rdimm-ddr4-tester:R_0R_0201_13" (pin_numbers hide) (pin_names hide) (in_bom yes) (on_board yes)
      (property "Reference" "R" (at 20.32 -5.08 0)
        (effects (font (size 1.27 1.27) (thickness 0.15)) (justify left bottom))
      )
      (property "Value" "R_0R_0201_13" (at 20.32 -12.7 0)
        (effects (font (size 1.27 1.27) (thickness 0.15)) (justify left bottom) hide)
      )
      (property "Footprint" "data-center-rdimm-ddr4-tester-footprints:R_0201" (at 20.32 -15.24 0)
        (effects (font (size 1.27 1.27) (thickness 0.15)) (justify left bottom) hide)
      )
      (property "Datasheet" "https://www.bourns.com/docs/product-datasheets/cr.pdf" (at 20.32 -17.78 0)
        (effects (font (size 1.27 1.27) (thickness 0.15)) (justify left bottom) hide)
      )
      (property "MPN" "CR0201-FX-0R00GLF" (at 20.32 -20.32 0)
        (effects (font (size 1.27 1.27) (thickness 0.15)) (justify left bottom) hide)
      )
      (property "Manufacturer" "Bourns" (at 20.32 -22.86 0)
        (effects (font (size 1.27 1.27) (thickness 0.15)) (justify left bottom) hide)
      )
      (property "License" "Apache-2.0" (at 20.32 -25.4 0)
        (effects (font (size 1.27 1.27) (thickness 0.15)) (justify left bottom) hide)
      )
      (property "Author" "Antmicro" (at 20.32 -27.94 0)
        (effects (font (size 1.27 1.27) (thickness 0.15)) (justify left bottom) hide)
      )
      (property "Val" "0R" (at 20.32 -7.62 0)
        (effects (font (size 1.27 1.27) (thickness 0.15)) (justify left bottom))
      )
      (property "Tolerance" "1%" (at 20.32 -10.16 0)
        (effects (font (size 1.27 1.27)) (justify left bottom) hide)
      )
      (property "ki_description" "0R resistor in 0201 package with 1% tolerance" (at 0 0 0)
        (effects (font (size 1.27 1.27)) hide)
      )
      (symbol "R_0R_0201_13_0_1"
        (rectangle (start 0.635 0.889) (end 4.445 -0.889)
          (stroke (width 0.254) (type default))
          (fill (type none))
        )
      )
      (symbol "R_0R_0201_13_1_1"
        (pin passive line (at 0 0 0) (length 0.635)
          (name "~" (effects (font (size 1.27 1.27))))
          (number "1" (effects (font (size 1.27 1.27))))
        )
        (pin passive line (at 5.08 0 180) (length 0.635)
          (name "~" (effects (font (size 1.27 1.27))))
          (number "2" (effects (font (size 1.27 1.27))))
        )
      )
    )
	(symbol "data-center-rdimm-ddr4-tester:R_0R_0201_14" (pin_numbers hide) (pin_names hide) (in_bom yes) (on_board yes)
      (property "Reference" "R" (at 20.32 -5.08 0)
        (effects (font (size 1.27 1.27) (thickness 0.15)) (justify left bottom))
      )
      (property "Value" "R_0R_0201_14" (at 20.32 -12.7 0)
        (effects (font (size 1.27 1.27) (thickness 0.15)) (justify left bottom) hide)
      )
      (property "Footprint" "data-center-rdimm-ddr4-tester-footprints:R_0201" (at 20.32 -15.24 0)
        (effects (font (size 1.27 1.27) (thickness 0.15)) (justify left bottom) hide)
      )
      (property "Datasheet" "https://www.bourns.com/docs/product-datasheets/cr.pdf" (at 20.32 -17.78 0)
        (effects (font (size 1.27 1.27) (thickness 0.15)) (justify left bottom) hide)
      )
      (property "MPN" "CR0201-FX-0R00GLF" (at 20.32 -20.32 0)
        (effects (font (size 1.27 1.27) (thickness 0.15)) (justify left bottom) hide)
      )
      (property "Manufacturer" "Bourns" (at 20.32 -22.86 0)
        (effects (font (size 1.27 1.27) (thickness 0.15)) (justify left bottom) hide)
      )
      (property "License" "Apache-2.0" (at 20.32 -25.4 0)
        (effects (font (size 1.27 1.27) (thickness 0.15)) (justify left bottom) hide)
      )
      (property "Author" "Antmicro" (at 20.32 -27.94 0)
        (effects (font (size 1.27 1.27) (thickness 0.15)) (justify left bottom) hide)
      )
      (property "Val" "0R" (at 20.32 -7.62 0)
        (effects (font (size 1.27 1.27) (thickness 0.15)) (justify left bottom))
      )
      (property "Tolerance" "1%" (at 20.32 -10.16 0)
        (effects (font (size 1.27 1.27)) (justify left bottom) hide)
      )
      (property "ki_description" "0R resistor in 0201 package with 1% tolerance" (at 0 0 0)
        (effects (font (size 1.27 1.27)) hide)
      )
      (symbol "R_0R_0201_14_0_1"
        (rectangle (start 0.635 0.889) (end 4.445 -0.889)
          (stroke (width 0.254) (type default))
          (fill (type none))
        )
      )
      (symbol "R_0R_0201_14_1_1"
        (pin passive line (at 0 0 0) (length 0.635)
          (name "~" (effects (font (size 1.27 1.27))))
          (number "1" (effects (font (size 1.27 1.27))))
        )
        (pin passive line (at 5.08 0 180) (length 0.635)
          (name "~" (effects (font (size 1.27 1.27))))
          (number "2" (effects (font (size 1.27 1.27))))
        )
      )
    )
	(symbol "data-center-rdimm-ddr4-tester:R_0R_0201_15" (pin_numbers hide) (pin_names hide) (in_bom yes) (on_board yes)
      (property "Reference" "R" (at 20.32 -5.08 0)
        (effects (font (size 1.27 1.27) (thickness 0.15)) (justify left bottom))
      )
      (property "Value" "R_0R_0201_15" (at 20.32 -12.7 0)
        (effects (font (size 1.27 1.27) (thickness 0.15)) (justify left bottom) hide)
      )
      (property "Footprint" "data-center-rdimm-ddr4-tester-footprints:R_0201" (at 20.32 -15.24 0)
        (effects (font (size 1.27 1.27) (thickness 0.15)) (justify left bottom) hide)
      )
      (property "Datasheet" "https://www.bourns.com/docs/product-datasheets/cr.pdf" (at 20.32 -17.78 0)
        (effects (font (size 1.27 1.27) (thickness 0.15)) (justify left bottom) hide)
      )
      (property "MPN" "CR0201-FX-0R00GLF" (at 20.32 -20.32 0)
        (effects (font (size 1.27 1.27) (thickness 0.15)) (justify left bottom) hide)
      )
      (property "Manufacturer" "Bourns" (at 20.32 -22.86 0)
        (effects (font (size 1.27 1.27) (thickness 0.15)) (justify left bottom) hide)
      )
      (property "License" "Apache-2.0" (at 20.32 -25.4 0)
        (effects (font (size 1.27 1.27) (thickness 0.15)) (justify left bottom) hide)
      )
      (property "Author" "Antmicro" (at 20.32 -27.94 0)
        (effects (font (size 1.27 1.27) (thickness 0.15)) (justify left bottom) hide)
      )
      (property "Val" "0R" (at 20.32 -7.62 0)
        (effects (font (size 1.27 1.27) (thickness 0.15)) (justify left bottom))
      )
      (property "Tolerance" "1%" (at 20.32 -10.16 0)
        (effects (font (size 1.27 1.27)) (justify left bottom) hide)
      )
      (property "ki_description" "0R resistor in 0201 package with 1% tolerance" (at 0 0 0)
        (effects (font (size 1.27 1.27)) hide)
      )
      (symbol "R_0R_0201_15_0_1"
        (rectangle (start 0.635 0.889) (end 4.445 -0.889)
          (stroke (width 0.254) (type default))
          (fill (type none))
        )
      )
      (symbol "R_0R_0201_15_1_1"
        (pin passive line (at 0 0 0) (length 0.635)
          (name "~" (effects (font (size 1.27 1.27))))
          (number "1" (effects (font (size 1.27 1.27))))
        )
        (pin passive line (at 5.08 0 180) (length 0.635)
          (name "~" (effects (font (size 1.27 1.27))))
          (number "2" (effects (font (size 1.27 1.27))))
        )
      )
    )
	(symbol "data-center-rdimm-ddr4-tester:R_0R_0201_16" (pin_numbers hide) (pin_names hide) (in_bom yes) (on_board yes)
      (property "Reference" "R" (at 20.32 -5.08 0)
        (effects (font (size 1.27 1.27) (thickness 0.15)) (justify left bottom))
      )
      (property "Value" "R_0R_0201_16" (at 20.32 -12.7 0)
        (effects (font (size 1.27 1.27) (thickness 0.15)) (justify left bottom) hide)
      )
      (property "Footprint" "data-center-rdimm-ddr4-tester-footprints:R_0201" (at 20.32 -15.24 0)
        (effects (font (size 1.27 1.27) (thickness 0.15)) (justify left bottom) hide)
      )
      (property "Datasheet" "https://www.bourns.com/docs/product-datasheets/cr.pdf" (at 20.32 -17.78 0)
        (effects (font (size 1.27 1.27) (thickness 0.15)) (justify left bottom) hide)
      )
      (property "MPN" "CR0201-FX-0R00GLF" (at 20.32 -20.32 0)
        (effects (font (size 1.27 1.27) (thickness 0.15)) (justify left bottom) hide)
      )
      (property "Manufacturer" "Bourns" (at 20.32 -22.86 0)
        (effects (font (size 1.27 1.27) (thickness 0.15)) (justify left bottom) hide)
      )
      (property "License" "Apache-2.0" (at 20.32 -25.4 0)
        (effects (font (size 1.27 1.27) (thickness 0.15)) (justify left bottom) hide)
      )
      (property "Author" "Antmicro" (at 20.32 -27.94 0)
        (effects (font (size 1.27 1.27) (thickness 0.15)) (justify left bottom) hide)
      )
      (property "Val" "0R" (at 20.32 -7.62 0)
        (effects (font (size 1.27 1.27) (thickness 0.15)) (justify left bottom))
      )
      (property "Tolerance" "1%" (at 20.32 -10.16 0)
        (effects (font (size 1.27 1.27)) (justify left bottom) hide)
      )
      (property "ki_description" "0R resistor in 0201 package with 1% tolerance" (at 0 0 0)
        (effects (font (size 1.27 1.27)) hide)
      )
      (symbol "R_0R_0201_16_0_1"
        (rectangle (start 0.635 0.889) (end 4.445 -0.889)
          (stroke (width 0.254) (type default))
          (fill (type none))
        )
      )
      (symbol "R_0R_0201_16_1_1"
        (pin passive line (at 0 0 0) (length 0.635)
          (name "~" (effects (font (size 1.27 1.27))))
          (number "1" (effects (font (size 1.27 1.27))))
        )
        (pin passive line (at 5.08 0 180) (length 0.635)
          (name "~" (effects (font (size 1.27 1.27))))
          (number "2" (effects (font (size 1.27 1.27))))
        )
      )
    )
	(symbol "data-center-rdimm-ddr4-tester:R_0R_0201_17" (pin_numbers hide) (pin_names hide) (in_bom yes) (on_board yes)
      (property "Reference" "R" (at 20.32 -5.08 0)
        (effects (font (size 1.27 1.27) (thickness 0.15)) (justify left bottom))
      )
      (property "Value" "R_0R_0201_17" (at 20.32 -12.7 0)
        (effects (font (size 1.27 1.27) (thickness 0.15)) (justify left bottom) hide)
      )
      (property "Footprint" "data-center-rdimm-ddr4-tester-footprints:R_0201" (at 20.32 -15.24 0)
        (effects (font (size 1.27 1.27) (thickness 0.15)) (justify left bottom) hide)
      )
      (property "Datasheet" "https://www.bourns.com/docs/product-datasheets/cr.pdf" (at 20.32 -17.78 0)
        (effects (font (size 1.27 1.27) (thickness 0.15)) (justify left bottom) hide)
      )
      (property "MPN" "CR0201-FX-0R00GLF" (at 20.32 -20.32 0)
        (effects (font (size 1.27 1.27) (thickness 0.15)) (justify left bottom) hide)
      )
      (property "Manufacturer" "Bourns" (at 20.32 -22.86 0)
        (effects (font (size 1.27 1.27) (thickness 0.15)) (justify left bottom) hide)
      )
      (property "License" "Apache-2.0" (at 20.32 -25.4 0)
        (effects (font (size 1.27 1.27) (thickness 0.15)) (justify left bottom) hide)
      )
      (property "Author" "Antmicro" (at 20.32 -27.94 0)
        (effects (font (size 1.27 1.27) (thickness 0.15)) (justify left bottom) hide)
      )
      (property "Val" "0R" (at 20.32 -7.62 0)
        (effects (font (size 1.27 1.27) (thickness 0.15)) (justify left bottom))
      )
      (property "Tolerance" "1%" (at 20.32 -10.16 0)
        (effects (font (size 1.27 1.27)) (justify left bottom) hide)
      )
      (property "ki_description" "0R resistor in 0201 package with 1% tolerance" (at 0 0 0)
        (effects (font (size 1.27 1.27)) hide)
      )
      (symbol "R_0R_0201_17_0_1"
        (rectangle (start 0.635 0.889) (end 4.445 -0.889)
          (stroke (width 0.254) (type default))
          (fill (type none))
        )
      )
      (symbol "R_0R_0201_17_1_1"
        (pin passive line (at 0 0 0) (length 0.635)
          (name "~" (effects (font (size 1.27 1.27))))
          (number "1" (effects (font (size 1.27 1.27))))
        )
        (pin passive line (at 5.08 0 180) (length 0.635)
          (name "~" (effects (font (size 1.27 1.27))))
          (number "2" (effects (font (size 1.27 1.27))))
        )
      )
    )
	(symbol "data-center-rdimm-ddr4-tester:R_0R_0402_10" (pin_numbers hide) (pin_names hide) (in_bom yes) (on_board yes)
      (property "Reference" "R" (at 20.32 -5.08 0)
        (effects (font (size 1.27 1.27) (thickness 0.15)) (justify left bottom))
      )
      (property "Value" "R_0R_0402_10" (at 20.32 -12.7 0)
        (effects (font (size 1.27 1.27) (thickness 0.15)) (justify left bottom) hide)
      )
      (property "Footprint" "data-center-rdimm-ddr4-tester-footprints:R_0402_1005Metric" (at 20.32 -15.24 0)
        (effects (font (size 1.27 1.27) (thickness 0.15)) (justify left bottom) hide)
      )
      (property "Datasheet" "https://industrial.panasonic.com/cdbs/www-data/pdf/RDA0000/AOA0000C301.pdf" (at 20.32 -17.78 0)
        (effects (font (size 1.27 1.27) (thickness 0.15)) (justify left bottom) hide)
      )
      (property "MPN" "ERJ2GE0R00X" (at 20.32 -20.32 0)
        (effects (font (size 1.27 1.27) (thickness 0.15)) (justify left bottom) hide)
      )
      (property "Manufacturer" "Panasonic" (at 20.32 -22.86 0)
        (effects (font (size 1.27 1.27) (thickness 0.15)) (justify left bottom) hide)
      )
      (property "License" "Apache-2.0" (at 20.32 -25.4 0)
        (effects (font (size 1.27 1.27) (thickness 0.15)) (justify left bottom) hide)
      )
      (property "Author" "Antmicro" (at 20.32 -27.94 0)
        (effects (font (size 1.27 1.27) (thickness 0.15)) (justify left bottom) hide)
      )
      (property "Val" "0R" (at 20.32 -7.62 0)
        (effects (font (size 1.27 1.27) (thickness 0.15)) (justify left bottom))
      )
      (property "Tolerance" "~" (at 20.32 -10.16 0)
        (effects (font (size 1.27 1.27)) (justify left bottom) hide)
      )
      (property "Current" "1A" (at 20.32 -30.48 0)
        (effects (font (size 1.27 1.27) (thickness 0.15)) (justify left bottom) hide)
      )
      (property "ki_description" "0R resistor in 0402 package with unspecified tolerance" (at 0 0 0)
        (effects (font (size 1.27 1.27)) hide)
      )
      (symbol "R_0R_0402_10_0_1"
        (rectangle (start 0.635 0.889) (end 4.445 -0.889)
          (stroke (width 0.254) (type default))
          (fill (type none))
        )
      )
      (symbol "R_0R_0402_10_1_1"
        (pin passive line (at 0 0 0) (length 0.635)
          (name "~" (effects (font (size 1.27 1.27))))
          (number "1" (effects (font (size 1.27 1.27))))
        )
        (pin passive line (at 5.08 0 180) (length 0.635)
          (name "~" (effects (font (size 1.27 1.27))))
          (number "2" (effects (font (size 1.27 1.27))))
        )
      )
    )
	(symbol "data-center-rdimm-ddr4-tester:R_10k_0402_10" (pin_numbers hide) (pin_names hide) (in_bom yes) (on_board yes)
      (property "Reference" "R" (at 20.32 -5.08 0)
        (effects (font (size 1.27 1.27) (thickness 0.15)) (justify left bottom))
      )
      (property "Value" "R_10k_0402_10" (at 20.32 -12.7 0)
        (effects (font (size 1.27 1.27) (thickness 0.15)) (justify left bottom) hide)
      )
      (property "Footprint" "data-center-rdimm-ddr4-tester-footprints:R_0402_1005Metric" (at 20.32 -15.24 0)
        (effects (font (size 1.27 1.27) (thickness 0.15)) (justify left bottom) hide)
      )
      (property "Datasheet" "https://www.bourns.com/docs/product-datasheets/cr.pdf" (at 20.32 -17.78 0)
        (effects (font (size 1.27 1.27) (thickness 0.15)) (justify left bottom) hide)
      )
      (property "MPN" "CR0402-FX-1002GLF" (at 20.32 -20.32 0)
        (effects (font (size 1.27 1.27) (thickness 0.15)) (justify left bottom) hide)
      )
      (property "Manufacturer" "Bourns" (at 20.32 -22.86 0)
        (effects (font (size 1.27 1.27) (thickness 0.15)) (justify left bottom) hide)
      )
      (property "License" "Apache-2.0" (at 20.32 -25.4 0)
        (effects (font (size 1.27 1.27) (thickness 0.15)) (justify left bottom) hide)
      )
      (property "Author" "Antmicro" (at 20.32 -27.94 0)
        (effects (font (size 1.27 1.27) (thickness 0.15)) (justify left bottom) hide)
      )
      (property "Val" "10k" (at 20.32 -7.62 0)
        (effects (font (size 1.27 1.27) (thickness 0.15)) (justify left bottom))
      )
      (property "Tolerance" "1%" (at 20.32 -10.16 0)
        (effects (font (size 1.27 1.27)) (justify left bottom) hide)
      )
      (property "ki_description" "10k resistor in 0402 package with 1% tolerance" (at 0 0 0)
        (effects (font (size 1.27 1.27)) hide)
      )
      (symbol "R_10k_0402_10_0_1"
        (rectangle (start 0.635 0.889) (end 4.445 -0.889)
          (stroke (width 0.254) (type default))
          (fill (type none))
        )
      )
      (symbol "R_10k_0402_10_1_1"
        (pin passive line (at 0 0 0) (length 0.635)
          (name "~" (effects (font (size 1.27 1.27))))
          (number "1" (effects (font (size 1.27 1.27))))
        )
        (pin passive line (at 5.08 0 180) (length 0.635)
          (name "~" (effects (font (size 1.27 1.27))))
          (number "2" (effects (font (size 1.27 1.27))))
        )
      )
    )
	(symbol "data-center-rdimm-ddr4-tester:R_10k_0402_11" (pin_numbers hide) (pin_names hide) (in_bom yes) (on_board yes)
      (property "Reference" "R" (at 20.32 -5.08 0)
        (effects (font (size 1.27 1.27) (thickness 0.15)) (justify left bottom))
      )
      (property "Value" "R_10k_0402_11" (at 20.32 -12.7 0)
        (effects (font (size 1.27 1.27) (thickness 0.15)) (justify left bottom) hide)
      )
      (property "Footprint" "data-center-rdimm-ddr4-tester-footprints:R_0402_1005Metric" (at 20.32 -15.24 0)
        (effects (font (size 1.27 1.27) (thickness 0.15)) (justify left bottom) hide)
      )
      (property "Datasheet" "https://www.bourns.com/docs/product-datasheets/cr.pdf" (at 20.32 -17.78 0)
        (effects (font (size 1.27 1.27) (thickness 0.15)) (justify left bottom) hide)
      )
      (property "MPN" "CR0402-FX-1002GLF" (at 20.32 -20.32 0)
        (effects (font (size 1.27 1.27) (thickness 0.15)) (justify left bottom) hide)
      )
      (property "Manufacturer" "Bourns" (at 20.32 -22.86 0)
        (effects (font (size 1.27 1.27) (thickness 0.15)) (justify left bottom) hide)
      )
      (property "License" "Apache-2.0" (at 20.32 -25.4 0)
        (effects (font (size 1.27 1.27) (thickness 0.15)) (justify left bottom) hide)
      )
      (property "Author" "Antmicro" (at 20.32 -27.94 0)
        (effects (font (size 1.27 1.27) (thickness 0.15)) (justify left bottom) hide)
      )
      (property "Val" "10k" (at 20.32 -7.62 0)
        (effects (font (size 1.27 1.27) (thickness 0.15)) (justify left bottom))
      )
      (property "Tolerance" "1%" (at 20.32 -10.16 0)
        (effects (font (size 1.27 1.27)) (justify left bottom) hide)
      )
      (property "ki_description" "10k resistor in 0402 package with 1% tolerance" (at 0 0 0)
        (effects (font (size 1.27 1.27)) hide)
      )
      (symbol "R_10k_0402_11_0_1"
        (rectangle (start 0.635 0.889) (end 4.445 -0.889)
          (stroke (width 0.254) (type default))
          (fill (type none))
        )
      )
      (symbol "R_10k_0402_11_1_1"
        (pin passive line (at 0 0 0) (length 0.635)
          (name "~" (effects (font (size 1.27 1.27))))
          (number "1" (effects (font (size 1.27 1.27))))
        )
        (pin passive line (at 5.08 0 180) (length 0.635)
          (name "~" (effects (font (size 1.27 1.27))))
          (number "2" (effects (font (size 1.27 1.27))))
        )
      )
    )
	(symbol "data-center-rdimm-ddr4-tester:R_10k_0402_12" (pin_numbers hide) (pin_names hide) (in_bom yes) (on_board yes)
      (property "Reference" "R" (at 20.32 -5.08 0)
        (effects (font (size 1.27 1.27) (thickness 0.15)) (justify left bottom))
      )
      (property "Value" "R_10k_0402_12" (at 20.32 -12.7 0)
        (effects (font (size 1.27 1.27) (thickness 0.15)) (justify left bottom) hide)
      )
      (property "Footprint" "data-center-rdimm-ddr4-tester-footprints:R_0402_1005Metric" (at 20.32 -15.24 0)
        (effects (font (size 1.27 1.27) (thickness 0.15)) (justify left bottom) hide)
      )
      (property "Datasheet" "https://www.bourns.com/docs/product-datasheets/cr.pdf" (at 20.32 -17.78 0)
        (effects (font (size 1.27 1.27) (thickness 0.15)) (justify left bottom) hide)
      )
      (property "MPN" "CR0402-FX-1002GLF" (at 20.32 -20.32 0)
        (effects (font (size 1.27 1.27) (thickness 0.15)) (justify left bottom) hide)
      )
      (property "Manufacturer" "Bourns" (at 20.32 -22.86 0)
        (effects (font (size 1.27 1.27) (thickness 0.15)) (justify left bottom) hide)
      )
      (property "License" "Apache-2.0" (at 20.32 -25.4 0)
        (effects (font (size 1.27 1.27) (thickness 0.15)) (justify left bottom) hide)
      )
      (property "Author" "Antmicro" (at 20.32 -27.94 0)
        (effects (font (size 1.27 1.27) (thickness 0.15)) (justify left bottom) hide)
      )
      (property "Val" "10k" (at 20.32 -7.62 0)
        (effects (font (size 1.27 1.27) (thickness 0.15)) (justify left bottom))
      )
      (property "Tolerance" "1%" (at 20.32 -10.16 0)
        (effects (font (size 1.27 1.27)) (justify left bottom) hide)
      )
      (property "ki_description" "10k resistor in 0402 package with 1% tolerance" (at 0 0 0)
        (effects (font (size 1.27 1.27)) hide)
      )
      (symbol "R_10k_0402_12_0_1"
        (rectangle (start 0.635 0.889) (end 4.445 -0.889)
          (stroke (width 0.254) (type default))
          (fill (type none))
        )
      )
      (symbol "R_10k_0402_12_1_1"
        (pin passive line (at 0 0 0) (length 0.635)
          (name "~" (effects (font (size 1.27 1.27))))
          (number "1" (effects (font (size 1.27 1.27))))
        )
        (pin passive line (at 5.08 0 180) (length 0.635)
          (name "~" (effects (font (size 1.27 1.27))))
          (number "2" (effects (font (size 1.27 1.27))))
        )
      )
    )
	(symbol "data-center-rdimm-ddr4-tester:R_10k_0402_13" (pin_numbers hide) (pin_names hide) (in_bom yes) (on_board yes)
      (property "Reference" "R" (at 20.32 -5.08 0)
        (effects (font (size 1.27 1.27) (thickness 0.15)) (justify left bottom))
      )
      (property "Value" "R_10k_0402_13" (at 20.32 -12.7 0)
        (effects (font (size 1.27 1.27) (thickness 0.15)) (justify left bottom) hide)
      )
      (property "Footprint" "data-center-rdimm-ddr4-tester-footprints:R_0402_1005Metric" (at 20.32 -15.24 0)
        (effects (font (size 1.27 1.27) (thickness 0.15)) (justify left bottom) hide)
      )
      (property "Datasheet" "https://www.bourns.com/docs/product-datasheets/cr.pdf" (at 20.32 -17.78 0)
        (effects (font (size 1.27 1.27) (thickness 0.15)) (justify left bottom) hide)
      )
      (property "MPN" "CR0402-FX-1002GLF" (at 20.32 -20.32 0)
        (effects (font (size 1.27 1.27) (thickness 0.15)) (justify left bottom) hide)
      )
      (property "Manufacturer" "Bourns" (at 20.32 -22.86 0)
        (effects (font (size 1.27 1.27) (thickness 0.15)) (justify left bottom) hide)
      )
      (property "License" "Apache-2.0" (at 20.32 -25.4 0)
        (effects (font (size 1.27 1.27) (thickness 0.15)) (justify left bottom) hide)
      )
      (property "Author" "Antmicro" (at 20.32 -27.94 0)
        (effects (font (size 1.27 1.27) (thickness 0.15)) (justify left bottom) hide)
      )
      (property "Val" "10k" (at 20.32 -7.62 0)
        (effects (font (size 1.27 1.27) (thickness 0.15)) (justify left bottom))
      )
      (property "Tolerance" "1%" (at 20.32 -10.16 0)
        (effects (font (size 1.27 1.27)) (justify left bottom) hide)
      )
      (property "ki_description" "10k resistor in 0402 package with 1% tolerance" (at 0 0 0)
        (effects (font (size 1.27 1.27)) hide)
      )
      (symbol "R_10k_0402_13_0_1"
        (rectangle (start 0.635 0.889) (end 4.445 -0.889)
          (stroke (width 0.254) (type default))
          (fill (type none))
        )
      )
      (symbol "R_10k_0402_13_1_1"
        (pin passive line (at 0 0 0) (length 0.635)
          (name "~" (effects (font (size 1.27 1.27))))
          (number "1" (effects (font (size 1.27 1.27))))
        )
        (pin passive line (at 5.08 0 180) (length 0.635)
          (name "~" (effects (font (size 1.27 1.27))))
          (number "2" (effects (font (size 1.27 1.27))))
        )
      )
    )
	(symbol "data-center-rdimm-ddr4-tester:R_10k_0402_14" (pin_numbers hide) (pin_names hide) (in_bom yes) (on_board yes)
      (property "Reference" "R" (at 20.32 -5.08 0)
        (effects (font (size 1.27 1.27) (thickness 0.15)) (justify left bottom))
      )
      (property "Value" "R_10k_0402_14" (at 20.32 -12.7 0)
        (effects (font (size 1.27 1.27) (thickness 0.15)) (justify left bottom) hide)
      )
      (property "Footprint" "data-center-rdimm-ddr4-tester-footprints:R_0402_1005Metric" (at 20.32 -15.24 0)
        (effects (font (size 1.27 1.27) (thickness 0.15)) (justify left bottom) hide)
      )
      (property "Datasheet" "https://www.bourns.com/docs/product-datasheets/cr.pdf" (at 20.32 -17.78 0)
        (effects (font (size 1.27 1.27) (thickness 0.15)) (justify left bottom) hide)
      )
      (property "MPN" "CR0402-FX-1002GLF" (at 20.32 -20.32 0)
        (effects (font (size 1.27 1.27) (thickness 0.15)) (justify left bottom) hide)
      )
      (property "Manufacturer" "Bourns" (at 20.32 -22.86 0)
        (effects (font (size 1.27 1.27) (thickness 0.15)) (justify left bottom) hide)
      )
      (property "License" "Apache-2.0" (at 20.32 -25.4 0)
        (effects (font (size 1.27 1.27) (thickness 0.15)) (justify left bottom) hide)
      )
      (property "Author" "Antmicro" (at 20.32 -27.94 0)
        (effects (font (size 1.27 1.27) (thickness 0.15)) (justify left bottom) hide)
      )
      (property "Val" "10k" (at 20.32 -7.62 0)
        (effects (font (size 1.27 1.27) (thickness 0.15)) (justify left bottom))
      )
      (property "Tolerance" "1%" (at 20.32 -10.16 0)
        (effects (font (size 1.27 1.27)) (justify left bottom) hide)
      )
      (property "ki_description" "10k resistor in 0402 package with 1% tolerance" (at 0 0 0)
        (effects (font (size 1.27 1.27)) hide)
      )
      (symbol "R_10k_0402_14_0_1"
        (rectangle (start 0.635 0.889) (end 4.445 -0.889)
          (stroke (width 0.254) (type default))
          (fill (type none))
        )
      )
      (symbol "R_10k_0402_14_1_1"
        (pin passive line (at 0 0 0) (length 0.635)
          (name "~" (effects (font (size 1.27 1.27))))
          (number "1" (effects (font (size 1.27 1.27))))
        )
        (pin passive line (at 5.08 0 180) (length 0.635)
          (name "~" (effects (font (size 1.27 1.27))))
          (number "2" (effects (font (size 1.27 1.27))))
        )
      )
    )
	(symbol "data-center-rdimm-ddr4-tester:R_22R_0402_10" (pin_numbers hide) (pin_names hide) (in_bom yes) (on_board yes)
      (property "Reference" "R" (at 20.32 -5.08 0)
        (effects (font (size 1.27 1.27) (thickness 0.15)) (justify left bottom))
      )
      (property "Value" "R_22R_0402_10" (at 20.32 -12.7 0)
        (effects (font (size 1.27 1.27) (thickness 0.15)) (justify left bottom) hide)
      )
      (property "Footprint" "data-center-rdimm-ddr4-tester-footprints:R_0402_1005Metric" (at 20.32 -15.24 0)
        (effects (font (size 1.27 1.27) (thickness 0.15)) (justify left bottom) hide)
      )
      (property "Datasheet" "https://www.bourns.com/docs/product-datasheets/cr.pdf" (at 20.32 -17.78 0)
        (effects (font (size 1.27 1.27) (thickness 0.15)) (justify left bottom) hide)
      )
      (property "MPN" "CR0402-FX-22R0GLF" (at 20.32 -20.32 0)
        (effects (font (size 1.27 1.27) (thickness 0.15)) (justify left bottom) hide)
      )
      (property "Manufacturer" "Bourns" (at 20.32 -22.86 0)
        (effects (font (size 1.27 1.27) (thickness 0.15)) (justify left bottom) hide)
      )
      (property "License" "Apache-2.0" (at 20.32 -25.4 0)
        (effects (font (size 1.27 1.27) (thickness 0.15)) (justify left bottom) hide)
      )
      (property "Author" "Antmicro" (at 20.32 -27.94 0)
        (effects (font (size 1.27 1.27) (thickness 0.15)) (justify left bottom) hide)
      )
      (property "Val" "22R" (at 20.32 -7.62 0)
        (effects (font (size 1.27 1.27) (thickness 0.15)) (justify left bottom))
      )
      (property "Tolerance" "1%" (at 20.32 -10.16 0)
        (effects (font (size 1.27 1.27)) (justify left bottom) hide)
      )
      (property "ki_description" "22R resistor in 0402 package with 1% tolerance" (at 0 0 0)
        (effects (font (size 1.27 1.27)) hide)
      )
      (symbol "R_22R_0402_10_0_1"
        (rectangle (start 0.635 0.889) (end 4.445 -0.889)
          (stroke (width 0.254) (type default))
          (fill (type none))
        )
      )
      (symbol "R_22R_0402_10_1_1"
        (pin passive line (at 0 0 0) (length 0.635)
          (name "~" (effects (font (size 1.27 1.27))))
          (number "1" (effects (font (size 1.27 1.27))))
        )
        (pin passive line (at 5.08 0 180) (length 0.635)
          (name "~" (effects (font (size 1.27 1.27))))
          (number "2" (effects (font (size 1.27 1.27))))
        )
      )
    )
	(symbol "data-center-rdimm-ddr4-tester:R_22R_0402_11" (pin_numbers hide) (pin_names hide) (in_bom yes) (on_board yes)
      (property "Reference" "R" (at 20.32 -5.08 0)
        (effects (font (size 1.27 1.27) (thickness 0.15)) (justify left bottom))
      )
      (property "Value" "R_22R_0402_11" (at 20.32 -12.7 0)
        (effects (font (size 1.27 1.27) (thickness 0.15)) (justify left bottom) hide)
      )
      (property "Footprint" "data-center-rdimm-ddr4-tester-footprints:R_0402_1005Metric" (at 20.32 -15.24 0)
        (effects (font (size 1.27 1.27) (thickness 0.15)) (justify left bottom) hide)
      )
      (property "Datasheet" "https://www.bourns.com/docs/product-datasheets/cr.pdf" (at 20.32 -17.78 0)
        (effects (font (size 1.27 1.27) (thickness 0.15)) (justify left bottom) hide)
      )
      (property "MPN" "CR0402-FX-22R0GLF" (at 20.32 -20.32 0)
        (effects (font (size 1.27 1.27) (thickness 0.15)) (justify left bottom) hide)
      )
      (property "Manufacturer" "Bourns" (at 20.32 -22.86 0)
        (effects (font (size 1.27 1.27) (thickness 0.15)) (justify left bottom) hide)
      )
      (property "License" "Apache-2.0" (at 20.32 -25.4 0)
        (effects (font (size 1.27 1.27) (thickness 0.15)) (justify left bottom) hide)
      )
      (property "Author" "Antmicro" (at 20.32 -27.94 0)
        (effects (font (size 1.27 1.27) (thickness 0.15)) (justify left bottom) hide)
      )
      (property "Val" "22R" (at 20.32 -7.62 0)
        (effects (font (size 1.27 1.27) (thickness 0.15)) (justify left bottom))
      )
      (property "Tolerance" "1%" (at 20.32 -10.16 0)
        (effects (font (size 1.27 1.27)) (justify left bottom) hide)
      )
      (property "ki_description" "22R resistor in 0402 package with 1% tolerance" (at 0 0 0)
        (effects (font (size 1.27 1.27)) hide)
      )
      (symbol "R_22R_0402_11_0_1"
        (rectangle (start 0.635 0.889) (end 4.445 -0.889)
          (stroke (width 0.254) (type default))
          (fill (type none))
        )
      )
      (symbol "R_22R_0402_11_1_1"
        (pin passive line (at 0 0 0) (length 0.635)
          (name "~" (effects (font (size 1.27 1.27))))
          (number "1" (effects (font (size 1.27 1.27))))
        )
        (pin passive line (at 5.08 0 180) (length 0.635)
          (name "~" (effects (font (size 1.27 1.27))))
          (number "2" (effects (font (size 1.27 1.27))))
        )
      )
    )
	(symbol "data-center-rdimm-ddr4-tester:R_22R_0402_12" (pin_numbers hide) (pin_names hide) (in_bom yes) (on_board yes)
      (property "Reference" "R" (at 20.32 -5.08 0)
        (effects (font (size 1.27 1.27) (thickness 0.15)) (justify left bottom))
      )
      (property "Value" "R_22R_0402_12" (at 20.32 -12.7 0)
        (effects (font (size 1.27 1.27) (thickness 0.15)) (justify left bottom) hide)
      )
      (property "Footprint" "data-center-rdimm-ddr4-tester-footprints:R_0402_1005Metric" (at 20.32 -15.24 0)
        (effects (font (size 1.27 1.27) (thickness 0.15)) (justify left bottom) hide)
      )
      (property "Datasheet" "https://www.bourns.com/docs/product-datasheets/cr.pdf" (at 20.32 -17.78 0)
        (effects (font (size 1.27 1.27) (thickness 0.15)) (justify left bottom) hide)
      )
      (property "MPN" "CR0402-FX-22R0GLF" (at 20.32 -20.32 0)
        (effects (font (size 1.27 1.27) (thickness 0.15)) (justify left bottom) hide)
      )
      (property "Manufacturer" "Bourns" (at 20.32 -22.86 0)
        (effects (font (size 1.27 1.27) (thickness 0.15)) (justify left bottom) hide)
      )
      (property "License" "Apache-2.0" (at 20.32 -25.4 0)
        (effects (font (size 1.27 1.27) (thickness 0.15)) (justify left bottom) hide)
      )
      (property "Author" "Antmicro" (at 20.32 -27.94 0)
        (effects (font (size 1.27 1.27) (thickness 0.15)) (justify left bottom) hide)
      )
      (property "Val" "22R" (at 20.32 -7.62 0)
        (effects (font (size 1.27 1.27) (thickness 0.15)) (justify left bottom))
      )
      (property "Tolerance" "1%" (at 20.32 -10.16 0)
        (effects (font (size 1.27 1.27)) (justify left bottom) hide)
      )
      (property "ki_description" "22R resistor in 0402 package with 1% tolerance" (at 0 0 0)
        (effects (font (size 1.27 1.27)) hide)
      )
      (symbol "R_22R_0402_12_0_1"
        (rectangle (start 0.635 0.889) (end 4.445 -0.889)
          (stroke (width 0.254) (type default))
          (fill (type none))
        )
      )
      (symbol "R_22R_0402_12_1_1"
        (pin passive line (at 0 0 0) (length 0.635)
          (name "~" (effects (font (size 1.27 1.27))))
          (number "1" (effects (font (size 1.27 1.27))))
        )
        (pin passive line (at 5.08 0 180) (length 0.635)
          (name "~" (effects (font (size 1.27 1.27))))
          (number "2" (effects (font (size 1.27 1.27))))
        )
      )
    )
	(symbol "data-center-rdimm-ddr4-tester:TP_1mm_SMD_10" (pin_numbers hide) (pin_names hide) (in_bom yes) (on_board yes)
      (property "Reference" "TP" (at 15.24 -5.08 0)
        (effects (font (size 1.27 1.27) (thickness 0.15)) (justify left bottom))
      )
      (property "Value" "TP_1mm_SMD_10" (at 15.24 -7.62 0)
        (effects (font (size 1.27 1.27) (thickness 0.15)) (justify left bottom) hide)
      )
      (property "Footprint" "data-center-rdimm-ddr4-tester-footprints:Testpoint_smd_1mm" (at 15.24 -10.16 0)
        (effects (font (size 1.27 1.27) (thickness 0.15)) (justify left bottom) hide)
      )
      (property "Datasheet" "" (at 15.24 -12.7 0)
        (effects (font (size 1.27 1.27) (thickness 0.15)) (justify left bottom) hide)
      )
      (property "MPN" "" (at 0 0 0)
        (effects (font (size 1.27 1.27)) hide)
      )
      (property "Manufacturer" "" (at 0 0 0)
        (effects (font (size 1.27 1.27)) hide)
      )
      (property "Author" "Antmicro" (at 15.24 -15.24 0)
        (effects (font (size 1.27 1.27) (thickness 0.15)) (justify left bottom) hide)
      )
      (property "License" "Apache-2.0" (at 15.24 -17.78 0)
        (effects (font (size 1.27 1.27) (thickness 0.15)) (justify left bottom) hide)
      )
      (property "ki_description" "Test Point 1mm" (at 0 0 0)
        (effects (font (size 1.27 1.27)) hide)
      )
      (symbol "TP_1mm_SMD_10_1_1"
        (circle (center 3.175 0) (radius 0.635)
          (stroke (width 0.254) (type default))
          (fill (type none))
        )
        (pin passive line (at 0 0 0) (length 2.54)
          (name "1" (effects (font (size 1.27 1.27))))
          (number "1" (effects (font (size 1.27 1.27))))
        )
      )
    )
	(symbol "data-center-rdimm-ddr4-tester:TP_1mm_SMD_11" (pin_numbers hide) (pin_names hide) (in_bom yes) (on_board yes)
      (property "Reference" "TP" (at 15.24 -5.08 0)
        (effects (font (size 1.27 1.27) (thickness 0.15)) (justify left bottom))
      )
      (property "Value" "TP_1mm_SMD_11" (at 15.24 -7.62 0)
        (effects (font (size 1.27 1.27) (thickness 0.15)) (justify left bottom) hide)
      )
      (property "Footprint" "data-center-rdimm-ddr4-tester-footprints:Testpoint_smd_1mm" (at 15.24 -10.16 0)
        (effects (font (size 1.27 1.27) (thickness 0.15)) (justify left bottom) hide)
      )
      (property "Datasheet" "" (at 15.24 -12.7 0)
        (effects (font (size 1.27 1.27) (thickness 0.15)) (justify left bottom) hide)
      )
      (property "MPN" "" (at 0 0 0)
        (effects (font (size 1.27 1.27)) hide)
      )
      (property "Manufacturer" "" (at 0 0 0)
        (effects (font (size 1.27 1.27)) hide)
      )
      (property "Author" "Antmicro" (at 15.24 -15.24 0)
        (effects (font (size 1.27 1.27) (thickness 0.15)) (justify left bottom) hide)
      )
      (property "License" "Apache-2.0" (at 15.24 -17.78 0)
        (effects (font (size 1.27 1.27) (thickness 0.15)) (justify left bottom) hide)
      )
      (property "ki_description" "Test Point 1mm" (at 0 0 0)
        (effects (font (size 1.27 1.27)) hide)
      )
      (symbol "TP_1mm_SMD_11_1_1"
        (circle (center 3.175 0) (radius 0.635)
          (stroke (width 0.254) (type default))
          (fill (type none))
        )
        (pin passive line (at 0 0 0) (length 2.54)
          (name "1" (effects (font (size 1.27 1.27))))
          (number "1" (effects (font (size 1.27 1.27))))
        )
      )
    )
	(symbol "data-center-rdimm-ddr4-tester:TP_1mm_SMD_12" (pin_numbers hide) (pin_names hide) (in_bom yes) (on_board yes)
      (property "Reference" "TP" (at 15.24 -5.08 0)
        (effects (font (size 1.27 1.27) (thickness 0.15)) (justify left bottom))
      )
      (property "Value" "TP_1mm_SMD_12" (at 15.24 -7.62 0)
        (effects (font (size 1.27 1.27) (thickness 0.15)) (justify left bottom) hide)
      )
      (property "Footprint" "data-center-rdimm-ddr4-tester-footprints:Testpoint_smd_1mm" (at 15.24 -10.16 0)
        (effects (font (size 1.27 1.27) (thickness 0.15)) (justify left bottom) hide)
      )
      (property "Datasheet" "" (at 15.24 -12.7 0)
        (effects (font (size 1.27 1.27) (thickness 0.15)) (justify left bottom) hide)
      )
      (property "MPN" "" (at 0 0 0)
        (effects (font (size 1.27 1.27)) hide)
      )
      (property "Manufacturer" "" (at 0 0 0)
        (effects (font (size 1.27 1.27)) hide)
      )
      (property "Author" "Antmicro" (at 15.24 -15.24 0)
        (effects (font (size 1.27 1.27) (thickness 0.15)) (justify left bottom) hide)
      )
      (property "License" "Apache-2.0" (at 15.24 -17.78 0)
        (effects (font (size 1.27 1.27) (thickness 0.15)) (justify left bottom) hide)
      )
      (property "ki_description" "Test Point 1mm" (at 0 0 0)
        (effects (font (size 1.27 1.27)) hide)
      )
      (symbol "TP_1mm_SMD_12_1_1"
        (circle (center 3.175 0) (radius 0.635)
          (stroke (width 0.254) (type default))
          (fill (type none))
        )
        (pin passive line (at 0 0 0) (length 2.54)
          (name "1" (effects (font (size 1.27 1.27))))
          (number "1" (effects (font (size 1.27 1.27))))
        )
      )
    )
	(symbol "data-center-rdimm-ddr4-tester:TP_1mm_SMD_13" (pin_numbers hide) (pin_names hide) (in_bom yes) (on_board yes)
      (property "Reference" "TP" (at 15.24 -5.08 0)
        (effects (font (size 1.27 1.27) (thickness 0.15)) (justify left bottom))
      )
      (property "Value" "TP_1mm_SMD_13" (at 15.24 -7.62 0)
        (effects (font (size 1.27 1.27) (thickness 0.15)) (justify left bottom) hide)
      )
      (property "Footprint" "data-center-rdimm-ddr4-tester-footprints:Testpoint_smd_1mm" (at 15.24 -10.16 0)
        (effects (font (size 1.27 1.27) (thickness 0.15)) (justify left bottom) hide)
      )
      (property "Datasheet" "" (at 15.24 -12.7 0)
        (effects (font (size 1.27 1.27) (thickness 0.15)) (justify left bottom) hide)
      )
      (property "MPN" "" (at 0 0 0)
        (effects (font (size 1.27 1.27)) hide)
      )
      (property "Manufacturer" "" (at 0 0 0)
        (effects (font (size 1.27 1.27)) hide)
      )
      (property "Author" "Antmicro" (at 15.24 -15.24 0)
        (effects (font (size 1.27 1.27) (thickness 0.15)) (justify left bottom) hide)
      )
      (property "License" "Apache-2.0" (at 15.24 -17.78 0)
        (effects (font (size 1.27 1.27) (thickness 0.15)) (justify left bottom) hide)
      )
      (property "ki_description" "Test Point 1mm" (at 0 0 0)
        (effects (font (size 1.27 1.27)) hide)
      )
      (symbol "TP_1mm_SMD_13_1_1"
        (circle (center 3.175 0) (radius 0.635)
          (stroke (width 0.254) (type default))
          (fill (type none))
        )
        (pin passive line (at 0 0 0) (length 2.54)
          (name "1" (effects (font (size 1.27 1.27))))
          (number "1" (effects (font (size 1.27 1.27))))
        )
      )
    )
	(symbol "data-center-rdimm-ddr4-tester:TP_1mm_SMD_14" (pin_numbers hide) (pin_names hide) (in_bom yes) (on_board yes)
      (property "Reference" "TP" (at 15.24 -5.08 0)
        (effects (font (size 1.27 1.27) (thickness 0.15)) (justify left bottom))
      )
      (property "Value" "TP_1mm_SMD_14" (at 15.24 -7.62 0)
        (effects (font (size 1.27 1.27) (thickness 0.15)) (justify left bottom) hide)
      )
      (property "Footprint" "data-center-rdimm-ddr4-tester-footprints:Testpoint_smd_1mm" (at 15.24 -10.16 0)
        (effects (font (size 1.27 1.27) (thickness 0.15)) (justify left bottom) hide)
      )
      (property "Datasheet" "" (at 15.24 -12.7 0)
        (effects (font (size 1.27 1.27) (thickness 0.15)) (justify left bottom) hide)
      )
      (property "MPN" "" (at 0 0 0)
        (effects (font (size 1.27 1.27)) hide)
      )
      (property "Manufacturer" "" (at 0 0 0)
        (effects (font (size 1.27 1.27)) hide)
      )
      (property "Author" "Antmicro" (at 15.24 -15.24 0)
        (effects (font (size 1.27 1.27) (thickness 0.15)) (justify left bottom) hide)
      )
      (property "License" "Apache-2.0" (at 15.24 -17.78 0)
        (effects (font (size 1.27 1.27) (thickness 0.15)) (justify left bottom) hide)
      )
      (property "ki_description" "Test Point 1mm" (at 0 0 0)
        (effects (font (size 1.27 1.27)) hide)
      )
      (symbol "TP_1mm_SMD_14_1_1"
        (circle (center 3.175 0) (radius 0.635)
          (stroke (width 0.254) (type default))
          (fill (type none))
        )
        (pin passive line (at 0 0 0) (length 2.54)
          (name "1" (effects (font (size 1.27 1.27))))
          (number "1" (effects (font (size 1.27 1.27))))
        )
      )
    )
	(symbol "data-center-rdimm-ddr4-tester:TestPoint_Probe_1206_RCW-0C" (pin_names hide) (in_bom yes) (on_board yes)
      (property "Reference" "TP" (at 17.78 -5.08 0)
        (effects (font (size 1.27 1.27) (thickness 0.15)) (justify left bottom))
      )
      (property "Value" "TestPoint_Probe_1206_RCW-0C" (at 17.78 -7.62 0)
        (effects (font (size 1.27 1.27) (thickness 0.15)) (justify left bottom))
      )
      (property "Footprint" "data-center-rdimm-ddr4-tester-footprints:PROBE_PAD_1206" (at 17.78 -10.16 0)
        (effects (font (size 1.27 1.27) (thickness 0.15)) (justify left bottom) hide)
      )
      (property "Datasheet" "https://www.te.com/commerce/DocumentDelivery/DDEController?Action=srchrtrv&DocNm=1773266&DocType=DS&DocLang=English" (at 17.78 -12.7 0)
        (effects (font (size 1.27 1.27) (thickness 0.15)) (justify left bottom) hide)
      )
      (property "MPN" "RCW-0C" (at 17.78 -15.24 0)
        (effects (font (size 1.27 1.27) (thickness 0.15)) (justify left bottom) hide)
      )
      (property "Manufacturer" "TE Connectivity" (at 17.78 -17.78 0)
        (effects (font (size 1.27 1.27) (thickness 0.15)) (justify left bottom) hide)
      )
      (property "Author" "Antmicro" (at 17.78 -20.32 0)
        (effects (font (size 1.27 1.27) (thickness 0.15)) (justify left bottom) hide)
      )
      (property "License" "Apache-2.0" (at 17.78 -22.86 0)
        (effects (font (size 1.27 1.27) (thickness 0.15)) (justify left bottom) hide)
      )
      (property "ki_description" "SMD Circuit Probe Pad 1206" (at 0 0 0)
        (effects (font (size 1.27 1.27)) hide)
      )
      (symbol "TestPoint_Probe_1206_RCW-0C_1_1"
        (circle (center 3.048 0) (radius 0.5588)
          (stroke (width 0.254) (type default))
          (fill (type none))
        )
        (pin passive line (at 0 0 0) (length 2.54)
          (name "1" (effects (font (size 1.27 1.27))))
          (number "1" (effects (font (size 1.27 1.27))))
        )
      )
    )
	(symbol "data-center-rdimm-ddr4-tester:USB-C_USB4105-GF-A" (in_bom yes) (on_board yes)
      (property "Reference" "J" (at 38.1 -2.54 0)
        (effects (font (size 1.27 1.27) (thickness 0.15)) (justify left bottom))
      )
      (property "Value" "USB-C_USB4105-GF-A" (at 38.1 -5.08 0)
        (effects (font (size 1.27 1.27) (thickness 0.15)) (justify left bottom))
      )
      (property "Footprint" "data-center-rdimm-ddr4-tester-footprints:USB-C_GCT_USB4105-GF-A" (at 38.1 -7.62 0)
        (effects (font (size 1.27 1.27) (thickness 0.15)) (justify left bottom) hide)
      )
      (property "Datasheet" "https://gct.co/files/drawings/usb4105.pdf" (at 38.1 -10.16 0)
        (effects (font (size 1.27 1.27) (thickness 0.15)) (justify left bottom) hide)
      )
      (property "Manufacturer" "GCT" (at 38.1 -12.7 0)
        (effects (font (size 1.27 1.27) (thickness 0.15)) (justify left bottom) hide)
      )
      (property "MPN" "USB4105-GF-A" (at 38.1 -15.24 0)
        (effects (font (size 1.27 1.27) (thickness 0.15)) (justify left bottom) hide)
      )
      (property "Author" "Antmicro" (at 38.1 -17.78 0)
        (effects (font (size 1.27 1.27) (thickness 0.15)) (justify left bottom) hide)
      )
      (property "License" "Apache-2.0" (at 38.1 -20.32 0)
        (effects (font (size 1.27 1.27) (thickness 0.15)) (justify left bottom) hide)
      )
      (symbol "USB-C_USB4105-GF-A_1_1"
        (polyline
          (pts
            (xy 11.43 -11.43)
            (xy 11.43 -19.05)
          )
          (stroke (width 0.254) (type default))
          (fill (type background))
        )
        (polyline
          (pts
            (xy 13.335 -4.699)
            (xy 13.335 -0.381)
          )
          (stroke (width 0.254) (type default))
          (fill (type background))
        )
        (polyline
          (pts
            (xy 15.24 -19.05)
            (xy 15.24 -11.43)
          )
          (stroke (width 0.254) (type default))
          (fill (type background))
        )
        (polyline
          (pts
            (xy 13.335 -3.937)
            (xy 14.224 -3.048)
            (xy 14.224 -2.413)
          )
          (stroke (width 0.254) (type default))
          (fill (type background))
        )
        (polyline
          (pts
            (xy 13.335 -3.556)
            (xy 12.446 -2.667)
            (xy 12.446 -2.032)
          )
          (stroke (width 0.254) (type default))
          (fill (type background))
        )
        (polyline
          (pts
            (xy 13.97 -0.381)
            (xy 13.335 0.762)
            (xy 12.7 -0.381)
            (xy 13.97 -0.381)
          )
          (stroke (width 0.254) (type default))
          (fill (type outline))
        )
        (rectangle (start 3.81 2.54) (end 17.145 -33.02)
          (stroke (width 0.254) (type default))
          (fill (type background))
        )
        (arc (start 11.43 -19.05) (mid 13.335 -20.9467) (end 15.24 -19.05)
          (stroke (width 0.254) (type default))
          (fill (type background))
        )
        (rectangle (start 12.065 -1.27) (end 12.827 -2.032)
          (stroke (width 0.254) (type default))
          (fill (type outline))
        )
        (arc (start 12.7 -19.05) (mid 13.335 -19.6823) (end 13.97 -19.05)
          (stroke (width 0.254) (type default))
          (fill (type outline))
        )
        (arc (start 12.7 -19.05) (mid 13.335 -19.6823) (end 13.97 -19.05)
          (stroke (width 0.254) (type default))
          (fill (type background))
        )
        (rectangle (start 12.7 -11.43) (end 13.97 -19.05)
          (stroke (width 0.254) (type default))
          (fill (type outline))
        )
        (circle (center 13.335 -4.826) (radius 0.5236)
          (stroke (width 0.254) (type default))
          (fill (type outline))
        )
        (arc (start 13.97 -11.43) (mid 13.335 -10.7977) (end 12.7 -11.43)
          (stroke (width 0.254) (type default))
          (fill (type outline))
        )
        (arc (start 13.97 -11.43) (mid 13.335 -10.7977) (end 12.7 -11.43)
          (stroke (width 0.254) (type default))
          (fill (type background))
        )
        (circle (center 14.224 -2.032) (radius 0.284)
          (stroke (width 0.254) (type default))
          (fill (type outline))
        )
        (arc (start 15.24 -11.43) (mid 13.335 -9.5333) (end 11.43 -11.43)
          (stroke (width 0.254) (type default))
          (fill (type background))
        )
        (pin passive line (at 0 -27.94 0) (length 3.81)
          (name "GND" (effects (font (size 1.27 1.27))))
          (number "A1" (effects (font (size 1.27 1.27))))
        )
        (pin passive line (at 0 -27.94 0) (length 3.81) hide
          (name "GND" (effects (font (size 1.27 1.27))))
          (number "A12" (effects (font (size 1.27 1.27))))
        )
        (pin passive line (at 0 0 0) (length 3.81)
          (name "VBUS" (effects (font (size 1.27 1.27))))
          (number "A4" (effects (font (size 1.27 1.27))))
        )
        (pin bidirectional line (at 0 -5.08 0) (length 3.81)
          (name "CC1" (effects (font (size 1.27 1.27))))
          (number "A5" (effects (font (size 1.27 1.27))))
        )
        (pin bidirectional line (at 0 -12.7 0) (length 3.81)
          (name "D+" (effects (font (size 1.27 1.27))))
          (number "A6" (effects (font (size 1.27 1.27))))
        )
        (pin bidirectional line (at 0 -15.24 0) (length 3.81)
          (name "D-" (effects (font (size 1.27 1.27))))
          (number "A7" (effects (font (size 1.27 1.27))))
        )
        (pin bidirectional line (at 0 -20.32 0) (length 3.81)
          (name "SBU1" (effects (font (size 1.27 1.27))))
          (number "A8" (effects (font (size 1.27 1.27))))
        )
        (pin passive line (at 0 0 0) (length 3.81) hide
          (name "VBUS" (effects (font (size 1.27 1.27))))
          (number "A9" (effects (font (size 1.27 1.27))))
        )
        (pin passive line (at 0 -27.94 0) (length 3.81) hide
          (name "GND" (effects (font (size 1.27 1.27))))
          (number "B1" (effects (font (size 1.27 1.27))))
        )
        (pin passive line (at 0 -27.94 0) (length 3.81) hide
          (name "GND" (effects (font (size 1.27 1.27))))
          (number "B12" (effects (font (size 1.27 1.27))))
        )
        (pin passive line (at 0 0 0) (length 3.81) hide
          (name "VBUS" (effects (font (size 1.27 1.27))))
          (number "B4" (effects (font (size 1.27 1.27))))
        )
        (pin bidirectional line (at 0 -7.62 0) (length 3.81)
          (name "CC2" (effects (font (size 1.27 1.27))))
          (number "B5" (effects (font (size 1.27 1.27))))
        )
        (pin passive line (at 0 -12.7 0) (length 3.81) hide
          (name "D+" (effects (font (size 1.27 1.27))))
          (number "B6" (effects (font (size 1.27 1.27))))
        )
        (pin passive line (at 0 -15.24 0) (length 3.81) hide
          (name "D-" (effects (font (size 1.27 1.27))))
          (number "B7" (effects (font (size 1.27 1.27))))
        )
        (pin bidirectional line (at 0 -22.86 0) (length 3.81)
          (name "SBU2" (effects (font (size 1.27 1.27))))
          (number "B8" (effects (font (size 1.27 1.27))))
        )
        (pin passive line (at 0 0 0) (length 3.81) hide
          (name "VBUS" (effects (font (size 1.27 1.27))))
          (number "B9" (effects (font (size 1.27 1.27))))
        )
        (pin passive line (at 0 -30.48 0) (length 3.81)
          (name "SHIELD" (effects (font (size 1.27 1.27))))
          (number "SH" (effects (font (size 1.27 1.27))))
        )
      )
    )
)
